G04 ================== begin FILE IDENTIFICATION RECORD ==================*
G04 Layout Name:  E:/<user>/9332_F0TG_MB_C/brd/0417/9332_F0TG_MB_C_V02_0417_0820.brd*
G04 Film Name:    pmt*
G04 File Format:  Gerber RS274X*
G04 File Origin:  Cadence Allegro 17.2-S081*
G04 Origin Date:  Wed Apr 19 14:49:58 2023*
G04 *
G04 Layer:  DRAWING FORMAT/TITLE_BLOCK_A*
G04 Layer:  VIA CLASS/PASTEMASK_TOP*
G04 Layer:  PACKAGE GEOMETRY/PASTEMASK_TOP*
G04 Layer:  DRAWING FORMAT/TITLE_BLOCK*
G04 Layer:  PIN/PASTEMASK_TOP*
G04 Layer:  MANUFACTURING/PHOTOPLOT_OUTLINE*
G04 Layer:  DRAWING FORMAT/TITLE_DATA_PMT*
G04 *
G04 Offset:    (0.00 0.00)*
G04 Mirror:    No*
G04 Mode:      Positive*
G04 Rotation:  0*
G04 FullContactRelief:  No*
G04 UndefLineWidth:     6.00*
G04 ================== end FILE IDENTIFICATION RECORD ====================*
%FSLAX25Y25*MOIN*%
%IR0*IPPOS*OFA0.00000B0.00000*MIA0B0*SFA1.00000B1.00000*%
%AMMACRO234*
4,1,28,.00748,.00051,
.00984,.00051,
.00985,.00602,
.009788,.006695,
.009614,.00735,
.009329,.007964,
.008942,.00852,
.008464,.009,
.00791,.00939,
.007296,.009677,
.006642,.009854,
.005967,.009915,
.00592,.00991,
-.0059,.00993,
-.006576,.009875,
-.007232,.009708,
-.00785,.009429,
-.008409,.009047,
-.008894,.008574,
-.009289,.008024,
-.009583,.007413,
-.009767,.006761,
-.009834,.006087,
-.00983,.00604,
-.00984,.00053,
-.00748,.00053,
-.00749,-.0099,
.00747,-.00992,
.00748,.00051,
0.0*
%
%ADD234MACRO234*%
%AMMACRO229*
4,1,32,-.01575,.06201,
-.01575,.0502,
.00197,.0502,
.00197,.04035,
-.01575,.04035,
-.01575,.03248,
.00197,.03248,
.00197,.02461,
-.01575,.02461,
-.01575,.01673,
.00197,.01673,
.00197,.00886,
-.01575,.00886,
-.01575,.00098,
.00197,.00098,
.00197,-.00689,
-.01575,-.00689,
-.01575,-.01476,
.00197,-.01476,
.00197,-.02264,
-.01575,-.02264,
-.01575,-.03051,
.00197,-.03051,
.00197,-.03839,
-.01575,-.03839,
-.01575,-.04626,
.00197,-.04626,
.00197,-.05413,
-.01575,-.05413,
-.01575,-.06201,
.01575,-.06201,
.01575,.06201,
-.01575,.06201,
0.0*
%
%ADD229MACRO229*%
%AMMACRO168*
4,1,28,-.00051,.00748,
-.00051,.00984,
-.00602,.00985,
-.006695,.009788,
-.00735,.009614,
-.007964,.009329,
-.00852,.008942,
-.009,.008464,
-.00939,.00791,
-.009677,.007296,
-.009854,.006642,
-.009915,.005967,
-.00991,.00592,
-.00993,-.0059,
-.009875,-.006576,
-.009708,-.007232,
-.009429,-.00785,
-.009047,-.008409,
-.008574,-.008894,
-.008024,-.009289,
-.007413,-.009583,
-.006761,-.009767,
-.006087,-.009834,
-.00604,-.00983,
-.00053,-.00984,
-.00053,-.00748,
.0099,-.00749,
.00992,.00747,
-.00051,.00748,
0.0*
%
%ADD168MACRO168*%
%AMMACRO129*
4,1,28,.00051,-.00748,
.00051,-.00984,
.00602,-.00985,
.006695,-.009788,
.00735,-.009614,
.007964,-.009329,
.00852,-.008942,
.009,-.008464,
.00939,-.00791,
.009677,-.007296,
.009854,-.006642,
.009915,-.005967,
.00991,-.00592,
.00993,.0059,
.009875,.006576,
.009708,.007232,
.009429,.00785,
.009047,.008409,
.008574,.008894,
.008024,.009289,
.007413,.009583,
.006761,.009767,
.006087,.009834,
.00604,.00983,
.00053,.00984,
.00053,.00748,
-.0099,.00749,
-.00992,-.00747,
.00051,-.00748,
0.0*
%
%ADD129MACRO129*%
%AMMACRO122*
4,1,5,.00591,-.01772,
.00591,.01772,
0.0,.01772,
-.00591,.01181,
-.00591,-.01772,
.00591,-.01772,
0.0*
%
%ADD122MACRO122*%
%AMMACRO251*
4,1,5,-.01772,-.00591,
.01772,-.00591,
.01772,0.0,
.01181,.00591,
-.01772,.00591,
-.01772,-.00591,
0.0*
%
%ADD251MACRO251*%
%AMMACRO287*
4,1,8,.02953,.06299,
-.02953,.06299,
-.02953,-.06299,
.02953,-.06299,
.02953,-.01968,
-.01771,-.01968,
-.01771,.01968,
.02953,.01968,
.02953,.06299,
0.0*
%
%ADD287MACRO287*%
%AMMACRO38*
4,1,8,.06299,-.02953,
.06299,.02953,
-.06299,.02953,
-.06299,-.02953,
-.01968,-.02953,
-.01968,.01771,
.01968,.01771,
.01968,-.02953,
.06299,-.02953,
0.0*
%
%ADD38MACRO38*%
%ADD222R,.231X.035*%
%AMMACRO120*
21,1,.016,.0041,0.0,0.0,60.*%
%ADD120MACRO120*%
%ADD45R,.17X.024*%
%AMMACRO233*
4,1,28,.00748,-.00052,
.00984,-.00052,
.00983,-.00603,
.009775,-.006705,
.0096,-.007359,
.009313,-.007973,
.008925,-.008528,
.008446,-.009007,
.007891,-.009395,
.007277,-.009682,
.006622,-.009857,
.005948,-.009916,
.0059,-.00992,
-.00592,-.0099,
-.006595,-.009852,
-.007251,-.009684,
-.007868,-.009404,
-.008427,-.009021,
-.008911,-.008546,
-.009305,-.007996,
-.009598,-.007384,
-.00978,-.006732,
-.009845,-.006058,
-.00985,-.00601,
-.00984,-.0005,
-.00748,-.0005,
-.00747,.00993,
.00749,.00991,
.00748,-.00052,
0.0*
%
%ADD233MACRO233*%
%ADD206R,.11X.049*%
%AMMACRO167*
4,1,28,.00052,.00748,
.00052,.00984,
.00603,.00983,
.006705,.009775,
.007359,.0096,
.007973,.009313,
.008528,.008925,
.009007,.008446,
.009395,.007891,
.009682,.007277,
.009857,.006622,
.009916,.005948,
.00992,.0059,
.0099,-.00592,
.009852,-.006595,
.009684,-.007251,
.009404,-.007868,
.009021,-.008427,
.008546,-.008911,
.007996,-.009305,
.007384,-.009598,
.006732,-.00978,
.006058,-.009845,
.00601,-.00985,
.0005,-.00984,
.0005,-.00748,
-.00993,-.00747,
-.00991,.00749,
.00052,.00748,
0.0*
%
%ADD167MACRO167*%
%AMMACRO128*
4,1,28,-.00052,-.00748,
-.00052,-.00984,
-.00603,-.00983,
-.006705,-.009775,
-.007359,-.0096,
-.007973,-.009313,
-.008528,-.008925,
-.009007,-.008446,
-.009395,-.007891,
-.009682,-.007277,
-.009857,-.006622,
-.009916,-.005948,
-.00992,-.0059,
-.0099,.00592,
-.009852,.006595,
-.009684,.007251,
-.009404,.007868,
-.009021,.008427,
-.008546,.008911,
-.007996,.009305,
-.007384,.009598,
-.006732,.00978,
-.006058,.009845,
-.00601,.00985,
-.0005,.00984,
-.0005,.00748,
.00993,.00747,
.00991,-.00749,
-.00052,-.00748,
0.0*
%
%ADD128MACRO128*%
%ADD107R,.103X.065*%
%ADD277R,.065X.103*%
%ADD186R,.04X.007*%
%ADD165R,.031X.007*%
%AMMACRO200*
21,1,.016,.0041,0.0,0.0,45.*%
%ADD200MACRO200*%
%ADD187R,.007X.031*%
%ADD185R,.007X.04*%
%ADD166R,.032X.007*%
%ADD101C,.012*%
%ADD69R,.0041X.016*%
%ADD10C,.03*%
%ADD255R,.13X.095*%
%ADD247O,.137X.064*%
%ADD188R,.032X.008*%
%ADD123R,.007X.032*%
%ADD111R,.095X.111*%
%ADD65R,.016X.0041*%
%ADD39R,.024X.007*%
%ADD182R,.052X.007*%
%ADD164R,.008X.032*%
%ADD53R,.007X.024*%
%ADD216R,.015X.009*%
%ADD183R,.007X.052*%
%ADD141C,.06*%
%ADD104C,.015*%
%ADD93R,.115X.085*%
%ADD71R,.026X.007*%
%ADD52R,.119X.063*%
%ADD49R,.024X.009*%
%ADD241R,.138X.063*%
%ADD214R,.009X.015*%
%ADD207C,.016*%
%AMMACRO89*
4,1,21,-.0035,-.0085,
-.0035,.012,
.0035,.012,
.0035,-.0085,
.003447,-.009108,
.003289,-.009697,
.003031,-.01025,
.002681,-.01075,
.00225,-.011181,
.00175,-.011531,
.001197,-.011789,
.000608,-.011947,
0.0,-.012,
-.000608,-.011947,
-.001197,-.011789,
-.00175,-.011531,
-.00225,-.011181,
-.002681,-.01075,
-.003031,-.01025,
-.003289,-.009697,
-.003447,-.009108,
-.0035,-.0085,
0.0*
%
%ADD89MACRO89*%
%AMMACRO85*
4,1,21,.0085,-.0035,
-.012,-.0035,
-.012,.0035,
.0085,.0035,
.009108,.003447,
.009697,.003289,
.01025,.003031,
.01075,.002681,
.011181,.00225,
.011531,.00175,
.011789,.001197,
.011947,.000608,
.012,0.0,
.011947,-.000608,
.011789,-.001197,
.011531,-.00175,
.011181,-.00225,
.01075,-.002681,
.01025,-.003031,
.009697,-.003289,
.009108,-.003447,
.0085,-.0035,
0.0*
%
%ADD85MACRO85*%
%ADD70R,.007X.026*%
%ADD58C,.061*%
%ADD50R,.009X.024*%
%ADD27R,.063X.119*%
%ADD263R,.028X.007*%
%ADD99R,.063X.138*%
%ADD84R,.048X.126*%
%ADD59O,.137X.068*%
%ADD262R,.007X.028*%
%ADD228R,.13X.0848*%
%ADD40C,.064*%
%ADD180R,.0848X.13*%
%ADD68R,.178X.054*%
%ADD271C,.048*%
%ADD221R,.032X.032*%
%ADD190C,.066*%
%ADD12C,.039*%
%AMMACRO288*
4,1,30,-.08089,.09065,
-.08227,.09203,
-.10433,.09203,
-.10433,.08022,
-.08309,.08022,
-.08171,.07884,
-.02464,.07884,
-.02464,-.02608,
-.06988,-.02609,
-.06988,-.09203,
.06988,-.09203,
.06988,-.01427,
.04035,-.01427,
.04035,.02116,
.10433,.02117,
.10433,.03298,
.09055,.03298,
.09055,.04085,
.10433,.04084,
.10433,.05261,
.09055,.05266,
.09055,.06053,
.10433,.06054,
.10433,.07237,
.09055,.07237,
.09055,.08022,
.10433,.08022,
.10433,.09203,
.08227,.09203,
.08089,.09065,
-.08089,.09065,
0.0*
%
%ADD288MACRO288*%
%ADD140R,.06X.06*%
%ADD264R,.158X.077*%
%ADD64R,.061X.061*%
%ADD44R,.166X.079*%
%ADD67R,.178X.095*%
%ADD267R,.064X.064*%
%AMMACRO245*
21,1,.016,.0041,0.0,0.0,33.917*%
%ADD245MACRO245*%
%ADD132C,.01772*%
%ADD272R,.048X.048*%
%ADD198R,.066X.066*%
%ADD63R,.067X.067*%
%AMMACRO14*
4,1,28,-.00748,-.00052,
-.00984,-.00052,
-.00984,-.00603,
-.009782,-.006705,
-.009607,-.007359,
-.009321,-.007974,
-.008933,-.008529,
-.008455,-.009009,
-.0079,-.009398,
-.007286,-.009685,
-.006632,-.009861,
-.005957,-.00992,
-.00591,-.00992,
.00591,-.00992,
.006585,-.009869,
.007242,-.009701,
.007859,-.009421,
.008418,-.009039,
.008903,-.008565,
.009297,-.008015,
.009591,-.007404,
.009773,-.006751,
.00984,-.006077,
.00984,-.00603,
.00984,-.00052,
.00748,-.00052,
.00748,.00991,
-.00748,.00991,
-.00748,-.00052,
0.0*
%
%ADD14MACRO14*%
%AMMACRO178*
4,1,5,.01378,.00098,
.01378,-.00492,
-.01378,-.00492,
-.01378,.00492,
.00984,.00492,
.01378,.00098,
0.0*
%
%ADD178MACRO178*%
%AMMACRO176*
4,1,5,.00098,-.01378,
-.00492,-.01378,
-.00492,.01378,
.00492,.01378,
.00492,-.00984,
.00098,-.01378,
0.0*
%
%ADD176MACRO176*%
%AMMACRO119*
4,1,5,.00492,.01673,
-.00492,.01673,
-.00492,-.01673,
.00098,-.01673,
.00492,-.0128,
.00492,.01673,
0.0*
%
%ADD119MACRO119*%
%AMMACRO24*
4,1,28,-.00052,.00748,
-.00052,.00984,
-.00603,.00984,
-.006705,.009782,
-.007359,.009607,
-.007974,.009321,
-.008529,.008933,
-.009009,.008455,
-.009398,.0079,
-.009685,.007286,
-.009861,.006632,
-.00992,.005957,
-.00992,.00591,
-.00992,-.00591,
-.009869,-.006585,
-.009701,-.007242,
-.009421,-.007859,
-.009039,-.008418,
-.008565,-.008903,
-.008015,-.009297,
-.007404,-.009591,
-.006751,-.009773,
-.006077,-.00984,
-.00603,-.00984,
-.00052,-.00984,
-.00052,-.00748,
.00991,-.00748,
.00991,.00748,
-.00052,.00748,
0.0*
%
%ADD24MACRO24*%
%AMMACRO33*
4,1,5,-.04823,.03445,
-.04823,-.04823,
.04823,-.04823,
.04823,.04823,
-.03445,.04823,
-.04823,.03445,
0.0*
%
%ADD33MACRO33*%
%AMMACRO13*
4,1,28,-.00748,.00051,
-.00984,.00051,
-.00984,.00602,
-.009782,.006695,
-.009607,.007349,
-.009321,.007964,
-.008933,.008519,
-.008455,.008998,
-.0079,.009388,
-.007287,.009675,
-.006632,.009851,
-.005958,.00991,
-.00591,.00991,
.00591,.00991,
.006585,.009859,
.007242,.009691,
.007859,.009411,
.008418,.009029,
.008903,.008555,
.009297,.008005,
.00959,.007394,
.009773,.006742,
.00984,.006068,
.00984,.00602,
.00984,.00051,
.00748,.00051,
.00748,-.00992,
-.00748,-.00992,
-.00748,.00051,
0.0*
%
%ADD13MACRO13*%
%AMMACRO175*
4,1,5,-.00098,-.01378,
.00492,-.01378,
.00492,.01378,
-.00492,.01378,
-.00492,-.00984,
-.00098,-.01378,
0.0*
%
%ADD175MACRO175*%
%AMMACRO173*
4,1,5,.01378,-.00098,
.01378,.00492,
-.01378,.00492,
-.01378,-.00492,
.00984,-.00492,
.01378,-.00098,
0.0*
%
%ADD173MACRO173*%
%AMMACRO26*
4,1,28,.00051,.00748,
.00051,.00984,
.00602,.00984,
.006695,.009782,
.007349,.009607,
.007964,.009321,
.008519,.008933,
.008998,.008455,
.009388,.0079,
.009675,.007287,
.009851,.006632,
.00991,.005958,
.00991,.00591,
.00991,-.00591,
.009859,-.006585,
.009691,-.007242,
.009411,-.007859,
.009029,-.008418,
.008555,-.008903,
.008005,-.009297,
.007394,-.00959,
.006742,-.009773,
.006068,-.00984,
.00602,-.00984,
.00051,-.00984,
.00051,-.00748,
-.00992,-.00748,
-.00992,.00748,
.00051,.00748,
0.0*
%
%ADD26MACRO26*%
%AMMACRO118*
4,1,8,-.01821,.0246,
.01821,.0246,
.01821,.01476,
-.00837,.01476,
-.00837,-.01477,
.01821,-.01477,
.01821,-.02461,
-.01821,-.02461,
-.01821,.0246,
0.0*
%
%ADD118MACRO118*%
%AMMACRO80*
4,1,13,-.012,.00002,
-.011943,.000627,
-.011782,.001216,
-.011521,.001767,
-.011168,.002265,
-.010734,.002694,
-.010233,.003041,
-.009678,.003296,
-.009088,.00345,
-.0085,.0035,
.012,.0035,
.012,-.0035,
-.00848,-.0035,
-.012,.00002,
0.0*
%
%ADD80MACRO80*%
%AMMACRO86*
4,1,13,.00002,.012,
.000627,.011943,
.001216,.011782,
.001767,.011521,
.002265,.011168,
.002694,.010734,
.003041,.010233,
.003296,.009678,
.00345,.009088,
.0035,.0085,
.0035,-.012,
-.0035,-.012,
-.0035,.00848,
.00002,.012,
0.0*
%
%ADD86MACRO86*%
%AMMACRO48*
4,1,6,-.1063,-.04134,
-.1063,.01378,
-.03543,.01378,
-.03543,.04134,
.1063,.04134,
.1063,-.04134,
-.1063,-.04134,
0.0*
%
%ADD48MACRO48*%
%AMMACRO88*
4,1,13,-.00849,.0035,
.012,.0035,
.012,-.0035,
-.0085,-.0035,
-.009108,-.003447,
-.009697,-.003289,
-.01025,-.003031,
-.01075,-.002681,
-.011181,-.00225,
-.011531,-.00175,
-.011789,-.001197,
-.011947,-.000608,
-.012,-.00001,
-.00849,.0035,
0.0*
%
%ADD88MACRO88*%
%AMMACRO83*
4,1,13,.0035,.00849,
.0035,-.012,
-.0035,-.012,
-.0035,.0085,
-.003447,.009108,
-.003289,.009697,
-.003031,.01025,
-.002681,.01075,
-.00225,.011181,
-.00175,.011531,
-.001197,.011789,
-.000608,.011947,
-.00001,.012,
.0035,.00849,
0.0*
%
%ADD83MACRO83*%
%ADD103O,.013X.01*%
%ADD280R,.13X.13*%
%ADD254R,.02X.01*%
%ADD102O,.01X.013*%
%AMMACRO232*
4,1,5,.01772,.00591,
-.01772,.00591,
-.01772,0.0,
-.01181,-.00591,
.01772,-.00591,
.01772,.00591,
0.0*
%
%ADD232MACRO232*%
%AMMACRO157*
4,1,40,-.00984,-.00472,
.00984,-.00472,
.010182,-.004691,
.010513,-.004603,
.010824,-.004458,
.011105,-.004262,
.011348,-.00402,
.011545,-.00374,
.01169,-.003429,
.01178,-.003098,
.01181,-.00276,
.01181,.00276,
.011779,.003101,
.011689,.003432,
.011543,.003742,
.011346,.004023,
.011102,.004264,
.010821,.00446,
.01051,.004604,
.010178,.004691,
.00984,.00472,
-.00984,.00472,
-.010182,.004691,
-.010513,.004603,
-.010824,.004458,
-.011105,.004262,
-.011348,.00402,
-.011545,.00374,
-.01169,.003429,
-.01178,.003098,
-.01181,.00276,
-.01181,-.00276,
-.011779,-.003101,
-.011689,-.003432,
-.011543,-.003742,
-.011346,-.004023,
-.011102,-.004264,
-.010821,-.00446,
-.01051,-.004604,
-.010178,-.004691,
-.00984,-.00472,
0.0*
%
%ADD157MACRO157*%
%ADD96R,.021X.01*%
%ADD297R,.02X.012*%
%ADD212R,.01X.021*%
%AMMACRO155*
4,1,40,-.00472,.00984,
-.00472,-.00984,
-.004691,-.010182,
-.004603,-.010513,
-.004458,-.010824,
-.004262,-.011105,
-.00402,-.011348,
-.00374,-.011545,
-.003429,-.01169,
-.003098,-.01178,
-.00276,-.01181,
.00276,-.01181,
.003101,-.011779,
.003432,-.011689,
.003742,-.011543,
.004023,-.011346,
.004264,-.011102,
.00446,-.010821,
.004604,-.01051,
.004691,-.010178,
.00472,-.00984,
.00472,.00984,
.004691,.010182,
.004603,.010513,
.004458,.010824,
.004262,.011105,
.00402,.011348,
.00374,.011545,
.003429,.01169,
.003098,.01178,
.00276,.01181,
-.00276,.01181,
-.003101,.011779,
-.003432,.011689,
-.003742,.011543,
-.004023,.011346,
-.004264,.011102,
-.00446,.010821,
-.004604,.01051,
-.004691,.010178,
-.00472,.00984,
0.0*
%
%ADD155MACRO155*%
%AMMACRO121*
21,1,.016,.0041,0.0,0.0,110.*%
%ADD121MACRO121*%
%ADD35R,.022X.01*%
%ADD259R,.05X.01*%
%ADD227R,.014X.01*%
%ADD115R,.032X.01*%
%ADD95R,.021X.012*%
%ADD34R,.01X.022*%
%ADD289R,.023X.011*%
%ADD226R,.015X.01*%
%ADD225R,.01X.014*%
%ADD211R,.012X.021*%
%AMMACRO197*
21,1,.016,.0041,0.0,0.0,112.*%
%ADD197MACRO197*%
%ADD159R,.05X.02*%
%ADD114R,.01X.05*%
%ADD113R,.01X.032*%
%ADD292R,.011X.023*%
%ADD290R,.024X.011*%
%ADD284R,.05X.03*%
%ADD261R,.061X.01*%
%ADD230R,.032X.012*%
%ADD224R,.01X.015*%
%ADD223R,.06X.02*%
%ADD174R,.052X.01*%
%ADD158R,.05X.012*%
%ADD291R,.011X.024*%
%AMMACRO244*
4,1,28,-.00748,-.00051,
-.00984,-.00051,
-.00985,-.00602,
-.009788,-.006695,
-.009614,-.00735,
-.009329,-.007964,
-.008942,-.00852,
-.008464,-.009,
-.00791,-.00939,
-.007296,-.009677,
-.006642,-.009854,
-.005967,-.009915,
-.00592,-.00991,
.0059,-.00993,
.006576,-.009875,
.007232,-.009708,
.00785,-.009429,
.008409,-.009047,
.008894,-.008574,
.009289,-.008024,
.009583,-.007413,
.009767,-.006761,
.009834,-.006087,
.00983,-.00604,
.00984,-.00053,
.00748,-.00053,
.00749,.0099,
-.00747,.00992,
-.00748,-.00051,
0.0*
%
%ADD244MACRO244*%
%ADD204R,.04X.032*%
%ADD181R,.022X.04*%
%ADD125R,.012X.032*%
%AMMACRO124*
4,1,32,.06201,.01575,
.0502,.01575,
.0502,-.00197,
.04035,-.00197,
.04035,.01575,
.03248,.01575,
.03248,-.00197,
.02461,-.00197,
.02461,.01575,
.01673,.01575,
.01673,-.00197,
.00886,-.00197,
.00886,.01575,
.00098,.01575,
.00098,-.00197,
-.00689,-.00197,
-.00689,.01575,
-.01476,.01575,
-.01476,-.00197,
-.02264,-.00197,
-.02264,.01575,
-.03051,.01575,
-.03051,-.00197,
-.03839,-.00197,
-.03839,.01575,
-.04626,.01575,
-.04626,-.00197,
-.05413,-.00197,
-.05413,.01575,
-.06201,.01575,
-.06201,-.01575,
.06201,-.01575,
.06201,.01575,
0.0*
%
%ADD124MACRO124*%
%ADD109R,.032X.022*%
%ADD108R,.05X.04*%
%ADD97R,.02X.016*%
%ADD42R,.015X.012*%
%ADD18R,.034X.02*%
%ADD260R,.061X.012*%
%AMMACRO250*
4,1,32,.01575,-.06201,
.01575,-.0502,
-.00197,-.0502,
-.00197,-.04035,
.01575,-.04035,
.01575,-.03248,
-.00197,-.03248,
-.00197,-.02461,
.01575,-.02461,
.01575,-.01673,
-.00197,-.01673,
-.00197,-.00886,
.01575,-.00886,
.01575,-.00098,
-.00197,-.00098,
-.00197,.00689,
.01575,.00689,
.01575,.01476,
-.00197,.01476,
-.00197,.02264,
.01575,.02264,
.01575,.03051,
-.00197,.03051,
-.00197,.03839,
.01575,.03839,
.01575,.04626,
-.00197,.04626,
-.00197,.05413,
.01575,.05413,
.01575,.06201,
-.01575,.06201,
-.01575,-.06201,
.01575,-.06201,
0.0*
%
%ADD250MACRO250*%
%ADD169R,.036X.01*%
%ADD163R,.016X.02*%
%ADD127R,.022X.032*%
%ADD112R,.02X.017*%
%ADD74R,.012X.015*%
%AMMACRO57*
4,1,44,-.01181,.00295,
-.01181,-.00295,
-.01178,-.003292,
-.011692,-.003623,
-.011548,-.003934,
-.011351,-.004215,
-.011109,-.004458,
-.010828,-.004655,
-.010517,-.004801,
-.010186,-.00489,
-.009845,-.00492,
-.00984,-.00492,
.00984,-.00492,
.010182,-.00489,
.010513,-.004802,
.010824,-.004658,
.011105,-.004461,
.011348,-.004219,
.011545,-.003938,
.011691,-.003627,
.01178,-.003296,
.01181,-.002955,
.01181,-.00295,
.01181,.00295,
.01178,.003292,
.011692,.003623,
.011548,.003934,
.011351,.004215,
.011109,.004458,
.010828,.004655,
.010517,.004801,
.010186,.00489,
.009845,.00492,
.00984,.00492,
-.00984,.00492,
-.010182,.00489,
-.010513,.004802,
-.010824,.004658,
-.011105,.004461,
-.011348,.004219,
-.011545,.003938,
-.011691,.003627,
-.01178,.003296,
-.01181,.002955,
-.01181,.00295,
0.0*
%
%ADD57MACRO57*%
%AMMACRO55*
4,1,44,.00295,.01181,
-.00295,.01181,
-.003292,.01178,
-.003623,.011692,
-.003934,.011548,
-.004215,.011351,
-.004458,.011109,
-.004655,.010828,
-.004801,.010517,
-.00489,.010186,
-.00492,.009845,
-.00492,.00984,
-.00492,-.00984,
-.00489,-.010182,
-.004802,-.010513,
-.004658,-.010824,
-.004461,-.011105,
-.004219,-.011348,
-.003938,-.011545,
-.003627,-.011691,
-.003296,-.01178,
-.002955,-.01181,
-.00295,-.01181,
.00295,-.01181,
.003292,-.01178,
.003623,-.011692,
.003934,-.011548,
.004215,-.011351,
.004458,-.011109,
.004655,-.010828,
.004801,-.010517,
.00489,-.010186,
.00492,-.009845,
.00492,-.00984,
.00492,.00984,
.00489,.010182,
.004802,.010513,
.004658,.010824,
.004461,.011105,
.004219,.011348,
.003938,.011545,
.003627,.011691,
.003296,.01178,
.002955,.01181,
.00295,.01181,
0.0*
%
%ADD55MACRO55*%
%ADD51R,.04X.05*%
%AMMACRO296*
4,1,8,-.02953,-.06299,
.02953,-.06299,
.02953,.06299,
-.02953,.06299,
-.02953,.01968,
.01771,.01968,
.01771,-.01968,
-.02953,-.01968,
-.02953,-.06299,
0.0*
%
%ADD296MACRO296*%
%ADD270R,.032X.024*%
%ADD256R,.012X.061*%
%ADD248R,.05X.015*%
%ADD210R,.025X.013*%
%ADD205R,.063X.011*%
%ADD179R,.017X.02*%
%ADD143R,.028X.01*%
%ADD76R,.04X.015*%
%ADD32R,.02X.018*%
%ADD283R,.01X.028*%
%ADD269R,.034X.014*%
%ADD249R,.052X.014*%
%ADD213R,.166X.13*%
%AMMACRO196*
21,1,.016,.0041,0.0,0.0,135.*%
%ADD196MACRO196*%
%ADD189R,.042X.024*%
%ADD138R,.053X.022*%
%ADD98R,.024X.032*%
%ADD94R,.013X.025*%
%ADD73R,.018X.02*%
%ADD46R,.018X.012*%
%AMMACRO37*
4,1,8,-.06299,.02953,
-.06299,-.02953,
.06299,-.02953,
.06299,.02953,
.01968,.02953,
.01968,-.01771,
-.01968,-.01771,
-.01968,.02953,
-.06299,.02953,
0.0*
%
%ADD37MACRO37*%
%ADD31R,.029X.01*%
%ADD253R,.27X.126*%
%ADD203R,.022X.053*%
%ADD193R,.044X.014*%
%ADD160R,.05X.035*%
%ADD154R,.052X.024*%
%ADD148R,.014X.034*%
%ADD77R,.024X.042*%
%ADD30R,.01X.029*%
%ADD236R,.036X.032*%
%ADD152R,.035X.05*%
%ADD150R,.024X.052*%
%ADD139R,.014X.044*%
%ADD137R,.138X.115*%
%ADD28R,.024X.017*%
%ADD25R,.036X.04*%
%ADD19R,.034X.016*%
%AMMACRO294*
4,1,32,.05512,.01181,
.04331,.01181,
.04331,-.00098,
.03543,-.00098,
.03543,.01181,
.02362,.01181,
.02362,-.00098,
.01575,-.00098,
.01575,.01181,
.00394,.01181,
.00394,-.00098,
-.00394,-.00098,
-.00394,.01181,
-.01575,.01181,
-.01575,-.00098,
-.02362,-.00098,
-.02362,.01181,
-.03543,.01181,
-.03543,-.00098,
-.04331,-.00098,
-.04331,.01181,
-.05512,.01181,
-.05512,-.00098,
-.06299,-.00098,
-.06299,.01181,
-.0748,.01181,
-.0748,-.01181,
.0748,-.01181,
.0748,.01181,
.06299,.01181,
.06299,-.00098,
.05512,-.00098,
.05512,.01181,
0.0*
%
%ADD294MACRO294*%
%ADD286R,.044X.016*%
%AMMACRO281*
4,1,8,.01771,.01476,
-.01772,.01476,
-.01772,-.01476,
.01771,-.01476,
.01771,-.00492,
-.00394,-.00492,
-.00394,.00492,
.01771,.00492,
.01771,.01476,
0.0*
%
%ADD281MACRO281*%
%ADD273R,.063X.015*%
%AMMACRO243*
4,1,28,-.00748,.00052,
-.00984,.00052,
-.00983,.00603,
-.009775,.006705,
-.0096,.007359,
-.009313,.007973,
-.008925,.008528,
-.008446,.009007,
-.007891,.009395,
-.007277,.009682,
-.006622,.009857,
-.005948,.009916,
-.0059,.00992,
.00592,.0099,
.006595,.009852,
.007251,.009684,
.007868,.009404,
.008427,.009021,
.008911,.008546,
.009305,.007996,
.009598,.007384,
.00978,.006732,
.009845,.006058,
.00985,.00601,
.00984,.0005,
.00748,.0005,
.00747,-.00993,
-.00749,-.00991,
-.00748,.00052,
0.0*
%
%ADD243MACRO243*%
%AMMACRO145*
4,1,8,.01476,-.01771,
.01476,.01772,
-.01476,.01772,
-.01476,-.01771,
-.00492,-.01771,
-.00492,.00394,
.00492,.00394,
.00492,-.01771,
.01476,-.01771,
0.0*
%
%ADD145MACRO145*%
%ADD117R,.115X.138*%
%ADD106R,.017X.024*%
%ADD105R,.032X.028*%
%ADD100R,.056X.04*%
%ADD61R,.032X.036*%
%ADD275R,.048X.04*%
%ADD252R,.128X.135*%
%ADD240R,.056X.05*%
%ADD218R,.024X.054*%
%ADD191R,.046X.024*%
%ADD162R,.028X.032*%
%ADD142R,.052X.018*%
%ADD92R,.028X.024*%
%ADD75R,.056X.014*%
%ADD60R,.04X.056*%
%ADD36R,.016X.044*%
%ADD276R,.024X.028*%
%ADD274R,.04X.048*%
%ADD265R,.054X.044*%
%ADD246R,.1692X.13*%
%ADD217R,.016X.054*%
%ADD208R,.024X.046*%
%ADD202R,.014X.056*%
%ADD194R,.054X.026*%
%ADD151R,.012X.049*%
%ADD15R,.095X.03*%
%ADD242C,.315*%
%ADD235R,.049X.014*%
%ADD192R,.046X.017*%
%ADD149R,.044X.054*%
%ADD131R,.056X.052*%
%ADD220R,.052X.056*%
%ADD215R,.063X.046*%
%ADD209R,.017X.046*%
%ADD199R,.048X.025*%
%ADD195R,.059X.014*%
%ADD161R,.038X.026*%
%ADD144R,.028X.018*%
%ADD136R,.014X.049*%
%ADD126R,.079X.012*%
%ADD62R,.091X.081*%
%ADD41R,.015X.057*%
%ADD23C,.244*%
%ADD268R,.028X.036*%
%ADD237R,.014X.059*%
%ADD231R,.012X.079*%
%ADD201R,.018X.028*%
%ADD135R,.026X.038*%
%AMMACRO81*
4,1,21,-.0085,.0035,
.012,.0035,
.012,-.0035,
-.0085,-.0035,
-.009108,-.003447,
-.009697,-.003289,
-.01025,-.003031,
-.01075,-.002681,
-.011181,-.00225,
-.011531,-.00175,
-.011789,-.001197,
-.011947,-.000608,
-.012,0.0,
-.011947,.000608,
-.011789,.001197,
-.011531,.00175,
-.011181,.00225,
-.01075,.002681,
-.01025,.003031,
-.009697,.003289,
-.009108,.003447,
-.0085,.0035,
0.0*
%
%ADD81MACRO81*%
%ADD29R,.14X.14*%
%ADD278R,.096X.034*%
%AMMACRO82*
4,1,21,.0035,.0085,
.0035,-.012,
-.0035,-.012,
-.0035,.0085,
-.003447,.009108,
-.003289,.009697,
-.003031,.01025,
-.002681,.01075,
-.00225,.011181,
-.00175,.011531,
-.001197,.011789,
-.000608,.011947,
0.0,.012,
.000608,.011947,
.001197,.011789,
.00175,.011531,
.00225,.011181,
.002681,.01075,
.003031,.01025,
.003289,.009697,
.003447,.009108,
.0035,.0085,
0.0*
%
%ADD82MACRO82*%
%ADD295R,.197X.128*%
%ADD266R,.017X.059*%
%ADD184R,.205X.205*%
%ADD153R,.124X.124*%
%ADD134C,.009*%
%ADD219R,.134X.134*%
%ADD66R,.099X.042*%
%ADD22R,.048X.056*%
%ADD130R,.042X.099*%
%ADD54R,.144X.144*%
%ADD11C,.394*%
%ADD238R,.059X.048*%
%AMMACRO293*
4,1,24,-.01051,.04391,
-.01188,.04527,
-.03394,.04527,
-.03394,.03346,
-.02016,.03348,
-.02016,.02559,
-.03394,.02559,
-.03394,.01379,
-.02016,.0138,
-.02016,.0059,
-.03394,.00592,
-.03394,-.00591,
-.02016,-.00589,
-.02016,-.01378,
-.03394,-.01378,
-.03394,-.0256,
-.02016,-.02557,
-.02016,-.03347,
-.03394,-.03347,
-.03394,-.04527,
-.01188,-.04527,
-.00913,-.04255,
.03394,-.04255,
.03394,.04391,
-.01051,.04391,
0.0*
%
%ADD293MACRO293*%
%ADD43R,.059X.02047*%
%ADD239R,.189X.186*%
%ADD110R,.138X.138*%
%ADD72R,.174X.174*%
%ADD47R,.069X.077*%
%AMMACRO21*
4,1,28,.00052,-.00748,
.00052,-.00984,
.00603,-.00984,
.006705,-.009782,
.007359,-.009607,
.007974,-.009321,
.008529,-.008933,
.009009,-.008455,
.009398,-.0079,
.009685,-.007286,
.009861,-.006632,
.00992,-.005957,
.00992,-.00591,
.00992,.00591,
.009869,.006585,
.009701,.007242,
.009421,.007859,
.009039,.008418,
.008565,.008903,
.008015,.009297,
.007404,.009591,
.006751,.009773,
.006077,.00984,
.00603,.00984,
.00052,.00984,
.00052,.00748,
-.00991,.00748,
-.00991,-.00748,
.00052,-.00748,
0.0*
%
%ADD21MACRO21*%
%AMMACRO17*
4,1,28,.00748,.00052,
.00984,.00052,
.00984,.00603,
.009782,.006705,
.009607,.007359,
.009321,.007974,
.008933,.008529,
.008455,.009009,
.0079,.009398,
.007286,.009685,
.006632,.009861,
.005957,.00992,
.00591,.00992,
-.00591,.00992,
-.006585,.009869,
-.007242,.009701,
-.007859,.009421,
-.008418,.009039,
-.008903,.008565,
-.009297,.008015,
-.009591,.007404,
-.009773,.006751,
-.00984,.006077,
-.00984,.00603,
-.00984,.00052,
-.00748,.00052,
-.00748,-.00991,
.00748,-.00991,
.00748,.00052,
0.0*
%
%ADD17MACRO17*%
%ADD133R,.099X.067*%
%ADD147R,.067X.099*%
%AMMACRO258*
4,1,5,.01673,-.00492,
.01673,.00492,
-.01673,.00492,
-.01673,-.00098,
-.0128,-.00492,
.01673,-.00492,
0.0*
%
%ADD258MACRO258*%
%AMMACRO170*
4,1,5,-.01378,-.00098,
-.01378,.00492,
.01378,.00492,
.01378,-.00492,
-.00984,-.00492,
-.01378,-.00098,
0.0*
%
%ADD170MACRO170*%
%AMMACRO20*
4,1,28,-.00051,-.00748,
-.00051,-.00984,
-.00602,-.00984,
-.006695,-.009782,
-.007349,-.009607,
-.007964,-.009321,
-.008519,-.008933,
-.008998,-.008455,
-.009388,-.0079,
-.009675,-.007287,
-.009851,-.006632,
-.00991,-.005958,
-.00991,-.00591,
-.00991,.00591,
-.009859,.006585,
-.009691,.007242,
-.009411,.007859,
-.009029,.008418,
-.008555,.008903,
-.008005,.009297,
-.007394,.00959,
-.006742,.009773,
-.006068,.00984,
-.00602,.00984,
-.00051,.00984,
-.00051,.00748,
.00992,.00748,
.00992,-.00748,
-.00051,-.00748,
0.0*
%
%ADD20MACRO20*%
%AMMACRO16*
4,1,28,.00748,-.00051,
.00984,-.00051,
.00984,-.00602,
.009782,-.006695,
.009607,-.007349,
.009321,-.007964,
.008933,-.008519,
.008455,-.008998,
.0079,-.009388,
.007287,-.009675,
.006632,-.009851,
.005958,-.00991,
.00591,-.00991,
-.00591,-.00991,
-.006585,-.009859,
-.007242,-.009691,
-.007859,-.009411,
-.008418,-.009029,
-.008903,-.008555,
-.009297,-.008005,
-.00959,-.007394,
-.009773,-.006742,
-.00984,-.006068,
-.00984,-.00602,
-.00984,-.00051,
-.00748,-.00051,
-.00748,.00992,
.00748,.00992,
.00748,-.00051,
0.0*
%
%ADD16MACRO16*%
%AMMACRO172*
4,1,5,-.00098,.01378,
.00492,.01378,
.00492,-.01378,
-.00492,-.01378,
-.00492,.00984,
-.00098,.01378,
0.0*
%
%ADD172MACRO172*%
%AMMACRO91*
4,1,13,-.00002,-.012,
-.000627,-.011943,
-.001216,-.011782,
-.001767,-.011521,
-.002265,-.011168,
-.002694,-.010734,
-.003041,-.010233,
-.003296,-.009678,
-.00345,-.009088,
-.0035,-.0085,
-.0035,.012,
.0035,.012,
.0035,-.00848,
-.00002,-.012,
0.0*
%
%ADD91MACRO91*%
%AMMACRO87*
4,1,13,.012,-.00002,
.011943,-.000627,
.011782,-.001216,
.011521,-.001767,
.011168,-.002265,
.010734,-.002694,
.010233,-.003041,
.009678,-.003296,
.009088,-.00345,
.0085,-.0035,
-.012,-.0035,
-.012,.0035,
.00848,.0035,
.012,-.00002,
0.0*
%
%ADD87MACRO87*%
%AMMACRO116*
4,1,6,.1063,.04134,
.1063,-.01378,
.03543,-.01378,
.03543,-.04134,
-.1063,-.04134,
-.1063,.04134,
.1063,.04134,
0.0*
%
%ADD116MACRO116*%
%AMMACRO177*
4,1,5,-.01378,.00098,
-.01378,-.00492,
.01378,-.00492,
.01378,.00492,
-.00984,.00492,
-.01378,.00098,
0.0*
%
%ADD177MACRO177*%
%AMMACRO282*
4,1,9,.01181,.01476,
-.01771,.01476,
-.01771,.00492,
.00394,.00492,
.00394,-.00492,
-.01771,-.00492,
-.01771,-.01476,
.01772,-.01476,
.01772,.00886,
.01181,.01476,
0.0*
%
%ADD282MACRO282*%
%AMMACRO257*
4,1,8,.0246,.01821,
.0246,-.01821,
.01476,-.01821,
.01476,.00837,
-.01477,.00837,
-.01477,-.01821,
-.02461,-.01821,
-.02461,.01821,
.0246,.01821,
0.0*
%
%ADD257MACRO257*%
%AMMACRO171*
4,1,5,.00098,.01378,
-.00492,.01378,
-.00492,-.01378,
.00492,-.01378,
.00492,.00984,
.00098,.01378,
0.0*
%
%ADD171MACRO171*%
%AMMACRO146*
4,1,9,.01476,-.01181,
.01476,.01771,
.00492,.01771,
.00492,-.00394,
-.00492,-.00394,
-.00492,.01771,
-.01476,.01771,
-.01476,-.01772,
.00886,-.01772,
.01476,-.01181,
0.0*
%
%ADD146MACRO146*%
%AMMACRO90*
4,1,13,-.0035,-.00849,
-.0035,.012,
.0035,.012,
.0035,-.0085,
.003447,-.009108,
.003289,-.009697,
.003031,-.01025,
.002681,-.01075,
.00225,-.011181,
.00175,-.011531,
.001197,-.011789,
.000608,-.011947,
.00001,-.012,
-.0035,-.00849,
0.0*
%
%ADD90MACRO90*%
%AMMACRO79*
4,1,13,.00849,-.0035,
-.012,-.0035,
-.012,.0035,
.0085,.0035,
.009108,.003447,
.009697,.003289,
.01025,.003031,
.01075,.002681,
.011181,.00225,
.011531,.00175,
.011789,.001197,
.011947,.000608,
.012,.00001,
.00849,-.0035,
0.0*
%
%ADD79MACRO79*%
%ADD298C,.006*%
G75*
%LPD*%
G75*
G54D100*
X186831Y151000D03*
X178169Y147260D03*
Y154740D03*
X396102Y536138D03*
X387440Y532398D03*
Y539878D03*
X588099Y253691D03*
Y261171D03*
X596761Y257431D03*
X608169Y447260D03*
X616831Y451000D03*
X608169Y454740D03*
X607557Y479606D03*
X616219Y475866D03*
Y483346D03*
X855184Y530845D03*
Y538325D03*
X863846Y534585D03*
X919968Y554548D03*
X928630Y558288D03*
X919968Y562028D03*
X1144118Y1445987D03*
Y1453467D03*
X1152780Y1449727D03*
G54D110*
X220523Y594408D03*
X252019D03*
X1322165Y577505D03*
Y609001D03*
G54D101*
X181503Y1516264D03*
Y1518626D03*
Y1520988D03*
Y1513902D03*
X179598Y1511505D03*
X181961D03*
X183548Y1517445D03*
Y1519807D03*
Y1522169D03*
X184323Y1511505D03*
X181503Y1530437D03*
Y1525713D03*
Y1532799D03*
Y1523351D03*
Y1528075D03*
X183548Y1531618D03*
Y1533980D03*
Y1536343D03*
Y1524532D03*
X181503Y1535162D03*
X179598Y1538431D03*
X181961D03*
X184323D03*
X189047Y1511505D03*
X189254Y1522200D03*
X193772Y1511505D03*
X193979Y1522200D03*
X198496Y1511505D03*
X198703Y1522200D03*
X186685Y1511505D03*
X191409D03*
X196134D03*
X200858D03*
X189254Y1524169D03*
Y1526137D03*
X193979Y1524169D03*
Y1526137D03*
X198703Y1524169D03*
Y1526137D03*
X189254Y1528106D03*
X193979D03*
X198703D03*
X189047Y1538431D03*
X193772D03*
X198496D03*
X186685D03*
X191409D03*
X196134D03*
X200858D03*
X203221Y1511505D03*
X203428Y1522200D03*
X207945Y1511505D03*
X208152Y1522200D03*
X212669Y1511505D03*
X212876Y1522200D03*
X215032Y1511505D03*
X205583D03*
X210307D03*
X212876Y1524169D03*
Y1526137D03*
X203428Y1524169D03*
Y1526137D03*
X208152Y1524169D03*
Y1526137D03*
X203428Y1528106D03*
X208152D03*
X212876D03*
X203221Y1538431D03*
X207945D03*
X212669D03*
X215032D03*
X205583D03*
X210307D03*
X217394Y1511505D03*
X217601Y1522200D03*
X222118Y1511505D03*
X222325Y1522200D03*
X226843Y1511505D03*
X227050Y1522200D03*
X219756Y1511505D03*
X224480D03*
X229205D03*
X227050Y1526137D03*
X217601Y1524169D03*
Y1526137D03*
X222325Y1524169D03*
Y1526137D03*
X227050Y1524169D03*
X217601Y1528106D03*
X222325D03*
X227050D03*
X217394Y1538431D03*
X222118D03*
X226843D03*
X219756D03*
X224480D03*
X229205D03*
X231567Y1511505D03*
X231774Y1522200D03*
X236291Y1511505D03*
X236498Y1522200D03*
X241016Y1511505D03*
X241223Y1522200D03*
X245740Y1511505D03*
X245947Y1522200D03*
X233929Y1511505D03*
X238654D03*
X243378D03*
X231774Y1524169D03*
Y1526137D03*
X236498Y1524169D03*
Y1526137D03*
X241223Y1524169D03*
Y1526137D03*
X245947Y1524169D03*
Y1526137D03*
X231774Y1528106D03*
X236498D03*
X241223D03*
X245947D03*
X231567Y1538431D03*
X236291D03*
X241016D03*
X245740D03*
X233929D03*
X238654D03*
X243378D03*
X255189Y1511505D03*
X255396Y1522200D03*
X259913Y1511505D03*
X260121Y1522200D03*
X261082Y1515083D03*
X250465Y1511505D03*
X250672Y1522200D03*
X248102Y1511505D03*
X252827D03*
X257551D03*
X255396Y1524169D03*
Y1526137D03*
X250672Y1524169D03*
Y1526137D03*
X255396Y1528106D03*
X261082Y1524532D03*
Y1526894D03*
Y1529256D03*
X250672Y1528106D03*
X255189Y1538431D03*
X259913D03*
X250465D03*
X248102D03*
X252827D03*
X257551D03*
X263128Y1516264D03*
X262276Y1511505D03*
X264638D03*
X263128Y1513902D03*
Y1518626D03*
Y1530437D03*
Y1525713D03*
Y1532799D03*
Y1528075D03*
X262276Y1538431D03*
X264638D03*
X309565Y1516264D03*
Y1518626D03*
Y1520988D03*
Y1513902D03*
X307660Y1511505D03*
X310023D03*
X311610Y1517445D03*
Y1519807D03*
Y1522169D03*
X312385Y1511505D03*
X317109D03*
X317316Y1522200D03*
X314747Y1511505D03*
X319471D03*
X309565Y1530437D03*
Y1525713D03*
X317316Y1524169D03*
Y1526137D03*
X309565Y1532799D03*
Y1523351D03*
Y1528075D03*
X311610Y1531618D03*
Y1533980D03*
Y1536343D03*
Y1524532D03*
X317316Y1528106D03*
X309565Y1535162D03*
X307660Y1538431D03*
X310023D03*
X312385D03*
X317109D03*
X314747D03*
X319471D03*
X321834Y1511505D03*
X322041Y1522200D03*
X326558Y1511505D03*
X326765Y1522200D03*
X331283Y1511505D03*
X331490Y1522200D03*
X324196Y1511505D03*
X328920D03*
X333645D03*
X322041Y1524169D03*
Y1526137D03*
X326765Y1524169D03*
Y1526137D03*
X331490Y1524169D03*
Y1526137D03*
X322041Y1528106D03*
X326765D03*
X331490D03*
X321834Y1538431D03*
X326558D03*
X331283D03*
X324196D03*
X328920D03*
X333645D03*
X336007Y1511505D03*
X336214Y1522200D03*
X340731Y1511505D03*
X340938Y1522200D03*
X345456Y1511505D03*
X345663Y1522200D03*
X350180Y1511505D03*
X350387Y1522200D03*
X343094Y1511505D03*
X347818D03*
X338369D03*
X340938Y1524169D03*
Y1526137D03*
X336214Y1524169D03*
Y1526137D03*
X345663Y1524169D03*
Y1526137D03*
X350387Y1524169D03*
Y1526137D03*
X336214Y1528106D03*
X340938D03*
X345663D03*
X350387D03*
X336007Y1538431D03*
X340731D03*
X345456D03*
X350180D03*
X343094D03*
X347818D03*
X338369D03*
X354905Y1511505D03*
X355112Y1522200D03*
X359629Y1511505D03*
X359836Y1522200D03*
X364353Y1511505D03*
X364560Y1522200D03*
X352542Y1511505D03*
X357267D03*
X361991D03*
X359836Y1524169D03*
Y1526137D03*
X364560Y1524169D03*
Y1526137D03*
X355112D03*
Y1524169D03*
Y1528106D03*
X359836D03*
X364560D03*
X354905Y1538431D03*
X359629D03*
X364353D03*
X352542D03*
X357267D03*
X361991D03*
X369078Y1511505D03*
X369285Y1522200D03*
X373802Y1511505D03*
X374009Y1522200D03*
X378527Y1511505D03*
X378734Y1522200D03*
X366716Y1511505D03*
X371440D03*
X376164D03*
X369285Y1524169D03*
Y1526137D03*
X374009Y1524169D03*
Y1526137D03*
X378734Y1524169D03*
Y1526137D03*
X369285Y1528106D03*
X374009D03*
X378734D03*
X369078Y1538431D03*
X373802D03*
X378527D03*
X366716D03*
X371440D03*
X376164D03*
X391190Y1516264D03*
X390338Y1511505D03*
X392700D03*
X383251D03*
X383458Y1522200D03*
X387975Y1511505D03*
X388183Y1522200D03*
X389144Y1515083D03*
X391190Y1513902D03*
Y1518626D03*
X380889Y1511505D03*
X385613D03*
X391190Y1530437D03*
Y1525713D03*
X383458Y1524169D03*
Y1526137D03*
X391190Y1532799D03*
X383458Y1528106D03*
X389144Y1524532D03*
Y1526894D03*
Y1529256D03*
X391190Y1528075D03*
X390338Y1538431D03*
X392700D03*
X383251D03*
X387975D03*
X380889D03*
X385613D03*
X445676Y1516264D03*
Y1518626D03*
Y1520988D03*
Y1513902D03*
X443771Y1511505D03*
X446134D03*
X447721Y1517445D03*
Y1519807D03*
Y1522169D03*
X448496Y1511505D03*
X453220D03*
X453427Y1522200D03*
X450858Y1511505D03*
X445676Y1530437D03*
Y1525713D03*
X453427Y1524169D03*
Y1526137D03*
X445676Y1532799D03*
Y1523351D03*
Y1528075D03*
X447721Y1531618D03*
Y1533980D03*
Y1536343D03*
Y1524532D03*
X453427Y1528106D03*
X445676Y1535162D03*
X443771Y1538431D03*
X446134D03*
X448496D03*
X453220D03*
X450858D03*
X457945Y1511505D03*
X458152Y1522200D03*
X462669Y1511505D03*
X462876Y1522200D03*
X467394Y1511505D03*
X467601Y1522200D03*
X455582Y1511505D03*
X460307D03*
X465031D03*
X469756D03*
X458152Y1524169D03*
Y1526137D03*
X462876Y1524169D03*
Y1526137D03*
X467601Y1524169D03*
Y1526137D03*
X458152Y1528106D03*
X462876D03*
X467601D03*
X457945Y1538431D03*
X462669D03*
X467394D03*
X455582D03*
X460307D03*
X465031D03*
X469756D03*
X472118Y1511505D03*
X472325Y1522200D03*
X476842Y1511505D03*
X477049Y1522200D03*
X481567Y1511505D03*
X481774Y1522200D03*
X479205Y1511505D03*
X483929D03*
X474480D03*
X477049Y1524169D03*
Y1526137D03*
X472325Y1524169D03*
Y1526137D03*
X481774Y1524169D03*
Y1526137D03*
X472325Y1528106D03*
X477049D03*
X481774D03*
X472118Y1538431D03*
X476842D03*
X481567D03*
X479205D03*
X483929D03*
X474480D03*
X486291Y1511505D03*
X486498Y1522200D03*
X491016Y1511505D03*
X491223Y1522200D03*
X495740Y1511505D03*
X495947Y1522200D03*
X488653Y1511505D03*
X493378D03*
X498102D03*
X495947Y1524169D03*
Y1526137D03*
X491223D03*
X486498Y1524169D03*
Y1526137D03*
X491223Y1524169D03*
X486498Y1528106D03*
X491223D03*
X495947D03*
X486291Y1538431D03*
X491016D03*
X495740D03*
X488653D03*
X493378D03*
X498102D03*
X500464Y1511505D03*
X500671Y1522200D03*
X505189Y1511505D03*
X505396Y1522200D03*
X509913Y1511505D03*
X510120Y1522200D03*
X502827Y1511505D03*
X507551D03*
X512275D03*
X500671Y1524169D03*
Y1526137D03*
X505396Y1524169D03*
Y1526137D03*
X510120Y1524169D03*
Y1526137D03*
X500671Y1528106D03*
X505396D03*
X510120D03*
X500464Y1538431D03*
X505189D03*
X509913D03*
X502827D03*
X507551D03*
X512275D03*
X527301Y1516264D03*
X526449Y1511505D03*
X528811D03*
X519362D03*
X519569Y1522200D03*
X524086Y1511505D03*
X524294Y1522200D03*
X525255Y1515083D03*
X527301Y1513902D03*
Y1518626D03*
X514638Y1511505D03*
X514845Y1522200D03*
X517000Y1511505D03*
X521724D03*
X527301Y1530437D03*
Y1525713D03*
X519569Y1524169D03*
Y1526137D03*
X514845Y1524169D03*
Y1526137D03*
X527301Y1532799D03*
X519569Y1528106D03*
X525255Y1524532D03*
Y1526894D03*
Y1529256D03*
X527301Y1528075D03*
X514845Y1528106D03*
X526449Y1538431D03*
X528811D03*
X519362D03*
X524086D03*
X514638D03*
X517000D03*
X521724D03*
X573738Y1516264D03*
Y1518626D03*
Y1520988D03*
Y1513902D03*
X571833Y1511505D03*
X573738Y1530437D03*
Y1525713D03*
Y1532799D03*
Y1523351D03*
Y1528075D03*
Y1535162D03*
X571833Y1538431D03*
X574196Y1511505D03*
X575783Y1517445D03*
Y1519807D03*
Y1522169D03*
X576558Y1511505D03*
X581282D03*
X581489Y1522200D03*
X586007Y1511505D03*
X586214Y1522200D03*
X578920Y1511505D03*
X583644D03*
X588369D03*
X581489Y1524169D03*
Y1526137D03*
X586214Y1524169D03*
Y1526137D03*
X575783Y1531618D03*
Y1533980D03*
Y1536343D03*
Y1524532D03*
X581489Y1528106D03*
X586214D03*
X574196Y1538431D03*
X576558D03*
X581282D03*
X586007D03*
X578920D03*
X583644D03*
X588369D03*
X590731Y1511505D03*
X590938Y1522200D03*
X595456Y1511505D03*
X595663Y1522200D03*
X600180Y1511505D03*
X600387Y1522200D03*
X593093Y1511505D03*
X597818D03*
X602542D03*
X590938Y1524169D03*
Y1526137D03*
X595663Y1524169D03*
Y1526137D03*
X600387Y1524169D03*
Y1526137D03*
X590938Y1528106D03*
X595663D03*
X600387D03*
X590731Y1538431D03*
X595456D03*
X600180D03*
X593093D03*
X597818D03*
X602542D03*
X604904Y1511505D03*
X605111Y1522200D03*
X609629Y1511505D03*
X609836Y1522200D03*
X614353Y1511505D03*
X614560Y1522200D03*
X607267Y1511505D03*
X611991D03*
X616715D03*
X605111Y1524169D03*
Y1526137D03*
X609836Y1524169D03*
Y1526137D03*
X614560Y1524169D03*
Y1526137D03*
X605111Y1528106D03*
X609836D03*
X614560D03*
X604904Y1538431D03*
X609629D03*
X614353D03*
X607267D03*
X611991D03*
X616715D03*
X619078Y1511505D03*
X619285Y1522200D03*
X623802Y1511505D03*
X624009Y1522200D03*
X628526Y1511505D03*
X628733Y1522200D03*
X633251Y1511505D03*
X633458Y1522200D03*
X621440Y1511505D03*
X626164D03*
X630889D03*
X624009Y1524169D03*
Y1526137D03*
X628733Y1524169D03*
Y1526137D03*
X633458Y1524169D03*
Y1526137D03*
X619285D03*
Y1524169D03*
Y1528106D03*
X624009D03*
X628733D03*
X633458D03*
X619078Y1538431D03*
X623802D03*
X628526D03*
X633251D03*
X621440D03*
X626164D03*
X630889D03*
X647424Y1511505D03*
X647631Y1522200D03*
X637975Y1511505D03*
X638182Y1522200D03*
X642700Y1511505D03*
X642907Y1522200D03*
X635613Y1511505D03*
X640337D03*
X645062D03*
X647631Y1524169D03*
Y1526137D03*
X638182Y1524169D03*
Y1526137D03*
X642907Y1524169D03*
Y1526137D03*
X647631Y1528106D03*
X638182D03*
X642907D03*
X647424Y1538431D03*
X637975D03*
X642700D03*
X635613D03*
X640337D03*
X645062D03*
X655363Y1516264D03*
X654511Y1511505D03*
X656873D03*
X652148D03*
X652356Y1522200D03*
X653317Y1515083D03*
X655363Y1513902D03*
Y1518626D03*
X649786Y1511505D03*
X655363Y1530437D03*
Y1525713D03*
Y1532799D03*
X653317Y1524532D03*
Y1526894D03*
Y1529256D03*
X655363Y1528075D03*
X654511Y1538431D03*
X656873D03*
X652148D03*
X649786D03*
X1189376Y1549264D03*
Y1551626D03*
Y1546902D03*
X1187471Y1544505D03*
X1189834D03*
X1191421Y1550445D03*
X1192196Y1544505D03*
X1196920D03*
X1194558D03*
X1199282D03*
X1189376Y1553988D03*
Y1563437D03*
Y1558713D03*
X1197127Y1557169D03*
Y1559137D03*
X1189376Y1565799D03*
Y1556351D03*
Y1561075D03*
X1191421Y1564618D03*
Y1566980D03*
Y1552807D03*
Y1555169D03*
Y1557532D03*
X1197127Y1555200D03*
Y1561106D03*
X1187471Y1571431D03*
X1189834D03*
X1191421Y1569343D03*
X1192196Y1571431D03*
X1196920D03*
X1189376Y1568162D03*
X1194558Y1571431D03*
X1199282D03*
X1201645Y1544505D03*
X1206369D03*
X1211094D03*
X1204007D03*
X1208731D03*
X1213456D03*
X1201852Y1557169D03*
Y1559137D03*
X1206576Y1557169D03*
Y1559137D03*
X1211301Y1557169D03*
Y1559137D03*
X1201852Y1555200D03*
Y1561106D03*
X1206576Y1555200D03*
Y1561106D03*
X1211301Y1555200D03*
Y1561106D03*
X1201645Y1571431D03*
X1206369D03*
X1211094D03*
X1204007D03*
X1208731D03*
X1213456D03*
X1215818Y1544505D03*
X1220542D03*
X1225267D03*
X1229991D03*
X1222905D03*
X1227629D03*
X1218180D03*
X1220749Y1557169D03*
Y1559137D03*
X1216025Y1557169D03*
Y1559137D03*
X1225474Y1557169D03*
Y1559137D03*
X1216025Y1555200D03*
Y1561106D03*
X1220749Y1555200D03*
Y1561106D03*
X1225474Y1555200D03*
Y1561106D03*
X1215818Y1571431D03*
X1220542D03*
X1225267D03*
X1229991D03*
X1222905D03*
X1227629D03*
X1218180D03*
X1234716Y1544505D03*
X1239440D03*
X1244164D03*
X1232353D03*
X1237078D03*
X1241802D03*
X1239647Y1557169D03*
Y1559137D03*
X1244371Y1557169D03*
Y1559137D03*
X1234923D03*
X1230198Y1557169D03*
Y1559137D03*
X1234923Y1557169D03*
X1230198Y1555200D03*
Y1561106D03*
X1234923Y1555200D03*
Y1561106D03*
X1239647Y1555200D03*
Y1561106D03*
X1244371Y1555200D03*
Y1561106D03*
X1234716Y1571431D03*
X1239440D03*
X1244164D03*
X1232353D03*
X1237078D03*
X1241802D03*
X1248889Y1544505D03*
X1253613D03*
X1258338D03*
X1246527D03*
X1251251D03*
X1255975D03*
X1249096Y1557169D03*
Y1559137D03*
X1253820Y1557169D03*
Y1559137D03*
X1258545Y1557169D03*
Y1559137D03*
X1249096Y1555200D03*
Y1561106D03*
X1253820Y1555200D03*
Y1561106D03*
X1258545Y1555200D03*
Y1561106D03*
X1248889Y1571431D03*
X1253613D03*
X1258338D03*
X1246527D03*
X1251251D03*
X1255975D03*
X1271001Y1549264D03*
X1270149Y1544505D03*
X1272511D03*
X1263062D03*
X1267786D03*
X1268955Y1548083D03*
X1271001Y1546902D03*
Y1551626D03*
X1260700Y1544505D03*
X1265424D03*
X1271001Y1563437D03*
Y1558713D03*
X1263269Y1557169D03*
Y1559137D03*
X1271001Y1565799D03*
X1263269Y1555200D03*
Y1561106D03*
X1267994Y1555200D03*
X1268955Y1557532D03*
Y1559894D03*
Y1562256D03*
X1271001Y1561075D03*
X1270149Y1571431D03*
X1272511D03*
X1263062D03*
X1267786D03*
X1260700D03*
X1265424D03*
X1317438Y1549264D03*
Y1551626D03*
Y1546902D03*
X1315533Y1544505D03*
X1317896D03*
X1319483Y1550445D03*
X1317438Y1553988D03*
Y1563437D03*
Y1558713D03*
Y1565799D03*
Y1556351D03*
Y1561075D03*
X1319483Y1564618D03*
Y1566980D03*
Y1552807D03*
Y1555169D03*
Y1557532D03*
X1315533Y1571431D03*
X1317896D03*
X1319483Y1569343D03*
X1317438Y1568162D03*
X1320258Y1544505D03*
X1324982D03*
X1329707D03*
X1334431D03*
X1322620D03*
X1327344D03*
X1332069D03*
X1325189Y1557169D03*
Y1559137D03*
X1329914Y1557169D03*
Y1559137D03*
X1325189Y1555200D03*
Y1561106D03*
X1329914Y1555200D03*
Y1561106D03*
X1320258Y1571431D03*
X1324982D03*
X1329707D03*
X1334431D03*
X1322620D03*
X1327344D03*
X1332069D03*
X1339156Y1544505D03*
X1343880D03*
X1348604D03*
X1336793D03*
X1341518D03*
X1346242D03*
X1348811Y1557169D03*
Y1559137D03*
X1334638Y1557169D03*
Y1559137D03*
X1339363Y1557169D03*
Y1559137D03*
X1344087Y1557169D03*
Y1559137D03*
X1334638Y1555200D03*
Y1561106D03*
X1339363Y1555200D03*
Y1561106D03*
X1344087Y1555200D03*
Y1561106D03*
X1348811Y1555200D03*
Y1561106D03*
X1339156Y1571431D03*
X1343880D03*
X1348604D03*
X1336793D03*
X1341518D03*
X1346242D03*
X1353329Y1544505D03*
X1358053D03*
X1362778D03*
X1350967D03*
X1355691D03*
X1360415D03*
X1362985Y1559137D03*
X1353536Y1557169D03*
Y1559137D03*
X1358260Y1557169D03*
Y1559137D03*
X1362985Y1557169D03*
X1353536Y1555200D03*
Y1561106D03*
X1358260Y1555200D03*
Y1561106D03*
X1362985Y1555200D03*
Y1561106D03*
X1353329Y1571431D03*
X1358053D03*
X1362778D03*
X1350967D03*
X1355691D03*
X1360415D03*
X1367502Y1544505D03*
X1372226D03*
X1376951D03*
X1365140D03*
X1369864D03*
X1374589D03*
X1367709Y1557169D03*
Y1559137D03*
X1372433Y1557169D03*
Y1559137D03*
X1377158Y1557169D03*
Y1559137D03*
X1367709Y1555200D03*
Y1561106D03*
X1372433Y1555200D03*
Y1561106D03*
X1377158Y1555200D03*
Y1561106D03*
X1367502Y1571431D03*
X1372226D03*
X1376951D03*
X1365140D03*
X1369864D03*
X1374589D03*
X1391124Y1544505D03*
X1381675D03*
X1386400D03*
X1379313D03*
X1384037D03*
X1388762D03*
X1393486D03*
X1391331Y1557169D03*
Y1559137D03*
X1381882Y1557169D03*
Y1559137D03*
X1386607Y1557169D03*
Y1559137D03*
X1391331Y1555200D03*
Y1561106D03*
X1381882Y1555200D03*
Y1561106D03*
X1386607Y1555200D03*
Y1561106D03*
X1391124Y1571431D03*
X1381675D03*
X1386400D03*
X1379313D03*
X1384037D03*
X1388762D03*
X1393486D03*
X1399063Y1549264D03*
X1398211Y1544505D03*
X1400573D03*
X1395848D03*
X1397017Y1548083D03*
X1399063Y1546902D03*
Y1551626D03*
Y1563437D03*
Y1558713D03*
Y1565799D03*
X1396056Y1555200D03*
X1397017Y1557532D03*
Y1559894D03*
Y1562256D03*
X1399063Y1561075D03*
X1398211Y1571431D03*
X1400573D03*
X1395848D03*
X1453550Y1549264D03*
Y1551626D03*
Y1546902D03*
X1451645Y1544505D03*
X1453550Y1553988D03*
Y1563437D03*
Y1558713D03*
Y1565799D03*
Y1556351D03*
Y1561075D03*
X1451645Y1571431D03*
X1453550Y1568162D03*
X1454008Y1544505D03*
X1455595Y1550445D03*
X1456370Y1544505D03*
X1461094D03*
X1465819D03*
X1458732D03*
X1463456D03*
X1468181D03*
X1461301Y1557169D03*
Y1559137D03*
X1466026Y1557169D03*
Y1559137D03*
X1455595Y1564618D03*
Y1566980D03*
Y1552807D03*
Y1555169D03*
Y1557532D03*
X1461301Y1555200D03*
Y1561106D03*
X1466026Y1555200D03*
Y1561106D03*
X1454008Y1571431D03*
X1455595Y1569343D03*
X1456370Y1571431D03*
X1461094D03*
X1465819D03*
X1458732D03*
X1463456D03*
X1468181D03*
X1470543Y1544505D03*
X1475268D03*
X1479992D03*
X1472905D03*
X1477630D03*
X1482354D03*
X1470750Y1557169D03*
Y1559137D03*
X1475475Y1557169D03*
Y1559137D03*
X1480199Y1557169D03*
Y1559137D03*
X1470750Y1555200D03*
Y1561106D03*
X1475475Y1555200D03*
Y1561106D03*
X1480199Y1555200D03*
Y1561106D03*
X1470543Y1571431D03*
X1475268D03*
X1479992D03*
X1472905D03*
X1477630D03*
X1482354D03*
X1484716Y1544505D03*
X1489441D03*
X1494165D03*
X1487079D03*
X1491803D03*
X1496527D03*
X1484923Y1557169D03*
Y1559137D03*
X1489648Y1557169D03*
Y1559137D03*
X1494372Y1557169D03*
Y1559137D03*
X1484923Y1555200D03*
Y1561106D03*
X1489648Y1555200D03*
Y1561106D03*
X1494372Y1555200D03*
Y1561106D03*
X1484716Y1571431D03*
X1489441D03*
X1494165D03*
X1487079D03*
X1491803D03*
X1496527D03*
X1498890Y1544505D03*
X1503614D03*
X1508338D03*
X1513063D03*
X1501252D03*
X1505976D03*
X1510701D03*
X1503821Y1557169D03*
Y1559137D03*
X1508545Y1557169D03*
Y1559137D03*
X1513270Y1557169D03*
Y1559137D03*
X1499097D03*
Y1557169D03*
Y1555200D03*
Y1561106D03*
X1503821Y1555200D03*
Y1561106D03*
X1508545Y1555200D03*
Y1561106D03*
X1513270Y1555200D03*
Y1561106D03*
X1498890Y1571431D03*
X1503614D03*
X1508338D03*
X1513063D03*
X1501252D03*
X1505976D03*
X1510701D03*
X1527236Y1544505D03*
X1517787D03*
X1522512D03*
X1515425D03*
X1520149D03*
X1524874D03*
X1527443Y1557169D03*
Y1559137D03*
X1517994Y1557169D03*
Y1559137D03*
X1522719Y1557169D03*
Y1559137D03*
X1527443Y1555200D03*
Y1561106D03*
X1517994Y1555200D03*
Y1561106D03*
X1522719Y1555200D03*
Y1561106D03*
X1527236Y1571431D03*
X1517787D03*
X1522512D03*
X1515425D03*
X1520149D03*
X1524874D03*
X1535175Y1549264D03*
X1534323Y1544505D03*
X1536685D03*
X1531960D03*
X1533129Y1548083D03*
X1535175Y1546902D03*
Y1551626D03*
X1529598Y1544505D03*
X1535175Y1563437D03*
Y1558713D03*
Y1565799D03*
X1532168Y1555200D03*
X1533129Y1557532D03*
Y1559894D03*
Y1562256D03*
X1535175Y1561075D03*
X1534323Y1571431D03*
X1536685D03*
X1531960D03*
X1529598D03*
X1581612Y1549264D03*
Y1551626D03*
Y1546902D03*
X1579707Y1544505D03*
X1582070D03*
X1583657Y1550445D03*
X1584432Y1544505D03*
X1586794D03*
X1581612Y1553988D03*
Y1563437D03*
Y1558713D03*
Y1565799D03*
Y1556351D03*
Y1561075D03*
X1583657Y1564618D03*
Y1566980D03*
Y1552807D03*
Y1555169D03*
Y1557532D03*
X1579707Y1571431D03*
X1582070D03*
X1583657Y1569343D03*
X1584432Y1571431D03*
X1581612Y1568162D03*
X1586794Y1571431D03*
X1589156Y1544505D03*
X1593881D03*
X1598605D03*
X1591518D03*
X1596243D03*
X1600967D03*
X1589363Y1557169D03*
Y1559137D03*
X1594088Y1557169D03*
Y1559137D03*
X1598812Y1557169D03*
Y1559137D03*
X1589363Y1555200D03*
Y1561106D03*
X1594088Y1555200D03*
Y1561106D03*
X1598812Y1555200D03*
Y1561106D03*
X1589156Y1571431D03*
X1593881D03*
X1598605D03*
X1591518D03*
X1596243D03*
X1600967D03*
X1603330Y1544505D03*
X1608054D03*
X1612778D03*
X1617503D03*
X1615141D03*
X1605692D03*
X1610416D03*
X1612985Y1557169D03*
Y1559137D03*
X1603537Y1557169D03*
Y1559137D03*
X1608261Y1557169D03*
Y1559137D03*
X1603537Y1555200D03*
Y1561106D03*
X1608261Y1555200D03*
Y1561106D03*
X1612985Y1555200D03*
Y1561106D03*
X1603330Y1571431D03*
X1608054D03*
X1612778D03*
X1617503D03*
X1615141D03*
X1605692D03*
X1610416D03*
X1622227Y1544505D03*
X1626952D03*
X1631676D03*
X1619865D03*
X1624589D03*
X1629314D03*
X1631883Y1557169D03*
Y1559137D03*
X1627159D03*
X1617710Y1557169D03*
Y1559137D03*
X1622434Y1557169D03*
Y1559137D03*
X1627159Y1557169D03*
X1617710Y1555200D03*
Y1561106D03*
X1622434Y1555200D03*
Y1561106D03*
X1627159Y1555200D03*
Y1561106D03*
X1631883Y1555200D03*
Y1561106D03*
X1622227Y1571431D03*
X1626952D03*
X1631676D03*
X1619865D03*
X1624589D03*
X1629314D03*
X1636400Y1544505D03*
X1641125D03*
X1645849D03*
X1634038D03*
X1638763D03*
X1643487D03*
X1636607Y1557169D03*
Y1559137D03*
X1641332Y1557169D03*
Y1559137D03*
X1646056Y1557169D03*
Y1559137D03*
X1636607Y1555200D03*
Y1561106D03*
X1641332Y1555200D03*
Y1561106D03*
X1646056Y1555200D03*
Y1561106D03*
X1636400Y1571431D03*
X1641125D03*
X1645849D03*
X1634038D03*
X1638763D03*
X1643487D03*
X1662385Y1544505D03*
X1655298D03*
X1660022D03*
X1661191Y1548083D03*
X1650574Y1544505D03*
X1648211D03*
X1652936D03*
X1657660D03*
X1655505Y1557169D03*
Y1559137D03*
X1650781Y1557169D03*
Y1559137D03*
X1655505Y1555200D03*
Y1561106D03*
X1660230Y1555200D03*
X1661191Y1557532D03*
Y1559894D03*
Y1562256D03*
X1650781Y1555200D03*
Y1561106D03*
X1662385Y1571431D03*
X1655298D03*
X1660022D03*
X1650574D03*
X1648211D03*
X1652936D03*
X1657660D03*
X1663237Y1549264D03*
X1664747Y1544505D03*
X1663237Y1546902D03*
Y1551626D03*
Y1563437D03*
Y1558713D03*
Y1565799D03*
Y1561075D03*
X1664747Y1571431D03*
G54D200*
X628988Y1415094D03*
X637447Y1421755D03*
X1307050Y546690D03*
G54D201*
X642394Y128047D03*
X638654D03*
X634914D03*
Y137495D03*
X642394D03*
G54D210*
X723436Y648667D03*
X716822D03*
X1148544Y1556029D03*
X1141930D03*
X1469652Y1679401D03*
X1476266D03*
G54D102*
X180780Y1509459D03*
X183142D03*
X185504D03*
X180780Y1540477D03*
X183142D03*
X185504D03*
X187866Y1509459D03*
X192591D03*
X197315D03*
X190228D03*
X194953D03*
X199677D03*
X187866Y1540477D03*
X192591D03*
X197315D03*
X190228D03*
X194953D03*
X199677D03*
X202039Y1509459D03*
X206764D03*
X211488D03*
X216213D03*
X213850D03*
X204402D03*
X209126D03*
X202039Y1540477D03*
X206764D03*
X211488D03*
X216213D03*
X213850D03*
X204402D03*
X209126D03*
X220937Y1509459D03*
X225661D03*
X230386D03*
X218575D03*
X223299D03*
X228024D03*
X220937Y1540477D03*
X225661D03*
X230386D03*
X218575D03*
X223299D03*
X228024D03*
X235110Y1509459D03*
X239835D03*
X244559D03*
X232748D03*
X237472D03*
X242197D03*
X235110Y1540477D03*
X239835D03*
X244559D03*
X232748D03*
X237472D03*
X242197D03*
X254008Y1509459D03*
X258732D03*
X249283D03*
X246921D03*
X251646D03*
X256370D03*
X254008Y1540477D03*
X258732D03*
X249283D03*
X246921D03*
X251646D03*
X256370D03*
X263457Y1509459D03*
X265819D03*
X261095D03*
Y1540477D03*
X263457D03*
X265819D03*
X308842Y1509459D03*
X311204D03*
X315928D03*
X313566D03*
X318290D03*
X308842Y1540477D03*
X311204D03*
X315928D03*
X313566D03*
X318290D03*
X320653Y1509459D03*
X325377D03*
X330101D03*
X334826D03*
X323015D03*
X327739D03*
X332464D03*
X320653Y1540477D03*
X325377D03*
X330101D03*
X334826D03*
X323015D03*
X327739D03*
X332464D03*
X339550Y1509459D03*
X344275D03*
X348999D03*
X341912D03*
X346637D03*
X337188D03*
X339550Y1540477D03*
X344275D03*
X348999D03*
X341912D03*
X346637D03*
X337188D03*
X353723Y1509459D03*
X358448D03*
X363172D03*
X351361D03*
X356086D03*
X360810D03*
X353723Y1540477D03*
X358448D03*
X363172D03*
X351361D03*
X356086D03*
X360810D03*
X367897Y1509459D03*
X372621D03*
X377345D03*
X365534D03*
X370259D03*
X374983D03*
X379708D03*
X367897Y1540477D03*
X372621D03*
X377345D03*
X365534D03*
X370259D03*
X374983D03*
X379708D03*
X391519Y1509459D03*
X393881D03*
X382070D03*
X386794D03*
X389157D03*
X384432D03*
X389157Y1540477D03*
X391519D03*
X393881D03*
X382070D03*
X386794D03*
X384432D03*
X444953Y1509459D03*
X447315D03*
X452039D03*
X449677D03*
X454401D03*
X444953Y1540477D03*
X447315D03*
X452039D03*
X449677D03*
X454401D03*
X456764Y1509459D03*
X461488D03*
X466212D03*
X459126D03*
X463850D03*
X468575D03*
X456764Y1540477D03*
X461488D03*
X466212D03*
X459126D03*
X463850D03*
X468575D03*
X470937Y1509459D03*
X475661D03*
X480386D03*
X478023D03*
X482748D03*
X473299D03*
X470937Y1540477D03*
X475661D03*
X480386D03*
X478023D03*
X482748D03*
X473299D03*
X485110Y1509459D03*
X489834D03*
X494559D03*
X499283D03*
X487472D03*
X492197D03*
X496921D03*
X485110Y1540477D03*
X489834D03*
X494559D03*
X499283D03*
X487472D03*
X492197D03*
X496921D03*
X504008Y1509459D03*
X508732D03*
X513456D03*
X501645D03*
X506370D03*
X511094D03*
X504008Y1540477D03*
X508732D03*
X513456D03*
X501645D03*
X506370D03*
X511094D03*
X527630Y1509459D03*
X518181D03*
X522905D03*
X525268D03*
X515819D03*
X520543D03*
X525268Y1540477D03*
X527630D03*
X518181D03*
X522905D03*
X515819D03*
X520543D03*
X529992Y1509459D03*
Y1540477D03*
X573015Y1509459D03*
Y1540477D03*
X575377Y1509459D03*
X580101D03*
X584826D03*
X577739D03*
X582463D03*
X587188D03*
X575377Y1540477D03*
X580101D03*
X584826D03*
X577739D03*
X582463D03*
X587188D03*
X589550Y1509459D03*
X594274D03*
X598999D03*
X603723D03*
X591912D03*
X596637D03*
X601361D03*
X589550Y1540477D03*
X594274D03*
X598999D03*
X603723D03*
X591912D03*
X596637D03*
X601361D03*
X608448Y1509459D03*
X613172D03*
X617896D03*
X606085D03*
X610810D03*
X615534D03*
X608448Y1540477D03*
X613172D03*
X617896D03*
X606085D03*
X610810D03*
X615534D03*
X622621Y1509459D03*
X627345D03*
X632070D03*
X620259D03*
X624983D03*
X629707D03*
X622621Y1540477D03*
X627345D03*
X632070D03*
X620259D03*
X624983D03*
X629707D03*
X646243Y1509459D03*
X636794D03*
X641518D03*
X634432D03*
X639156D03*
X643881D03*
X648605D03*
X646243Y1540477D03*
X636794D03*
X641518D03*
X634432D03*
X639156D03*
X643881D03*
X648605D03*
X655692Y1509459D03*
X658054D03*
X650967D03*
X653330D03*
Y1540477D03*
X655692D03*
X658054D03*
X650967D03*
X1188653Y1542459D03*
X1191015D03*
X1195739D03*
X1193377D03*
X1198101D03*
X1188653Y1573477D03*
X1191015D03*
X1195739D03*
X1193377D03*
X1198101D03*
X1200464Y1542459D03*
X1205188D03*
X1209912D03*
X1214637D03*
X1202826D03*
X1207550D03*
X1212275D03*
X1200464Y1573477D03*
X1205188D03*
X1209912D03*
X1214637D03*
X1202826D03*
X1207550D03*
X1212275D03*
X1219361Y1542459D03*
X1224086D03*
X1228810D03*
X1221723D03*
X1226448D03*
X1216999D03*
X1219361Y1573477D03*
X1224086D03*
X1228810D03*
X1221723D03*
X1226448D03*
X1216999D03*
X1233534Y1542459D03*
X1238259D03*
X1242983D03*
X1231172D03*
X1235897D03*
X1240621D03*
X1233534Y1573477D03*
X1238259D03*
X1242983D03*
X1231172D03*
X1235897D03*
X1240621D03*
X1247708Y1542459D03*
X1252432D03*
X1257156D03*
X1245345D03*
X1250070D03*
X1254794D03*
X1259519D03*
X1247708Y1573477D03*
X1252432D03*
X1257156D03*
X1245345D03*
X1250070D03*
X1254794D03*
X1259519D03*
X1271330Y1542459D03*
X1273692D03*
X1261881D03*
X1266605D03*
X1268968D03*
X1264243D03*
X1268968Y1573477D03*
X1271330D03*
X1273692D03*
X1261881D03*
X1266605D03*
X1264243D03*
X1316715Y1542459D03*
X1319077D03*
X1316715Y1573477D03*
X1319077D03*
X1323801Y1542459D03*
X1328526D03*
X1333250D03*
X1321439D03*
X1326163D03*
X1330888D03*
X1323801Y1573477D03*
X1328526D03*
X1333250D03*
X1321439D03*
X1326163D03*
X1330888D03*
X1337974Y1542459D03*
X1342699D03*
X1347423D03*
X1335612D03*
X1340337D03*
X1345061D03*
X1337974Y1573477D03*
X1342699D03*
X1347423D03*
X1335612D03*
X1340337D03*
X1345061D03*
X1352148Y1542459D03*
X1356872D03*
X1361596D03*
X1349785D03*
X1354510D03*
X1359234D03*
X1363959D03*
X1352148Y1573477D03*
X1356872D03*
X1361596D03*
X1349785D03*
X1354510D03*
X1359234D03*
X1363959D03*
X1366321Y1542459D03*
X1371045D03*
X1375770D03*
X1368683D03*
X1373407D03*
X1378132D03*
X1366321Y1573477D03*
X1371045D03*
X1375770D03*
X1368683D03*
X1373407D03*
X1378132D03*
X1389943Y1542459D03*
X1380494D03*
X1385218D03*
X1382856D03*
X1387581D03*
X1392305D03*
X1389943Y1573477D03*
X1380494D03*
X1385218D03*
X1382856D03*
X1387581D03*
X1392305D03*
X1399392Y1542459D03*
X1401754D03*
X1394667D03*
X1397030D03*
Y1573477D03*
X1399392D03*
X1401754D03*
X1394667D03*
X1452827Y1542459D03*
Y1573477D03*
X1455189Y1542459D03*
X1459913D03*
X1464638D03*
X1457551D03*
X1462275D03*
X1467000D03*
X1455189Y1573477D03*
X1459913D03*
X1464638D03*
X1457551D03*
X1462275D03*
X1467000D03*
X1469362Y1542459D03*
X1474086D03*
X1478811D03*
X1471724D03*
X1476449D03*
X1481173D03*
X1469362Y1573477D03*
X1474086D03*
X1478811D03*
X1471724D03*
X1476449D03*
X1481173D03*
X1483535Y1542459D03*
X1488260D03*
X1492984D03*
X1497708D03*
X1485897D03*
X1490622D03*
X1495346D03*
X1483535Y1573477D03*
X1488260D03*
X1492984D03*
X1497708D03*
X1485897D03*
X1490622D03*
X1495346D03*
X1502433Y1542459D03*
X1507157D03*
X1511882D03*
X1500071D03*
X1504795D03*
X1509519D03*
X1502433Y1573477D03*
X1507157D03*
X1511882D03*
X1500071D03*
X1504795D03*
X1509519D03*
X1526055Y1542459D03*
X1516606D03*
X1521330D03*
X1514244D03*
X1518968D03*
X1523693D03*
X1526055Y1573477D03*
X1516606D03*
X1521330D03*
X1514244D03*
X1518968D03*
X1523693D03*
X1535504Y1542459D03*
X1537866D03*
X1530779D03*
X1533142D03*
X1528417D03*
X1533142Y1573477D03*
X1535504D03*
X1537866D03*
X1530779D03*
X1528417D03*
X1580889Y1542459D03*
X1583251D03*
X1585613D03*
X1580889Y1573477D03*
X1583251D03*
X1585613D03*
X1587975Y1542459D03*
X1592700D03*
X1597424D03*
X1602148D03*
X1590337D03*
X1595062D03*
X1599786D03*
X1587975Y1573477D03*
X1592700D03*
X1597424D03*
X1602148D03*
X1590337D03*
X1595062D03*
X1599786D03*
X1606873Y1542459D03*
X1611597D03*
X1616322D03*
X1613959D03*
X1604511D03*
X1609235D03*
X1606873Y1573477D03*
X1611597D03*
X1616322D03*
X1613959D03*
X1604511D03*
X1609235D03*
X1621046Y1542459D03*
X1625770D03*
X1630495D03*
X1618684D03*
X1623408D03*
X1628133D03*
X1621046Y1573477D03*
X1625770D03*
X1630495D03*
X1618684D03*
X1623408D03*
X1628133D03*
X1635219Y1542459D03*
X1639944D03*
X1644668D03*
X1632857D03*
X1637581D03*
X1642306D03*
X1647030D03*
X1635219Y1573477D03*
X1639944D03*
X1644668D03*
X1632857D03*
X1637581D03*
X1642306D03*
X1647030D03*
X1654117Y1542459D03*
X1658841D03*
X1649392D03*
X1661204D03*
X1651755D03*
X1656479D03*
X1661204Y1573477D03*
X1654117D03*
X1658841D03*
X1649392D03*
X1651755D03*
X1656479D03*
X1663566Y1542459D03*
X1665928D03*
X1663566Y1573477D03*
X1665928D03*
G54D111*
X215312Y1577778D03*
X240508D03*
X252717Y1577830D03*
X277913D03*
X516830D03*
X542026D03*
X1222952Y1610648D03*
X1248148D03*
X1260530Y1610830D03*
X1285726D03*
X1524704D03*
X1549900D03*
G54D120*
X270291Y589457D03*
G54D130*
X280810Y1545361D03*
X295180D03*
X416921D03*
X431291D03*
X544983D03*
X559353D03*
X714349Y1423623D03*
X728719D03*
X880297Y1068533D03*
X894667D03*
X971040Y1067984D03*
X985410D03*
X1288683Y1578361D03*
X1303053D03*
X1424795D03*
X1439165D03*
X1552857D03*
X1567227D03*
X1721146Y1419712D03*
X1735516D03*
G54D220*
X746517Y126419D03*
X757935D03*
G54D202*
X641437Y1692156D03*
X643997D03*
X646556D03*
X638878D03*
Y1709734D03*
X641437D03*
X643997D03*
X646556D03*
G54D112*
X242215Y144320D03*
Y146879D03*
Y149438D03*
X242255Y155044D03*
Y157603D03*
Y160162D03*
X249695Y149438D03*
Y146879D03*
Y144320D03*
X249735Y160162D03*
Y157603D03*
Y155044D03*
X449760Y1632441D03*
Y1635000D03*
Y1637559D03*
X457240D03*
Y1635000D03*
Y1632441D03*
X573388Y415846D03*
Y413287D03*
Y410728D03*
X565908D03*
Y413287D03*
Y415846D03*
Y421390D03*
Y423949D03*
Y426508D03*
X573388D03*
Y423949D03*
Y421390D03*
X624760Y416441D03*
Y419000D03*
X632240D03*
Y416441D03*
X624760Y421559D03*
X632240D03*
X643785Y299730D03*
Y297171D03*
X636305D03*
Y299730D03*
X643785Y302289D03*
X636305D03*
X646984Y507479D03*
X639504D03*
X646984Y512597D03*
Y510038D03*
X639504D03*
Y512597D03*
X657173Y1727718D03*
Y1730277D03*
Y1717056D03*
Y1722174D03*
Y1719615D03*
Y1732836D03*
X664653Y1727718D03*
Y1730277D03*
Y1717056D03*
Y1719615D03*
Y1722174D03*
Y1732836D03*
X689781Y1640773D03*
Y1643332D03*
Y1645891D03*
X697261Y1640773D03*
Y1645891D03*
Y1643332D03*
X761245Y167518D03*
Y170077D03*
Y172636D03*
X768725D03*
Y170077D03*
Y167518D03*
X1005169Y268884D03*
X997689D03*
X1005169Y263340D03*
Y260781D03*
Y258222D03*
X997689D03*
Y260781D03*
Y263340D03*
X1005169Y274002D03*
Y271443D03*
X997689D03*
Y274002D03*
X1107021Y1718991D03*
Y1724109D03*
Y1721550D03*
X1114501Y1718991D03*
Y1721550D03*
Y1724109D03*
X1194267Y1712261D03*
Y1709702D03*
Y1707143D03*
X1194314Y1726261D03*
Y1723702D03*
Y1721143D03*
X1201747Y1712261D03*
Y1707143D03*
Y1709702D03*
X1201794Y1726261D03*
Y1721143D03*
Y1723702D03*
X1301705Y77748D03*
Y80307D03*
Y82866D03*
X1309185D03*
Y80307D03*
Y77748D03*
X1425569Y1596545D03*
X1433049D03*
X1425569Y1599104D03*
Y1601663D03*
X1433049D03*
Y1599104D03*
X1582927Y536344D03*
Y533785D03*
Y531226D03*
X1590407Y536344D03*
Y531226D03*
Y533785D03*
X1670500Y1714318D03*
Y1711759D03*
X1663020D03*
Y1714318D03*
X1670500Y1729468D03*
Y1726909D03*
X1663020D03*
Y1729468D03*
X1670500Y1716877D03*
X1663020D03*
X1670500Y1732027D03*
X1663020D03*
X1705500Y1714318D03*
Y1711759D03*
X1698020D03*
Y1714318D03*
X1705500Y1716877D03*
X1698020D03*
X1737140Y1708265D03*
Y1710824D03*
Y1713383D03*
Y1723415D03*
Y1725974D03*
Y1728533D03*
X1744620Y1713383D03*
Y1710824D03*
Y1708265D03*
Y1728533D03*
Y1725974D03*
Y1723415D03*
X1810045Y164393D03*
Y161834D03*
Y159275D03*
X1802565D03*
Y161834D03*
Y164393D03*
X1827636Y159275D03*
Y161834D03*
Y164393D03*
X1835116D03*
Y161834D03*
Y159275D03*
G54D211*
X723082Y651187D03*
Y646147D03*
X717176Y651187D03*
Y646147D03*
X1148190Y1558549D03*
Y1553509D03*
X1142284Y1558549D03*
Y1553509D03*
X1470006Y1676881D03*
Y1681921D03*
X1475912Y1676881D03*
Y1681921D03*
G54D121*
X275558Y589395D03*
G54D103*
X179457Y1515083D03*
Y1517445D03*
Y1519807D03*
Y1522169D03*
Y1526894D03*
Y1531618D03*
Y1533980D03*
Y1524532D03*
Y1529256D03*
Y1536343D03*
X265173Y1517445D03*
Y1515083D03*
Y1519807D03*
Y1522169D03*
Y1526894D03*
Y1529256D03*
Y1531618D03*
Y1533980D03*
Y1536343D03*
Y1524532D03*
X307519Y1515083D03*
Y1517445D03*
Y1519807D03*
Y1522169D03*
Y1526894D03*
Y1531618D03*
Y1533980D03*
Y1524532D03*
Y1529256D03*
Y1536343D03*
X393235Y1517445D03*
Y1515083D03*
Y1519807D03*
Y1522169D03*
Y1526894D03*
Y1529256D03*
Y1531618D03*
Y1533980D03*
Y1536343D03*
Y1524532D03*
X443630Y1515083D03*
Y1517445D03*
Y1519807D03*
Y1522169D03*
Y1526894D03*
Y1531618D03*
Y1533980D03*
Y1524532D03*
Y1529256D03*
Y1536343D03*
X529346Y1517445D03*
Y1515083D03*
Y1519807D03*
Y1522169D03*
Y1526894D03*
Y1529256D03*
Y1531618D03*
Y1533980D03*
Y1536343D03*
Y1524532D03*
X571692Y1515083D03*
Y1517445D03*
Y1519807D03*
Y1522169D03*
Y1526894D03*
Y1531618D03*
Y1533980D03*
Y1524532D03*
Y1529256D03*
Y1536343D03*
X657408Y1517445D03*
Y1515083D03*
Y1519807D03*
Y1522169D03*
Y1526894D03*
Y1529256D03*
Y1531618D03*
Y1533980D03*
Y1536343D03*
Y1524532D03*
X1187330Y1548083D03*
Y1550445D03*
Y1559894D03*
Y1564618D03*
Y1552807D03*
Y1555169D03*
Y1566980D03*
Y1557532D03*
Y1562256D03*
Y1569343D03*
X1273046Y1550445D03*
Y1548083D03*
Y1552807D03*
Y1555169D03*
Y1559894D03*
Y1562256D03*
Y1564618D03*
Y1566980D03*
Y1557532D03*
Y1569343D03*
X1315392Y1548083D03*
Y1550445D03*
Y1559894D03*
Y1564618D03*
Y1552807D03*
Y1555169D03*
Y1566980D03*
Y1557532D03*
Y1562256D03*
Y1569343D03*
X1401108Y1550445D03*
Y1548083D03*
Y1552807D03*
Y1555169D03*
Y1559894D03*
Y1562256D03*
Y1564618D03*
Y1566980D03*
Y1557532D03*
Y1569343D03*
X1451504Y1548083D03*
Y1550445D03*
Y1559894D03*
Y1564618D03*
Y1552807D03*
Y1555169D03*
Y1566980D03*
Y1557532D03*
Y1562256D03*
Y1569343D03*
X1537220Y1550445D03*
Y1548083D03*
Y1552807D03*
Y1555169D03*
Y1559894D03*
Y1562256D03*
Y1564618D03*
Y1566980D03*
Y1557532D03*
Y1569343D03*
X1579566Y1548083D03*
Y1550445D03*
Y1559894D03*
Y1564618D03*
Y1552807D03*
Y1555169D03*
Y1566980D03*
Y1557532D03*
Y1562256D03*
Y1569343D03*
X1665282Y1550445D03*
Y1548083D03*
Y1552807D03*
Y1555169D03*
Y1559894D03*
Y1562256D03*
Y1564618D03*
Y1566980D03*
Y1557532D03*
Y1569343D03*
G54D10*
X8879Y180928D03*
X8013Y219222D03*
X6109Y1673058D03*
X18691Y180321D03*
X14517Y223688D03*
X34180Y293407D03*
X38944Y303000D03*
X39600Y378562D03*
X38800Y406562D03*
X39163Y519914D03*
X40373Y762118D03*
Y768332D03*
X55301Y53544D03*
X44700Y375262D03*
X50200D03*
X53500Y371362D03*
X40800Y400962D03*
X43814Y408139D03*
X47902Y512585D03*
X53658Y512639D03*
X41010Y534105D03*
X49039Y542027D03*
X54399D03*
X42150Y1546791D03*
X45120Y1603396D03*
X45833Y1626496D03*
X50927Y1663587D03*
Y1668587D03*
X49069Y1678149D03*
X59406Y57055D03*
X64000Y306000D03*
X65710Y376042D03*
X63350Y371362D03*
X57342Y375262D03*
X58254Y514975D03*
X59849Y541987D03*
X66250Y1412899D03*
X68392Y1432013D03*
X59039Y1549644D03*
X66854Y1597165D03*
X61133Y1631796D03*
X56133Y1631696D03*
X62152Y1653448D03*
X68399Y1653382D03*
X56821Y1653527D03*
X64462Y1678404D03*
X56694Y1677916D03*
X70237Y1678363D03*
X80991Y151189D03*
X84009Y146557D03*
X80979Y156192D03*
X80965Y161194D03*
X84377Y166361D03*
X71136Y390398D03*
X76600Y386364D03*
X70500Y381562D03*
X71480Y399442D03*
X76200Y395865D03*
X78760Y1312186D03*
Y1307106D03*
X70460Y1600665D03*
X74233Y1614396D03*
Y1607847D03*
X73399Y1653408D03*
X79117Y1666864D03*
X82630Y1678315D03*
X76468Y1678409D03*
X89539Y-76554D03*
X89009Y146231D03*
X94010Y146250D03*
X98892Y147345D03*
X94291Y167275D03*
X89290Y167307D03*
X93193Y1377757D03*
X92988Y1560481D03*
X100939Y-76554D03*
X112339D03*
X100818Y165506D03*
X113500Y1398600D03*
X102376Y1409377D03*
X102548Y1415954D03*
X107202Y1558112D03*
X123739Y-76554D03*
X120016Y289822D03*
X115016D03*
X120016Y310256D03*
X115016D03*
X124700Y1401000D03*
X120700Y1408100D03*
X118658Y1455464D03*
X121500Y1467400D03*
X120353Y1655843D03*
X119927Y1669843D03*
Y1674843D03*
X123353Y1686843D03*
X135139Y-76554D03*
X136617Y521997D03*
Y526997D03*
X143649Y672383D03*
X143949Y677610D03*
X141514Y1436500D03*
X132353Y1655769D03*
X144253Y1655843D03*
X132427Y1686343D03*
X137427D03*
X157939Y-76554D03*
X146539D03*
X157923Y1520968D03*
X152339Y1655756D03*
X144985Y1671863D03*
X151353Y1686843D03*
X169339Y-76554D03*
X162112Y1450019D03*
X166180Y1514420D03*
X161162Y1514314D03*
X167900Y1540000D03*
Y1535000D03*
Y1530000D03*
X180739Y-76554D03*
X186421Y671555D03*
X184700Y677660D03*
X185124Y1701851D03*
X185084Y1691988D03*
X192139Y-76554D03*
X203539D03*
X195979Y106017D03*
X192845Y136262D03*
X195979Y125562D03*
X204088Y138912D03*
X197375Y152500D03*
X197575Y160432D03*
X198698Y1662215D03*
X214939Y-76554D03*
X208179Y106017D03*
X214900Y120502D03*
X218402Y148760D03*
X211862Y1701100D03*
X233335Y57341D03*
X233785Y208935D03*
X227157Y715915D03*
X245330Y56939D03*
X239734Y57435D03*
X237929Y107838D03*
X242196Y119305D03*
X243813Y132383D03*
X236916Y146832D03*
X237396Y163965D03*
X248625Y762182D03*
X243625D03*
X249909Y58971D03*
X253086Y87365D03*
X254936Y146882D03*
X254821Y151940D03*
X259496Y162665D03*
X256090Y206540D03*
X263271Y771988D03*
X259490Y1565110D03*
X258560Y1558660D03*
X274996Y153865D03*
X275049Y148706D03*
X276996Y143965D03*
X274996Y159206D03*
X278697Y165096D03*
X265075Y213077D03*
X264818Y227950D03*
X276704Y1526953D03*
X264617Y1561520D03*
X287196Y143965D03*
X292496Y144016D03*
X281996Y143965D03*
X284990Y168020D03*
X290840Y170080D03*
X283811Y215870D03*
X286546Y222118D03*
X287000Y243069D03*
X292740Y242691D03*
X286872Y1508981D03*
X289460Y1520200D03*
X289224Y1514314D03*
X281704Y1526953D03*
X297696Y144165D03*
X294224Y1514314D03*
X308222Y1561079D03*
X319641Y274000D03*
X314271Y593038D03*
X314771Y1555834D03*
X312715Y1575985D03*
X329221Y164920D03*
X333031Y255324D03*
X337750Y584750D03*
X339811Y131052D03*
X341895Y233980D03*
X342192Y270260D03*
X351157Y550415D03*
Y590415D03*
X365400Y146910D03*
X365836Y163265D03*
X365162Y243366D03*
X357391Y286874D03*
X357341Y281424D03*
X366000Y307500D03*
X365071Y551038D03*
X362200Y566750D03*
X364047Y556773D03*
X360261Y561044D03*
X379090Y157936D03*
X376091Y287874D03*
Y280274D03*
Y295474D03*
X382184Y476726D03*
Y496726D03*
X371962Y524954D03*
X380771Y542138D03*
X379689Y586040D03*
X368798Y587938D03*
X376197Y1576200D03*
X375513Y1587172D03*
X387894Y135157D03*
X397090Y151741D03*
X389000Y303760D03*
X394184Y476726D03*
X397184Y496726D03*
X392184D03*
X388985Y554870D03*
X395171Y559463D03*
X397101Y566188D03*
X395157Y573815D03*
X393604Y579473D03*
X387103Y584506D03*
X391175Y1565695D03*
X393261Y1560775D03*
X386822Y1556550D03*
X389128Y1576969D03*
X391604Y1587172D03*
X387324Y1670120D03*
X392324D03*
X397324D03*
X403881Y133980D03*
X406000Y139483D03*
X398599Y209695D03*
X407299Y201500D03*
X402184Y476844D03*
Y496726D03*
X406512Y534213D03*
X399657Y546915D03*
X409766Y1526953D03*
X404766D03*
X404775Y1535976D03*
Y1540976D03*
X407611Y1599022D03*
X401547Y1603022D03*
X407676Y1626475D03*
X412342Y1628467D03*
X406441Y1657000D03*
X427549Y60016D03*
X414400Y110770D03*
X413416Y153150D03*
X420527Y144234D03*
X427299Y199500D03*
X419299Y201000D03*
X422302Y214926D03*
X420000Y219940D03*
X423583Y245868D03*
X424220Y253768D03*
Y263768D03*
Y258768D03*
X415984Y476767D03*
Y496649D03*
X414934Y1508981D03*
X419934D03*
X425571Y1520200D03*
X424775Y1513907D03*
X422437Y1526983D03*
X425000Y1626900D03*
X413299Y1633417D03*
X417000Y1661000D03*
X440186Y93386D03*
X432200Y101800D03*
X428085Y98885D03*
X442221Y100933D03*
X436482Y98172D03*
X435383Y149854D03*
X441240Y149323D03*
X429200Y155890D03*
X435299Y201745D03*
X429784Y476690D03*
Y496572D03*
X435580Y1279986D03*
X430335Y1514314D03*
X431682Y1601671D03*
X433795Y1606554D03*
X436500Y1618700D03*
X428500Y1630500D03*
X434280Y1644807D03*
X446797Y148500D03*
X454997Y155750D03*
X443299Y201745D03*
X451224Y201820D03*
X447691Y489766D03*
X453470Y1555409D03*
X446959Y1576531D03*
X446807Y1585178D03*
X443594Y1640854D03*
X464249Y60016D03*
X466449Y55016D03*
X465849Y65016D03*
X465687Y105944D03*
X469874Y100869D03*
X466396Y95901D03*
X466600Y118000D03*
X468348Y112011D03*
X466600Y133000D03*
Y138000D03*
X466680Y124253D03*
X462637Y146170D03*
X468997Y155750D03*
X461997D03*
X459174Y209620D03*
Y204620D03*
X468540Y293270D03*
X461535Y293862D03*
X459673Y1572604D03*
X463581Y1584220D03*
X465000Y1644000D03*
X464500Y1679774D03*
X465000Y1705500D03*
X464500Y1711500D03*
X485260Y168390D03*
X478997Y155750D03*
X473997D03*
X485997D03*
X475578Y214985D03*
X477856Y1682741D03*
X479000Y1706500D03*
X502204Y179084D03*
X488800Y307380D03*
X515539Y77767D03*
X510477D03*
X507204Y179084D03*
X512204D03*
X510786Y194424D03*
X506462Y190316D03*
X510692Y248651D03*
X513193Y436878D03*
X511601Y445740D03*
X523150Y77767D03*
X528212D03*
X523504Y214072D03*
X528450Y1564400D03*
X523250Y1564540D03*
X522933Y1556550D03*
X544600Y131060D03*
X546461Y156667D03*
X533850Y169018D03*
X545396Y184681D03*
X536821Y190256D03*
Y195256D03*
X537402Y430775D03*
X540751Y603398D03*
X545877Y1526953D03*
X540877D03*
X554196Y179881D03*
X555755Y302485D03*
X548945Y302782D03*
X556248Y389786D03*
Y394786D03*
X561048Y412774D03*
X553715Y408628D03*
X556981Y451000D03*
X553058Y472332D03*
X555897Y657605D03*
Y662605D03*
X555091Y1265586D03*
X547645Y1509085D03*
X553633Y1520200D03*
X558397Y1514314D03*
X553397D03*
X572232Y77862D03*
X562784Y78299D03*
X572221Y83562D03*
X567521Y87362D03*
X567508Y81049D03*
X562821Y84262D03*
X575800Y316330D03*
X571925Y458443D03*
X570216Y759762D03*
X575216D03*
X570216Y772262D03*
X575216D03*
X572395Y1561079D03*
X572243Y1569327D03*
X586394Y78494D03*
X579060Y77970D03*
X579885Y371627D03*
X585585Y382427D03*
Y395177D03*
X578248Y415846D03*
X590998Y411846D03*
X578248Y423949D03*
X578267Y431976D03*
X584165Y479658D03*
X578944Y1555834D03*
X602287Y85071D03*
X595394Y144640D03*
X599030Y225861D03*
Y219777D03*
X605650Y214136D03*
X599974Y214461D03*
X594105Y234277D03*
X604974Y235511D03*
X600494Y232821D03*
X592248Y389786D03*
X598185Y404287D03*
X594251Y425240D03*
X600000Y446000D03*
X599623Y458376D03*
X599452Y470130D03*
X595253Y1266668D03*
X618039Y84584D03*
X616274Y187961D03*
X621274D03*
X616274Y197961D03*
X621274D03*
X616274Y192961D03*
X621274D03*
Y207961D03*
X616274Y202961D03*
X621274D03*
X616274Y212961D03*
X611074Y214061D03*
X620735Y215169D03*
X610304Y235381D03*
X615885Y371627D03*
X621585Y382427D03*
Y395177D03*
X617000Y435632D03*
X615425Y422465D03*
X634914Y121280D03*
X626705Y285305D03*
X631505Y299730D03*
Y294730D03*
X624609Y468828D03*
X622434Y1362366D03*
X628194Y1395604D03*
X634516Y1686547D03*
X633333Y1692156D03*
X642541Y78436D03*
X646388Y89882D03*
X651391Y138972D03*
Y133972D03*
X642394Y144262D03*
X651391Y143972D03*
Y148972D03*
X648585Y302289D03*
X649888Y395717D03*
X651132Y436517D03*
X650875Y449862D03*
X650800Y456240D03*
X651016Y469863D03*
X637522Y501978D03*
X643313Y518746D03*
X638967Y671774D03*
X638847Y1389887D03*
X650995Y1556550D03*
X657166Y79131D03*
X654391Y152972D03*
X654471Y163972D03*
X654371Y158572D03*
X654157Y169197D03*
X654326Y174437D03*
X654311Y186192D03*
X656318Y254591D03*
X656128Y263486D03*
X659326Y363566D03*
X659575Y478662D03*
X651908Y507929D03*
Y514092D03*
X666100Y1308048D03*
Y1312502D03*
X663224Y1387870D03*
X663431Y1645780D03*
X659837Y1698400D03*
X660654Y1704783D03*
X675242Y111960D03*
X673861Y121202D03*
X678072Y128093D03*
X680200Y417110D03*
Y425280D03*
X680266Y434313D03*
X680250Y452074D03*
Y459812D03*
Y467712D03*
X668660Y486095D03*
X681227Y488419D03*
X668946Y1508979D03*
X679792Y1536622D03*
X667971Y1685417D03*
X669513Y1732836D03*
X669555Y1723539D03*
X686211Y91492D03*
X695040Y401079D03*
X694600Y406060D03*
X683500Y421080D03*
X683400Y430360D03*
Y445830D03*
X683300Y438320D03*
X683450Y455932D03*
Y463812D03*
X694549Y499912D03*
X688500Y535514D03*
X691682Y586081D03*
X686211Y1534158D03*
X696554Y125044D03*
X710451Y152512D03*
X710799Y163012D03*
X700000Y386790D03*
X704000Y406000D03*
X699945Y402495D03*
X708218Y401233D03*
X709570Y504315D03*
X697359Y504128D03*
X700278Y499958D03*
X706041Y500099D03*
X700461Y517157D03*
X704710Y668000D03*
X698391Y1385228D03*
X708994Y1568507D03*
X710420Y1585173D03*
X710550Y1576523D03*
X709836Y1594721D03*
X709382Y1601210D03*
X697950Y1634097D03*
X707997Y1630768D03*
X702160Y1647367D03*
X709523Y1674429D03*
X704019Y1671507D03*
X704659Y1678474D03*
X719640Y386862D03*
X711500Y405673D03*
X723500Y401062D03*
X715500Y401378D03*
X719500Y406062D03*
X724500Y503014D03*
X712500Y500014D03*
X720500D03*
X716500Y503014D03*
X720400Y517440D03*
X718129Y656130D03*
X723166Y656225D03*
X715803Y670949D03*
X715152Y1634265D03*
X721898Y1636624D03*
X725371Y1673230D03*
X718891Y1672937D03*
X721408Y1677865D03*
X739500Y383500D03*
X733900Y405940D03*
X737425Y402000D03*
X736500Y500014D03*
X732500Y503014D03*
X728500Y500014D03*
X728938Y517520D03*
X741000Y518862D03*
X736339Y514603D03*
X731694Y662061D03*
X730782Y1555496D03*
X727755Y1636539D03*
X732260Y1633591D03*
X736485Y1636763D03*
X740723Y1633619D03*
X738526Y1674392D03*
X730592Y1672921D03*
X734017Y1676824D03*
X741850Y87100D03*
X753601Y143438D03*
X753501Y151312D03*
X755901Y170562D03*
X753500Y208000D03*
X746500Y207500D03*
X751000Y225000D03*
X754800Y379919D03*
X743500Y386962D03*
X745000Y400000D03*
X744000Y405970D03*
X750800Y405992D03*
X753700Y401179D03*
X752500Y500014D03*
X742144Y504935D03*
X744500Y500014D03*
X748500Y503014D03*
X747110Y1579863D03*
X747160Y1587773D03*
X744315Y1673134D03*
X745382Y1683663D03*
X764343Y162084D03*
X761000Y199000D03*
X763958Y272775D03*
X764767Y267322D03*
X763500Y386862D03*
X756300Y405840D03*
X762500Y401100D03*
X761600Y406060D03*
X766300Y404280D03*
X757500Y499980D03*
X765690D03*
X761500Y503014D03*
X764600Y517022D03*
X766566Y532172D03*
X770800Y535640D03*
X757770Y1636083D03*
X761510Y1656483D03*
X773901Y170064D03*
X783267Y267722D03*
Y282922D03*
Y275322D03*
X772513Y374490D03*
X783736Y441100D03*
X783241Y461515D03*
X777385Y466879D03*
X783796Y456205D03*
X783895Y470961D03*
X783759Y479344D03*
X777465Y483344D03*
X776400Y533300D03*
X778850Y1556133D03*
X771592Y1572717D03*
X771650Y1591733D03*
X794058Y301569D03*
X793221Y296062D03*
X793897Y309026D03*
X786624Y465585D03*
X800185Y453381D03*
X799150Y1575233D03*
X799775Y1591498D03*
Y1598719D03*
X799888Y1603833D03*
X814115Y120773D03*
X810811Y135132D03*
X810641Y128262D03*
X810481Y141762D03*
X803302Y265848D03*
X810139Y274098D03*
X805491Y373158D03*
X802175Y418362D03*
X813114Y443344D03*
X801552Y463318D03*
X811189Y524000D03*
X809216Y551473D03*
X814954Y565087D03*
X813400Y1575483D03*
X813571Y1597534D03*
X822531Y125698D03*
X828615D03*
X816232Y341584D03*
X818157Y381020D03*
X816747Y412367D03*
X816236Y439279D03*
X816109Y449802D03*
X816000Y463578D03*
X816170Y458524D03*
X816109Y471344D03*
X820500Y515323D03*
X817441Y533000D03*
X820850Y1556133D03*
X831540Y70643D03*
X834115Y135698D03*
X833615Y129198D03*
X839461Y146042D03*
X833321Y145912D03*
X831296Y171632D03*
X845221Y192862D03*
X839221D03*
X834921Y220303D03*
X838681Y224752D03*
X843511Y228962D03*
X839081Y233252D03*
X836181Y275686D03*
X843417Y384888D03*
X838500Y471000D03*
X835236Y483635D03*
X841854Y504972D03*
X836893Y537215D03*
X834750Y561347D03*
X841150Y1575233D03*
X841775Y1591574D03*
X841851Y1598753D03*
X841924Y1603879D03*
X852258Y54892D03*
X856630Y70793D03*
X846191Y145262D03*
X849321Y196532D03*
X853341Y199932D03*
X855401Y204772D03*
X859075Y387739D03*
X852000Y408000D03*
X848500Y461500D03*
X852240Y482500D03*
X849351Y499070D03*
X855400Y1575483D03*
X856015Y1596916D03*
X855745Y1615986D03*
X866452Y168862D03*
Y173862D03*
X869901Y209562D03*
X868520Y263654D03*
X871190Y391760D03*
X865366Y393710D03*
X864386Y417186D03*
X862987Y507305D03*
X868496Y776516D03*
X862850Y1556133D03*
X870453Y1616463D03*
X883150Y1575233D03*
X883869Y1591629D03*
X883831Y1598716D03*
X883905Y1603864D03*
X882535Y1616701D03*
X900456Y155618D03*
X895456D03*
X893701Y201799D03*
X899501Y201899D03*
X904850Y1556133D03*
X897381Y1574788D03*
X898065Y1596318D03*
X910258Y600751D03*
X910377Y606694D03*
X925068Y272340D03*
X925650Y1576233D03*
Y1586733D03*
X925726Y1592261D03*
X945263Y269781D03*
X938956Y585132D03*
X940856Y614150D03*
X939681Y628662D03*
X944265Y1285729D03*
X937755Y1594881D03*
X963500Y1275000D03*
X977071Y215709D03*
X981897Y198629D03*
X992830Y260781D03*
Y271443D03*
X992508Y295634D03*
X988646Y371434D03*
X986696Y428366D03*
X988242Y1273193D03*
X1008707Y230423D03*
X997461Y230019D03*
X1008108Y420886D03*
X999304Y1282574D03*
Y1289215D03*
X1014435Y160518D03*
X1021440Y226423D03*
X1010028Y263340D03*
Y274002D03*
X1010550Y298312D03*
X1010157Y288489D03*
X1019264Y493655D03*
X1022764Y489655D03*
X1019410Y485582D03*
X1018872Y549855D03*
X1029269Y378764D03*
X1033069Y382764D03*
X1029269Y386244D03*
X1033449Y424500D03*
X1039015Y444404D03*
X1034246Y553980D03*
X1038333Y551098D03*
X1038054Y544261D03*
X1050639Y1311149D03*
Y1307149D03*
X1058223Y464938D03*
X1060316Y460251D03*
X1058205Y471500D03*
X1062258Y467919D03*
X1060719Y516059D03*
X1066019Y1378597D03*
X1075600Y1533700D03*
X1088558Y377306D03*
X1088588Y382506D03*
X1090035Y388477D03*
X1088221Y394170D03*
X1107043Y447355D03*
X1109043Y452855D03*
X1107005Y481355D03*
X1107043Y468039D03*
X1111043Y471855D03*
X1107005Y475355D03*
X1111005Y478355D03*
X1107043Y489391D03*
X1111043Y485771D03*
X1103110Y1533520D03*
X1113167Y1554508D03*
X1105500Y1643500D03*
X1107766Y1635951D03*
X1111167Y1643333D03*
X1110936Y1654416D03*
X1109519Y1660925D03*
X1103489Y1711244D03*
X1128100Y376862D03*
X1127408Y386271D03*
X1126387Y615658D03*
X1123816Y1456373D03*
X1119131Y1534854D03*
X1117665Y1539877D03*
X1125156Y1573436D03*
X1120656D03*
X1115005Y1573346D03*
X1120152Y1597498D03*
X1125756D03*
X1115005Y1587936D03*
X1116481Y1661631D03*
X1120303Y1670114D03*
X1115450Y1685011D03*
X1119361Y1724109D03*
X1141901Y56691D03*
X1138710Y370496D03*
X1131400Y391562D03*
X1141267Y500296D03*
X1143095Y1459523D03*
X1137604Y1561627D03*
X1141916Y1573597D03*
X1132168Y1630557D03*
X1138456Y1632280D03*
X1142350Y1659564D03*
X1135398Y1663760D03*
X1148043Y456855D03*
X1152043Y453121D03*
X1148043Y462921D03*
X1152543Y459855D03*
Y465480D03*
X1148043Y468039D03*
X1152839Y482374D03*
X1151036Y501627D03*
X1155109Y1456295D03*
X1152549Y1562311D03*
X1148089Y1573555D03*
X1163431Y82818D03*
X1166691Y1555367D03*
X1169035Y1547314D03*
X1187374Y59122D03*
X1187214Y52572D03*
X1186734Y65122D03*
X1180777Y90385D03*
X1180280Y100793D03*
X1177336Y577407D03*
X1178536Y584307D03*
X1174053Y1547420D03*
X1175773Y1568000D03*
Y1563000D03*
Y1573000D03*
X1181660Y1690829D03*
X1195488Y83175D03*
X1197381Y133866D03*
X1196227Y432202D03*
Y448202D03*
Y440202D03*
X1195645Y601873D03*
Y605973D03*
X1196988Y1673050D03*
X1189407Y1707143D03*
X1189454Y1723702D03*
X1213107Y161551D03*
X1210607Y157051D03*
Y166051D03*
X1210707Y171051D03*
X1212888Y176470D03*
X1209059Y181187D03*
X1212182Y185187D03*
X1214094Y282948D03*
Y287948D03*
X1209937Y465376D03*
Y460376D03*
Y470376D03*
X1203272Y1399140D03*
X1204492Y1442500D03*
X1204664Y1447500D03*
X1213072Y1673059D03*
X1230693Y150239D03*
X1230094Y287948D03*
Y282948D03*
X1222094D03*
Y292066D03*
Y305216D03*
X1226094Y314216D03*
X1232154Y436875D03*
Y431875D03*
Y441875D03*
X1224200Y1393500D03*
X1221837Y1438800D03*
X1246715Y463158D03*
X1245187Y458182D03*
Y453182D03*
X1239800Y1389500D03*
X1233700Y1395600D03*
X1241613Y1414500D03*
X1239965Y1427544D03*
X1252693Y133549D03*
X1249693Y129239D03*
Y145053D03*
X1253107Y167276D03*
X1249107Y163551D03*
X1253107Y180551D03*
X1249107Y177051D03*
Y170551D03*
X1253107Y174051D03*
X1249107Y184051D03*
X1262094Y282948D03*
X1254094D03*
X1262094Y287948D03*
X1258500Y392500D03*
X1259075Y769000D03*
X1275964Y95379D03*
X1267611Y150030D03*
X1270094Y282948D03*
Y292066D03*
X1274000Y385000D03*
X1277457Y396165D03*
X1269258Y399125D03*
X1272457Y394559D03*
X1269229Y407865D03*
X1277738Y417241D03*
X1272825Y416295D03*
X1277677Y770388D03*
X1264895Y769106D03*
X1267530Y1598620D03*
X1272490Y1594520D03*
X1265783Y1590340D03*
X1283465Y86960D03*
X1284593Y122259D03*
X1287693Y128239D03*
X1290193Y132739D03*
X1287693Y137239D03*
Y146239D03*
X1290193Y141739D03*
X1280901Y168401D03*
X1281128Y161816D03*
X1280791Y173783D03*
X1281570Y184513D03*
X1278094Y282948D03*
X1286094D03*
Y292066D03*
X1282458Y396184D03*
X1287340Y397279D03*
X1280886Y421145D03*
X1281677Y756588D03*
X1290677Y771388D03*
X1289577Y1559953D03*
X1284577D03*
X1296200Y56536D03*
X1301705Y72342D03*
X1294094Y287948D03*
Y282948D03*
X1302094D03*
Y292066D03*
X1296677Y770888D03*
X1297333Y1553200D03*
X1302097Y1547314D03*
X1294745Y1541981D03*
X1297097Y1547314D03*
X1308110Y56536D03*
X1320020Y56604D03*
X1313615Y72342D03*
X1310094Y287948D03*
Y282948D03*
X1318094D03*
X1316095Y1594079D03*
X1315943Y1600322D03*
X1331930Y56570D03*
X1329435Y70452D03*
X1333399Y87709D03*
X1334094Y287948D03*
X1326094Y282948D03*
X1334094D03*
X1326094Y292066D03*
X1337257Y678765D03*
X1322644Y1588834D03*
X1343840Y56536D03*
X1337435Y70452D03*
X1343877D03*
X1341399Y87709D03*
X1348199D03*
X1350094Y287948D03*
X1342094Y282948D03*
X1350094D03*
X1342094Y292066D03*
X1355750Y56536D03*
X1353309Y87675D03*
X1360109D03*
X1356199Y100425D03*
X1366094Y287948D03*
X1358094Y282948D03*
X1366094D03*
X1358094Y292066D03*
X1367950Y56536D03*
X1378945Y68142D03*
X1372655Y236594D03*
Y241594D03*
Y246594D03*
Y251594D03*
X1379261Y1716438D03*
X1394695Y1589550D03*
X1383800Y1695238D03*
X1392420Y1708038D03*
X1410961Y1280751D03*
X1399009Y1598883D03*
X1401552Y1594362D03*
X1398018Y1605304D03*
X1410622Y1617000D03*
X1399940Y1646967D03*
X1424271Y112849D03*
X1422807Y1541981D03*
X1417639Y1559953D03*
X1412639D03*
X1412648Y1568976D03*
Y1573976D03*
X1416000Y1617000D03*
X1418740Y1638167D03*
X1439951Y62174D03*
X1431816Y104219D03*
X1438549Y124818D03*
X1433549D03*
X1435645Y166180D03*
X1427119Y244450D03*
X1440119D03*
X1438209Y1547314D03*
X1433209D03*
X1427807Y1541981D03*
X1429800Y1557762D03*
X1433184Y1628126D03*
X1439500Y1633500D03*
X1450723Y103655D03*
X1443549Y124818D03*
X1450915Y125038D03*
X1449769Y163842D03*
X1441898Y576755D03*
X1449956Y1267923D03*
X1455314Y1267286D03*
X1452207Y1594079D03*
X1454274Y1600121D03*
X1451500Y1633500D03*
X1445500D03*
X1445079Y1677089D03*
X1451000Y1677000D03*
X1445754Y1689990D03*
X1460820Y52933D03*
X1458756Y1588834D03*
X1463231Y1676766D03*
X1472647Y539478D03*
X1473444Y555208D03*
X1478147Y547728D03*
X1484347Y580388D03*
X1481612Y1675112D03*
X1474146Y1687854D03*
X1492789Y576602D03*
X1509479Y130822D03*
X1502085Y545432D03*
X1507109Y550059D03*
X1502757Y570977D03*
X1505477Y1265844D03*
X1513046Y1286424D03*
X1530884Y62569D03*
X1526894Y209250D03*
Y221250D03*
Y214250D03*
Y249250D03*
Y244250D03*
X1519457Y556338D03*
X1522875Y1268496D03*
X1529045Y1280128D03*
X1521346Y1281136D03*
X1518081Y1296288D03*
X1530807Y1589550D03*
X1533815Y57185D03*
X1545747Y301400D03*
X1545556Y292816D03*
X1545187Y306854D03*
X1542842Y1265928D03*
X1532335Y1265721D03*
X1537295Y1274681D03*
X1531750Y1598190D03*
X1536664Y1594520D03*
X1553772Y289856D03*
X1558773Y289875D03*
X1559054Y310900D03*
X1553653Y310980D03*
X1548197Y311209D03*
X1558924Y1541975D03*
X1553751Y1559953D03*
X1548751D03*
X1563655Y290970D03*
X1561507Y1553200D03*
X1566271Y1547314D03*
X1561271D03*
X1582928Y214250D03*
Y234250D03*
Y239250D03*
Y229250D03*
Y244250D03*
X1577934Y531226D03*
X1586818Y1588834D03*
X1580269Y1594079D03*
X1580117Y1600322D03*
X1605241Y541123D03*
X1617534Y289742D03*
X1627800Y519254D03*
X1629833Y1312091D03*
X1634065Y1415729D03*
X1646010Y423702D03*
X1647377Y1385408D03*
X1646533Y1445767D03*
X1662900Y141762D03*
Y151762D03*
Y146762D03*
Y161762D03*
X1654610Y405002D03*
X1661610Y405202D03*
X1653610Y423702D03*
X1661210D03*
X1650757Y626918D03*
X1658869Y1589550D03*
X1680020Y420132D03*
X1674640Y1445639D03*
X1676819Y1541979D03*
X1665726Y1594362D03*
X1679816Y1674318D03*
X1676397Y1684818D03*
X1677930Y1679305D03*
X1676397Y1689818D03*
Y1699818D03*
Y1694818D03*
X1675360Y1716877D03*
Y1732027D03*
X1687537Y1567788D03*
X1694075Y1567158D03*
X1686064Y1573892D03*
X1684816Y1674318D03*
X1689816D03*
X1706066Y57098D03*
X1700617Y1682744D03*
Y1687744D03*
Y1692744D03*
X1722566Y57098D03*
X1717566D03*
X1712566D03*
X1717808Y108959D03*
X1716876Y120278D03*
X1721384Y135373D03*
X1717100Y377962D03*
X1718465Y660982D03*
X1718576Y666238D03*
X1718819Y1400561D03*
X1710360Y1716877D03*
X1729609Y90014D03*
X1731470Y358022D03*
X1738480Y358082D03*
X1735870Y387082D03*
X1728860Y387032D03*
X1730202Y1579277D03*
X1734589Y1666203D03*
X1735463Y1684165D03*
X1734863Y1676514D03*
X1741852Y123774D03*
X1745490Y357002D03*
X1746120Y368132D03*
X1745910Y363112D03*
Y373522D03*
X1742770Y387112D03*
X1747963Y1652565D03*
X1752963Y1652665D03*
X1740463Y1684165D03*
X1745463D03*
X1749480Y1728533D03*
X1756598Y677503D03*
X1762812D03*
X1763263Y1657865D03*
X1763163Y1679965D03*
X1775558Y1604620D03*
X1797692Y146285D03*
X1797765Y151834D03*
Y156834D03*
Y161834D03*
X1785051Y177578D03*
X1795346Y372732D03*
X1793479Y1598723D03*
X1785221Y1605473D03*
X1800212Y390411D03*
X1810924Y427432D03*
X1800979Y1583378D03*
X1815315Y145716D03*
X1814905Y156797D03*
Y166947D03*
X1818274Y366053D03*
Y385293D03*
X1839916Y161834D03*
G54D20*
X18848Y516951D03*
X33001Y401000D03*
X48678Y1519335D03*
X38149Y1594396D03*
Y1607896D03*
Y1598896D03*
Y1603396D03*
Y1612896D03*
Y1617396D03*
X44443Y1668587D03*
Y1663587D03*
X52143Y1681489D03*
X45143Y1681645D03*
X66741Y268223D03*
X57123Y423746D03*
X67149Y1630396D03*
X59143Y1682016D03*
X74267Y145191D03*
X74270Y149191D03*
Y153191D03*
X81890Y382219D03*
Y391391D03*
Y395865D03*
X73516Y1434000D03*
X79149Y1611896D03*
Y1625396D03*
Y1620896D03*
Y1616396D03*
X70683Y1634905D03*
X89017Y140950D03*
X96574Y1353216D03*
X87016Y1417000D03*
Y1412500D03*
Y1408000D03*
Y1421500D03*
X96016Y1426000D03*
Y1430500D03*
Y1440000D03*
Y1435500D03*
X87016D03*
X84421Y1519335D03*
X85712Y1549369D03*
X83212Y1544869D03*
X92283Y1716241D03*
X85436Y1706511D03*
X85273Y1716331D03*
X104637Y1554069D03*
X104002Y1671361D03*
Y1667361D03*
Y1679564D03*
Y1675564D03*
X107516Y1712450D03*
X123369Y1661087D03*
X141508Y521997D03*
Y530997D03*
Y534997D03*
X129174Y1353216D03*
X141016Y1417500D03*
X136936Y1701011D03*
X136834Y1705166D03*
X132783Y1718241D03*
X139783Y1726241D03*
Y1722241D03*
X151716Y438810D03*
X149763Y668361D03*
X145016Y1421500D03*
Y1425500D03*
X155831Y1726500D03*
X168366Y395040D03*
X166382Y684799D03*
Y680799D03*
X161874Y1353216D03*
X172016Y1711000D03*
Y1725000D03*
X174616Y416600D03*
X178496Y438270D03*
X176516Y672500D03*
Y676500D03*
X192936Y140962D03*
X195652Y165325D03*
X194774Y1353216D03*
X199016Y1707000D03*
X197795Y1723000D03*
X222368Y144710D03*
X230536Y159071D03*
X227574Y1353216D03*
X242236Y75862D03*
X234216Y142062D03*
X232759Y715823D03*
X255916Y58400D03*
Y54400D03*
X254816Y73400D03*
X255916Y62400D03*
X257813Y87543D03*
X247313Y115743D03*
X260859Y583999D03*
X261174Y1307070D03*
X275472Y78461D03*
X267069Y151203D03*
Y147203D03*
X267119Y137302D03*
X270016Y211000D03*
X262016Y217500D03*
X278972Y74536D03*
X283816Y136962D03*
X277016Y215000D03*
X283807Y577698D03*
X280657Y574022D03*
X276942Y570398D03*
X283807Y581298D03*
X284483Y1342705D03*
X298182Y67128D03*
X302173Y91767D03*
X295943Y85983D03*
Y82483D03*
X294070Y1307042D03*
X317115Y95852D03*
X317119Y99837D03*
X314355Y227851D03*
Y231851D03*
X310516Y241000D03*
X309016Y263000D03*
X326162Y147120D03*
Y152120D03*
Y156120D03*
Y160120D03*
X326974Y1306985D03*
X343186Y229180D03*
X345673Y586415D03*
X338755Y702203D03*
X352449Y219343D03*
X362924Y294030D03*
X353673Y582415D03*
Y578415D03*
X356073Y590415D03*
Y586415D03*
X359774Y1307185D03*
X376011Y149077D03*
X370979Y163173D03*
X374041Y235455D03*
X374071Y239615D03*
X371815Y701935D03*
X381104Y287370D03*
X387673Y565915D03*
X387473Y571115D03*
X392356Y1326516D03*
X394121Y1611022D03*
Y1607022D03*
Y1603022D03*
Y1599022D03*
X405657Y144300D03*
X402309Y157034D03*
Y152278D03*
X401516Y304000D03*
X399887Y555915D03*
Y561415D03*
X409016Y1641000D03*
X406016Y1649500D03*
X419516Y54762D03*
X413217Y99148D03*
X414456Y226323D03*
Y230323D03*
Y240501D03*
X415231Y254165D03*
Y270165D03*
Y262165D03*
X415682Y1032304D03*
X419516Y1639000D03*
Y1634000D03*
X414016Y1649500D03*
Y1653500D03*
X431267Y1285694D03*
Y1289694D03*
X451315Y206620D03*
Y210620D03*
X451368Y283318D03*
X465515Y210620D03*
Y206620D03*
X465912Y222764D03*
Y235764D03*
Y243764D03*
X462672Y1013604D03*
Y1009864D03*
Y1006123D03*
Y1017344D03*
Y1024824D03*
Y1028564D03*
Y1021084D03*
Y1032304D03*
X465016Y1655500D03*
Y1672000D03*
X465516Y1701000D03*
Y1733500D03*
X480316Y288469D03*
X476321Y309809D03*
X472516Y1668000D03*
Y1659500D03*
Y1676000D03*
Y1697000D03*
Y1710500D03*
Y1733500D03*
X485899Y60105D03*
X486059Y55095D03*
X485789Y64965D03*
X490013Y167625D03*
X489198Y201516D03*
Y197516D03*
X497748D03*
X494550Y233000D03*
Y243178D03*
X501292Y209285D03*
Y213285D03*
Y220166D03*
X511239Y280721D03*
X541712Y190256D03*
Y199256D03*
X543504Y222441D03*
Y235560D03*
Y226441D03*
X538658Y292268D03*
X544253Y659489D03*
X551352Y156667D03*
X551454Y239566D03*
X553189Y403586D03*
X546016Y459000D03*
X559016Y473500D03*
X574519Y164356D03*
Y169415D03*
X567316Y297469D03*
X563321Y318809D03*
X572016Y454500D03*
X578040Y257171D03*
X579976Y366827D03*
X583139Y415846D03*
Y427949D03*
X583158Y431976D03*
X587687Y1266668D03*
Y1262668D03*
X600285Y145640D03*
Y149640D03*
X602794Y157640D03*
X600285Y153640D03*
X591045Y213277D03*
X598239Y289721D03*
X593516Y445500D03*
Y449500D03*
X597014Y464349D03*
X590519Y474353D03*
X600287Y1270598D03*
Y1278598D03*
Y1274598D03*
X613298Y179720D03*
X605909Y260010D03*
X615976Y366827D03*
X615516Y418000D03*
X615407Y426901D03*
X628016Y427000D03*
X629519Y437881D03*
X630175Y461441D03*
X629925Y468856D03*
X619329Y1371182D03*
X619354Y1382864D03*
Y1378964D03*
X619329Y1375082D03*
X619293Y1390732D03*
X646237Y184862D03*
X634625Y230975D03*
Y226975D03*
X648676Y307089D03*
X642596Y401580D03*
X642540Y405449D03*
X647016Y418500D03*
X643016Y433862D03*
X647016Y422500D03*
X643016Y437862D03*
Y442362D03*
Y453862D03*
Y449862D03*
X643140Y461853D03*
X643027Y457746D03*
X643157Y469863D03*
X643016Y488000D03*
X647016Y519500D03*
X659516Y390000D03*
X656516Y429862D03*
Y425862D03*
Y433862D03*
Y453862D03*
Y469862D03*
Y473862D03*
X655738Y1363394D03*
X655770Y1367283D03*
X652716Y1687400D03*
X653316Y1708184D03*
X662516Y1712084D03*
X653316Y1702400D03*
X664739Y363261D03*
X672516Y417862D03*
Y413362D03*
Y433862D03*
Y429862D03*
Y425862D03*
Y421862D03*
Y442362D03*
Y449862D03*
X672548Y486942D03*
X672805Y495084D03*
X665516Y533500D03*
X671116Y1312502D03*
X677821Y1635842D03*
Y1647842D03*
X690736Y76962D03*
X690969Y91668D03*
X680469Y119868D03*
X704130Y1371225D03*
X702126Y1564523D03*
X702016Y1556500D03*
X702126Y1576523D03*
Y1572523D03*
Y1568523D03*
Y1584523D03*
X702016Y1596500D03*
X702126Y1588523D03*
Y1592523D03*
X702016Y1604500D03*
X699244Y1623062D03*
X696855Y1681996D03*
X710237Y221862D03*
X713537Y1403571D03*
X717266Y1566333D03*
X730009Y86998D03*
X730519Y105468D03*
Y101968D03*
X738249Y111252D03*
X736912Y1371325D03*
X724266Y1566333D03*
X725377Y1610743D03*
X725266Y1606733D03*
X751649Y115288D03*
X751651Y119172D03*
X745761Y137864D03*
X748251Y161463D03*
X748516Y175500D03*
X746319Y1403671D03*
X752126Y1580023D03*
X754570Y228201D03*
X756782Y269322D03*
Y265322D03*
X763153Y1570633D03*
X763166Y1574733D03*
Y1578733D03*
Y1587733D03*
X774936Y163254D03*
X773043Y303410D03*
X772958Y308755D03*
X779016Y367500D03*
X776168Y415344D03*
X775168Y431344D03*
Y427344D03*
Y423344D03*
Y447344D03*
Y443344D03*
Y439344D03*
Y435344D03*
Y451344D03*
X788282Y274822D03*
X786143Y303410D03*
X786058Y308755D03*
X789516Y403000D03*
Y399000D03*
X789618Y419344D03*
X789516Y411500D03*
X789618Y431344D03*
Y427344D03*
Y423344D03*
X789668Y435344D03*
X789618Y443344D03*
X789668Y447344D03*
X805516Y392500D03*
X812516D03*
X806551Y427344D03*
X806525Y435628D03*
X805425Y439628D03*
X806449Y459344D03*
Y455344D03*
X806516Y508000D03*
X804666Y1570633D03*
Y1578633D03*
Y1594633D03*
Y1582633D03*
Y1602633D03*
X820016Y409500D03*
X827016D03*
X820935Y427344D03*
Y431344D03*
Y443552D03*
X821062Y439279D03*
X820935Y435628D03*
Y449802D03*
Y459344D03*
X837342Y90451D03*
X839236Y129362D03*
Y135862D03*
X837074Y435552D03*
Y439552D03*
Y443552D03*
Y459578D03*
Y455578D03*
Y463578D03*
X835516Y475000D03*
X848737Y135862D03*
Y129362D03*
X856319Y265057D03*
X856829Y283527D03*
Y280027D03*
X848516Y381000D03*
Y385000D03*
X852716Y401280D03*
X852778Y524413D03*
X846666Y1570633D03*
Y1578633D03*
Y1594633D03*
Y1582633D03*
Y1602633D03*
X871236Y171362D03*
Y176862D03*
X865409Y223763D03*
X858108Y240441D03*
X865409Y227763D03*
X864559Y289311D03*
X859016Y391500D03*
X881241Y192055D03*
X877959Y293347D03*
X877982Y297365D03*
X878016Y301500D03*
X877516Y326000D03*
X902467Y597449D03*
X902316Y602182D03*
X894139Y1137843D03*
X894546Y1149069D03*
Y1153497D03*
X899410Y1159831D03*
X888666Y1570633D03*
Y1578633D03*
Y1594633D03*
Y1582633D03*
Y1602633D03*
X906688Y582412D03*
X903647Y611358D03*
X906688Y625912D03*
X906564Y1161169D03*
X926540Y570703D03*
X930666Y1590233D03*
X941461Y185052D03*
Y189052D03*
X945097Y590417D03*
X941164Y1137843D03*
X941571Y1149069D03*
Y1153497D03*
X946435Y1159831D03*
X961641Y202096D03*
X953589Y1161169D03*
X965141Y198171D03*
X991516Y152299D03*
X982440Y175483D03*
X984971Y264781D03*
Y275443D03*
X977241Y1055484D03*
X998516Y152299D03*
X994428Y217233D03*
X992900Y473675D03*
Y479175D03*
X996572Y521014D03*
Y516014D03*
Y526074D03*
Y531074D03*
X1009892Y175278D03*
Y171278D03*
X1013836Y194499D03*
X1021485Y378764D03*
Y383764D03*
Y388764D03*
X1021516Y402000D03*
X1021485Y393764D03*
X1014073Y425902D03*
X1011280Y460155D03*
Y456155D03*
Y452155D03*
Y464155D03*
Y468155D03*
Y476155D03*
Y472155D03*
Y493655D03*
Y488642D03*
Y480155D03*
X1012302Y550074D03*
Y545074D03*
X1027920Y287311D03*
Y298311D03*
X1028516Y566000D03*
X1043761Y406586D03*
X1039770Y516014D03*
Y521074D03*
Y526074D03*
Y534074D03*
X1042516Y538000D03*
X1041770Y544574D03*
Y549574D03*
X1041847Y553641D03*
X1065810Y475525D03*
X1065780Y483655D03*
Y487655D03*
X1068597Y369792D03*
X1074810Y471500D03*
Y467000D03*
X1074726Y483782D03*
Y487782D03*
X1068312Y1353197D03*
X1087027Y373187D03*
X1081751Y387226D03*
Y379226D03*
Y383226D03*
Y391226D03*
X1090454Y472105D03*
X1091630Y1687229D03*
Y1691229D03*
X1098964Y447355D03*
Y463355D03*
Y459355D03*
Y455355D03*
Y451355D03*
Y467355D03*
Y475355D03*
Y484391D03*
Y489391D03*
X1100912Y1353197D03*
X1099016Y1642500D03*
X1099580Y1696029D03*
X1108380Y1711244D03*
X1133612Y1353197D03*
X1159027Y73939D03*
X1169722Y442341D03*
Y447841D03*
Y464341D03*
Y453341D03*
Y458841D03*
Y469841D03*
Y481691D03*
X1166512Y1353197D03*
X1160291Y1454234D03*
X1178703Y61515D03*
Y57015D03*
X1178723Y52815D03*
X1185103Y99694D03*
X1185208Y574322D03*
X1192218Y177187D03*
Y173187D03*
X1188443Y432202D03*
Y448202D03*
Y440202D03*
Y460202D03*
X1188563Y470392D03*
X1188503Y465272D03*
X1199628Y582443D03*
Y587443D03*
X1199312Y1353197D03*
X1188016Y1401000D03*
Y1396500D03*
Y1405500D03*
Y1410000D03*
X1197016Y1414500D03*
Y1419000D03*
Y1428500D03*
Y1433000D03*
X1188016Y1437500D03*
X1189553Y1693850D03*
X1196553D03*
X1192703Y1689850D03*
X1199993Y1731803D03*
X1202528Y164987D03*
Y160987D03*
Y185187D03*
X1204895Y1693859D03*
X1211895D03*
X1208045Y1689859D03*
X1241709Y128239D03*
Y132739D03*
Y123739D03*
Y137239D03*
X1231209Y145239D03*
X1236970Y427255D03*
Y431255D03*
Y439255D03*
Y435255D03*
X1237303Y1307051D03*
X1240016Y1406500D03*
X1258963Y459182D03*
X1259033Y454372D03*
X1250078Y453182D03*
Y458182D03*
X1245516Y1410500D03*
Y1414500D03*
X1272627Y154030D03*
X1262715Y395125D03*
X1262718Y399125D03*
X1263016Y765000D03*
X1270199Y1307023D03*
X1260612Y1342686D03*
X1277465Y390884D03*
X1295209Y141739D03*
Y137739D03*
X1296123Y162051D03*
Y166051D03*
Y171551D03*
Y184051D03*
X1299167Y527418D03*
X1297248Y541634D03*
X1300782Y552813D03*
X1304239Y560209D03*
X1291850Y592871D03*
X1303103Y1306966D03*
X1316357Y567148D03*
X1309203Y565771D03*
X1318454Y1408282D03*
X1343312Y678393D03*
X1335903Y1307166D03*
X1378231Y236594D03*
Y241594D03*
Y246594D03*
Y251594D03*
X1368485Y1326497D03*
X1391824Y1032303D03*
X1382009Y1670391D03*
X1389009Y1674391D03*
X1384561Y1700038D03*
X1388691Y1695238D03*
X1384561Y1712038D03*
Y1708038D03*
X1387120Y1728318D03*
X1407706Y1285765D03*
Y1289765D03*
X1398149Y1622167D03*
X1405149Y1626167D03*
X1404831Y1646967D03*
X1423813Y1609904D03*
Y1623366D03*
X1418831Y1646967D03*
X1432198Y117664D03*
X1438814Y1013603D03*
Y1009863D03*
Y1006122D03*
Y1017343D03*
Y1028563D03*
Y1021083D03*
Y1024823D03*
Y1032303D03*
X1432825Y1613904D03*
X1433013Y1623504D03*
X1428902Y1647087D03*
X1462773Y537827D03*
X1466773Y580977D03*
Y572977D03*
Y568977D03*
Y576977D03*
X1458773D03*
X1482025Y702203D03*
X1510773Y547977D03*
Y551977D03*
X1500773Y556477D03*
X1500873Y561677D03*
X1510773Y563977D03*
X1514458Y130813D03*
X1519035Y209250D03*
Y213250D03*
Y221250D03*
Y225250D03*
Y231250D03*
Y238017D03*
Y249250D03*
Y244250D03*
Y253250D03*
X1515107Y702203D03*
X1539030Y288816D03*
X1539033Y292816D03*
Y296816D03*
X1553780Y284575D03*
X1547153Y1262314D03*
X1547193Y1270188D03*
Y1274188D03*
X1558064Y1302609D03*
X1570808Y1271378D03*
X1587819Y225250D03*
Y214250D03*
Y229250D03*
Y234250D03*
Y239250D03*
Y244250D03*
X1582193Y1278988D03*
X1575221Y1275454D03*
X1582193Y1292988D03*
X1581788Y1298278D03*
X1574923Y1288958D03*
X1598815Y536344D03*
Y531226D03*
X1588693Y1278988D03*
X1610581Y538723D03*
X1610464Y554664D03*
X1610527Y559092D03*
X1622425Y290742D03*
Y294742D03*
Y298742D03*
Y302742D03*
X1622482Y566803D03*
X1629744Y1432248D03*
X1629719Y1424466D03*
Y1428366D03*
X1629744Y1436148D03*
X1629683Y1448016D03*
X1635516Y381500D03*
X1644626Y414202D03*
X1634849Y1311874D03*
X1646693Y1440488D03*
X1656664Y692328D03*
X1651863Y1370514D03*
X1661270Y1402860D03*
X1666326Y1416678D03*
X1692520Y401485D03*
X1687149Y424694D03*
X1684645Y1370614D03*
X1684824Y1696427D03*
X1694052Y1402960D03*
X1722434Y116867D03*
X1715043Y424340D03*
Y420340D03*
X1732381Y53651D03*
Y57651D03*
X1733134Y89827D03*
X1723350Y656238D03*
X1735961Y1552371D03*
X1726979Y1681465D03*
Y1676965D03*
X1740325Y89264D03*
X1743825Y85339D03*
X1751103Y364048D03*
Y368048D03*
X1751236Y377452D03*
Y382952D03*
X1739593Y668216D03*
Y664216D03*
X1760554Y68637D03*
X1761064Y87107D03*
Y83607D03*
X1764943Y368148D03*
X1764736Y372452D03*
X1764943Y364148D03*
X1764939Y1635686D03*
X1768794Y92891D03*
X1778591Y186911D03*
Y194399D03*
X1781020Y182463D03*
X1778647Y197899D03*
X1771704Y1552371D03*
X1772995Y1582405D03*
X1770495Y1577905D03*
X1767979Y1661465D03*
Y1657465D03*
X1782194Y96927D03*
X1782152Y100939D03*
X1789906Y156834D03*
Y161834D03*
X1791920Y1587105D03*
X1822096Y151834D03*
X1823172Y388051D03*
X1822815Y427432D03*
X1822808Y431678D03*
X1844807Y165834D03*
X1844777Y170287D03*
G54D11*
X27559Y87795D03*
X40708Y631889D03*
Y1368908D03*
X51180Y1714961D03*
X373622Y87795D03*
X395671Y1714960D03*
X661024Y631890D03*
X707677Y1714960D03*
X800787Y87795D03*
X931693Y757874D03*
X931692Y1072835D03*
X931693Y1387795D03*
X1045866Y87795D03*
X1155709Y1714961D03*
X1271260Y631890D03*
X1461806Y1714961D03*
X1499606Y87795D03*
X1806298Y1714961D03*
X1829921Y87795D03*
X1816772Y631889D03*
Y1368897D03*
G54D131*
X306753Y112844D03*
Y124262D03*
X1021924Y150805D03*
Y162223D03*
X1776878Y113968D03*
Y125386D03*
G54D203*
X662740Y370677D03*
X659000D03*
X655260D03*
Y380323D03*
X662740D03*
X1360629Y106559D03*
Y116205D03*
X1364369D03*
X1368109Y106559D03*
Y116205D03*
G54D230*
X785252Y1334469D03*
X796276Y1347855D03*
X905618Y1141976D03*
X916642Y1155362D03*
X952643Y1141976D03*
X963667Y1155362D03*
X1315411Y547916D03*
X1326435Y561302D03*
X1621536Y547571D03*
X1632560Y560957D03*
G54D113*
X260521Y104291D03*
X258553D03*
Y115315D03*
X260521D03*
X274301Y104291D03*
X272333D03*
X270364D03*
X268395D03*
X266427D03*
X264459D03*
X262490D03*
Y115315D03*
X264459D03*
X266427D03*
X268395D03*
X270364D03*
X272333D03*
X691709Y108416D03*
Y119440D03*
X707457Y108416D03*
X705489D03*
X703520D03*
X701551D03*
X699583D03*
X697615D03*
X695646D03*
X693677D03*
Y119440D03*
X695646D03*
X697615D03*
X699583D03*
X701551D03*
X703520D03*
X705489D03*
X997487Y211742D03*
X1001423D03*
X1735642Y105415D03*
X1733674D03*
Y116439D03*
X1735642D03*
X1749422Y105415D03*
X1747454D03*
X1745485D03*
X1743516D03*
X1741548D03*
X1739580D03*
X1737611D03*
Y116439D03*
X1739580D03*
X1741548D03*
X1743516D03*
X1745485D03*
X1747454D03*
G54D212*
X721113Y651187D03*
Y646147D03*
X719145Y651187D03*
Y646147D03*
X1146221Y1558549D03*
Y1553509D03*
X1144253Y1558549D03*
Y1553509D03*
X1471975Y1676881D03*
Y1681921D03*
X1473943Y1676881D03*
Y1681921D03*
G54D140*
X326731Y653394D03*
X363731D03*
X433624Y594259D03*
X754645Y1426892D03*
X1166535Y1412479D03*
X1291146Y1375715D03*
X1320516D03*
X1415690Y601230D03*
X1487677Y640145D03*
X1524437Y640365D03*
X1701285Y198612D03*
X1700840Y1424519D03*
X1731660Y198612D03*
X1770442Y284934D03*
X1800002D03*
G54D221*
X753500Y196547D03*
Y202453D03*
X1301710Y60741D03*
Y66647D03*
X1313620Y60741D03*
Y66647D03*
X1349350Y60741D03*
Y66647D03*
G54D104*
X184530Y1514243D03*
X186105Y1516970D03*
X184530Y1527880D03*
X186105Y1530608D03*
X189254Y1514243D03*
X193979D03*
X198703D03*
X187680Y1519698D03*
X192404D03*
X197128D03*
X190829Y1516970D03*
X195554D03*
X200278D03*
X189254Y1536063D03*
X193979D03*
X198703D03*
X187680Y1533336D03*
X192404D03*
X197128D03*
X190829Y1530608D03*
X195554D03*
X200278D03*
X203428Y1514243D03*
X208152D03*
X212876D03*
X216026Y1519698D03*
X201853D03*
X206577D03*
X211302D03*
X214451Y1516970D03*
X205002D03*
X209727D03*
X203428Y1536063D03*
X208152D03*
X212876D03*
X216026Y1533336D03*
X201853D03*
X206577D03*
X211302D03*
X214451Y1530608D03*
X205002D03*
X209727D03*
X217601Y1514243D03*
X222325D03*
X227050D03*
X220750Y1519698D03*
X225475D03*
X230199D03*
X219176Y1516970D03*
X223900D03*
X228624D03*
X217601Y1536063D03*
X222325D03*
X227050D03*
X220750Y1533336D03*
X225475D03*
X230199D03*
X219176Y1530608D03*
X223900D03*
X228624D03*
X231774Y1514243D03*
X236498D03*
X241223D03*
X245947D03*
X234924Y1519698D03*
X239648D03*
X244372D03*
X233349Y1516970D03*
X238073D03*
X242798D03*
X231774Y1536063D03*
X236498D03*
X241223D03*
X245947D03*
X234924Y1533336D03*
X239648D03*
X244372D03*
X233349Y1530608D03*
X238073D03*
X242798D03*
X255396Y1514243D03*
X250672D03*
X249097Y1519698D03*
X253821D03*
X258546D03*
X247522Y1516970D03*
X252247D03*
X256971D03*
X255396Y1536063D03*
X260121D03*
X250672D03*
X249097Y1533336D03*
X253821D03*
X258546D03*
X247522Y1530608D03*
X252247D03*
X256971D03*
X312592Y1514243D03*
X317316D03*
X315742Y1519698D03*
X320466D03*
X314167Y1516970D03*
X318891D03*
X312592Y1527880D03*
X317316Y1536063D03*
X315742Y1533336D03*
X320466D03*
X314167Y1530608D03*
X318891D03*
X322041Y1514243D03*
X326765D03*
X331490D03*
X325190Y1519698D03*
X329915D03*
X334639D03*
X323616Y1516970D03*
X328340D03*
X333064D03*
X322041Y1536063D03*
X326765D03*
X331490D03*
X325190Y1533336D03*
X329915D03*
X334639D03*
X323616Y1530608D03*
X328340D03*
X333064D03*
X336214Y1514243D03*
X340938D03*
X345663D03*
X350387D03*
X344088Y1519698D03*
X348812D03*
X339364D03*
X342513Y1516970D03*
X347238D03*
X337789D03*
X336214Y1536063D03*
X340938D03*
X345663D03*
X350387D03*
X344088Y1533336D03*
X348812D03*
X339364D03*
X342513Y1530608D03*
X347238D03*
X337789D03*
X355112Y1514243D03*
X359836D03*
X364560D03*
X353537Y1519698D03*
X358261D03*
X362986D03*
X351962Y1516970D03*
X356686D03*
X361411D03*
X355112Y1536063D03*
X359836D03*
X364560D03*
X353537Y1533336D03*
X358261D03*
X362986D03*
X351962Y1530608D03*
X356686D03*
X361411D03*
X369285Y1514243D03*
X374009D03*
X378734D03*
X367710Y1519698D03*
X372434D03*
X377159D03*
X366135Y1516970D03*
X370860D03*
X375584D03*
X380309D03*
X369285Y1536063D03*
X374009D03*
X378734D03*
X367710Y1533336D03*
X372434D03*
X377159D03*
X366135Y1530608D03*
X370860D03*
X375584D03*
X380309D03*
X383458Y1514243D03*
X381883Y1519698D03*
X386608D03*
X385033Y1516970D03*
X383458Y1536063D03*
X388183D03*
X381883Y1533336D03*
X386608D03*
X385033Y1530608D03*
X448703Y1514243D03*
X453427D03*
X451853Y1519698D03*
X450278Y1516970D03*
X455002D03*
X448703Y1527880D03*
X453427Y1536063D03*
X451853Y1533336D03*
X450278Y1530608D03*
X455002D03*
X458152Y1514243D03*
X462876D03*
X467601D03*
X456577Y1519698D03*
X461301D03*
X466026D03*
X459727Y1516970D03*
X464451D03*
X469175D03*
X458152Y1536063D03*
X462876D03*
X467601D03*
X456577Y1533336D03*
X461301D03*
X466026D03*
X459727Y1530608D03*
X464451D03*
X469175D03*
X472325Y1514243D03*
X477049D03*
X481774D03*
X480199Y1519698D03*
X470750D03*
X475475D03*
X478624Y1516970D03*
X483349D03*
X473900D03*
X472325Y1536063D03*
X477049D03*
X481774D03*
X480199Y1533336D03*
X470750D03*
X475475D03*
X478624Y1530608D03*
X483349D03*
X473900D03*
X486498Y1514243D03*
X491223D03*
X495947D03*
X484923Y1519698D03*
X489648D03*
X494372D03*
X499097D03*
X488073Y1516970D03*
X492797D03*
X497522D03*
X486498Y1536063D03*
X491223D03*
X495947D03*
X484923Y1533336D03*
X489648D03*
X494372D03*
X499097D03*
X488073Y1530608D03*
X492797D03*
X497522D03*
X500671Y1514243D03*
X505396D03*
X510120D03*
X503821Y1519698D03*
X508545D03*
X513270D03*
X502246Y1516970D03*
X506971D03*
X511695D03*
X500671Y1536063D03*
X505396D03*
X510120D03*
X503821Y1533336D03*
X508545D03*
X513270D03*
X502246Y1530608D03*
X506971D03*
X511695D03*
X519569Y1514243D03*
X514845D03*
X517994Y1519698D03*
X522719D03*
X516420Y1516970D03*
X521144D03*
X519569Y1536063D03*
X524294D03*
X514845D03*
X517994Y1533336D03*
X522719D03*
X516420Y1530608D03*
X521144D03*
X576765Y1514243D03*
X581489D03*
X586214D03*
X579915Y1519698D03*
X584639D03*
X578340Y1516970D03*
X583064D03*
X587789D03*
X576765Y1527880D03*
X581489Y1536063D03*
X586214D03*
X579915Y1533336D03*
X584639D03*
X578340Y1530608D03*
X583064D03*
X587789D03*
X590938Y1514243D03*
X595663D03*
X600387D03*
X589363Y1519698D03*
X594088D03*
X598812D03*
X603537D03*
X592513Y1516970D03*
X597237D03*
X601962D03*
X590938Y1536063D03*
X595663D03*
X600387D03*
X589363Y1533336D03*
X594088D03*
X598812D03*
X603537D03*
X592513Y1530608D03*
X597237D03*
X601962D03*
X605111Y1514243D03*
X609836D03*
X614560D03*
X608261Y1519698D03*
X612985D03*
X617710D03*
X606686Y1516970D03*
X611411D03*
X616135D03*
X605111Y1536063D03*
X609836D03*
X614560D03*
X608261Y1533336D03*
X612985D03*
X617710D03*
X606686Y1530608D03*
X611411D03*
X616135D03*
X619285Y1514243D03*
X624009D03*
X628733D03*
X633458D03*
X622434Y1519698D03*
X627159D03*
X631883D03*
X620859Y1516970D03*
X625584D03*
X630308D03*
X619285Y1536063D03*
X624009D03*
X628733D03*
X633458D03*
X622434Y1533336D03*
X627159D03*
X631883D03*
X620859Y1530608D03*
X625584D03*
X630308D03*
X647631Y1514243D03*
X638182D03*
X642907D03*
X636607Y1519698D03*
X641332D03*
X646056D03*
X635033Y1516970D03*
X639757D03*
X644482D03*
X647631Y1536063D03*
X638182D03*
X642907D03*
X636607Y1533336D03*
X641332D03*
X646056D03*
X635033Y1530608D03*
X639757D03*
X644482D03*
X650781Y1519698D03*
X649206Y1516970D03*
X652356Y1536063D03*
X650781Y1533336D03*
X649206Y1530608D03*
X1192403Y1547243D03*
X1197127D03*
X1193978Y1549970D03*
X1198702D03*
X1192403Y1560880D03*
X1195553Y1566336D03*
X1200277D03*
X1193978Y1563608D03*
X1198702D03*
X1195553Y1552698D03*
X1200277D03*
X1197127Y1569063D03*
X1201852Y1547243D03*
X1206576D03*
X1211301D03*
X1203427Y1549970D03*
X1208151D03*
X1212875D03*
X1205001Y1566336D03*
X1209726D03*
X1214450D03*
X1203427Y1563608D03*
X1208151D03*
X1212875D03*
X1205001Y1552698D03*
X1209726D03*
X1214450D03*
X1201852Y1569063D03*
X1206576D03*
X1211301D03*
X1216025Y1547243D03*
X1220749D03*
X1225474D03*
X1230198D03*
X1222324Y1549970D03*
X1227049D03*
X1217600D03*
X1223899Y1566336D03*
X1228623D03*
X1219175D03*
X1222324Y1563608D03*
X1227049D03*
X1217600D03*
X1223899Y1552698D03*
X1228623D03*
X1219175D03*
X1216025Y1569063D03*
X1220749D03*
X1225474D03*
X1230198D03*
X1234923Y1547243D03*
X1239647D03*
X1244371D03*
X1231773Y1549970D03*
X1236497D03*
X1241222D03*
X1233348Y1566336D03*
X1238072D03*
X1242797D03*
X1231773Y1563608D03*
X1236497D03*
X1241222D03*
X1233348Y1552698D03*
X1238072D03*
X1242797D03*
X1234923Y1569063D03*
X1239647D03*
X1244371D03*
X1249096Y1547243D03*
X1253820D03*
X1258545D03*
X1245946Y1549970D03*
X1250671D03*
X1255395D03*
X1247521Y1566336D03*
X1252245D03*
X1256970D03*
X1245946Y1563608D03*
X1250671D03*
X1255395D03*
X1247521Y1552698D03*
X1252245D03*
X1256970D03*
X1249096Y1569063D03*
X1253820D03*
X1258545D03*
X1263269Y1547243D03*
X1260120Y1549970D03*
X1264844D03*
X1261694Y1566336D03*
X1266419D03*
X1260120Y1563608D03*
X1264844D03*
X1261694Y1552698D03*
X1266419D03*
X1263269Y1569063D03*
X1267994D03*
X1320465Y1547243D03*
X1325189D03*
X1329914D03*
X1322040Y1549970D03*
X1326764D03*
X1331489D03*
X1320465Y1560880D03*
X1323615Y1566336D03*
X1328339D03*
X1333063D03*
X1322040Y1563608D03*
X1326764D03*
X1331489D03*
X1323615Y1552698D03*
X1328339D03*
X1333063D03*
X1325189Y1569063D03*
X1329914D03*
X1334638Y1547243D03*
X1339363D03*
X1344087D03*
X1348811D03*
X1336213Y1549970D03*
X1340937D03*
X1345662D03*
X1337788Y1566336D03*
X1342512D03*
X1347237D03*
X1336213Y1563608D03*
X1340937D03*
X1345662D03*
X1337788Y1552698D03*
X1342512D03*
X1347237D03*
X1334638Y1569063D03*
X1339363D03*
X1344087D03*
X1348811D03*
X1353536Y1547243D03*
X1358260D03*
X1362985D03*
X1350386Y1549970D03*
X1355111D03*
X1359835D03*
X1351961Y1566336D03*
X1356685D03*
X1361410D03*
X1350386Y1563608D03*
X1355111D03*
X1359835D03*
X1351961Y1552698D03*
X1356685D03*
X1361410D03*
X1353536Y1569063D03*
X1358260D03*
X1362985D03*
X1367709Y1547243D03*
X1372433D03*
X1377158D03*
X1364559Y1549970D03*
X1369284D03*
X1374008D03*
X1378733D03*
X1366134Y1566336D03*
X1370859D03*
X1375583D03*
X1364559Y1563608D03*
X1369284D03*
X1374008D03*
X1378733D03*
X1366134Y1552698D03*
X1370859D03*
X1375583D03*
X1367709Y1569063D03*
X1372433D03*
X1377158D03*
X1391331Y1547243D03*
X1381882D03*
X1386607D03*
X1383457Y1549970D03*
X1388182D03*
X1392906D03*
X1380307Y1566336D03*
X1385032D03*
X1389756D03*
X1383457Y1563608D03*
X1388182D03*
X1392906D03*
X1380307Y1552698D03*
X1385032D03*
X1389756D03*
X1391331Y1569063D03*
X1381882D03*
X1386607D03*
X1394481Y1566336D03*
Y1552698D03*
X1396056Y1569063D03*
X1456577Y1547243D03*
X1461301D03*
X1466026D03*
X1458152Y1549970D03*
X1462876D03*
X1467601D03*
X1456577Y1560880D03*
X1459727Y1566336D03*
X1464451D03*
X1458152Y1563608D03*
X1462876D03*
X1467601D03*
X1459727Y1552698D03*
X1464451D03*
X1461301Y1569063D03*
X1466026D03*
X1470750Y1547243D03*
X1475475D03*
X1480199D03*
X1472325Y1549970D03*
X1477049D03*
X1481774D03*
X1469175Y1566336D03*
X1473900D03*
X1478624D03*
X1483349D03*
X1472325Y1563608D03*
X1477049D03*
X1481774D03*
X1469175Y1552698D03*
X1473900D03*
X1478624D03*
X1483349D03*
X1470750Y1569063D03*
X1475475D03*
X1480199D03*
X1484923Y1547243D03*
X1489648D03*
X1494372D03*
X1486498Y1549970D03*
X1491223D03*
X1495947D03*
X1488073Y1566336D03*
X1492797D03*
X1497522D03*
X1486498Y1563608D03*
X1491223D03*
X1495947D03*
X1488073Y1552698D03*
X1492797D03*
X1497522D03*
X1484923Y1569063D03*
X1489648D03*
X1494372D03*
X1499097Y1547243D03*
X1503821D03*
X1508545D03*
X1513270D03*
X1500671Y1549970D03*
X1505396D03*
X1510120D03*
X1502246Y1566336D03*
X1506971D03*
X1511695D03*
X1500671Y1563608D03*
X1505396D03*
X1510120D03*
X1502246Y1552698D03*
X1506971D03*
X1511695D03*
X1499097Y1569063D03*
X1503821D03*
X1508545D03*
X1513270D03*
X1527443Y1547243D03*
X1517994D03*
X1522719D03*
X1514845Y1549970D03*
X1519569D03*
X1524294D03*
X1516419Y1566336D03*
X1521144D03*
X1525868D03*
X1514845Y1563608D03*
X1519569D03*
X1524294D03*
X1516419Y1552698D03*
X1521144D03*
X1525868D03*
X1527443Y1569063D03*
X1517994D03*
X1522719D03*
X1529018Y1549970D03*
X1530593Y1566336D03*
X1529018Y1563608D03*
X1530593Y1552698D03*
X1532168Y1569063D03*
X1584639Y1547243D03*
X1586214Y1549970D03*
X1584639Y1560880D03*
X1587789Y1566336D03*
X1586214Y1563608D03*
X1587789Y1552698D03*
X1589363Y1547243D03*
X1594088D03*
X1598812D03*
X1590938Y1549970D03*
X1595663D03*
X1600387D03*
X1592513Y1566336D03*
X1597237D03*
X1601962D03*
X1590938Y1563608D03*
X1595663D03*
X1600387D03*
X1592513Y1552698D03*
X1597237D03*
X1601962D03*
X1589363Y1569063D03*
X1594088D03*
X1598812D03*
X1603537Y1547243D03*
X1608261D03*
X1612985D03*
X1617710D03*
X1614560Y1549970D03*
X1605111D03*
X1609836D03*
X1616135Y1566336D03*
X1606686D03*
X1611411D03*
X1614560Y1563608D03*
X1605111D03*
X1609836D03*
X1616135Y1552698D03*
X1606686D03*
X1611411D03*
X1603537Y1569063D03*
X1608261D03*
X1612985D03*
X1617710D03*
X1622434Y1547243D03*
X1627159D03*
X1631883D03*
X1619285Y1549970D03*
X1624009D03*
X1628733D03*
X1620859Y1566336D03*
X1625584D03*
X1630308D03*
X1619285Y1563608D03*
X1624009D03*
X1628733D03*
X1620859Y1552698D03*
X1625584D03*
X1630308D03*
X1622434Y1569063D03*
X1627159D03*
X1631883D03*
X1636607Y1547243D03*
X1641332D03*
X1646056D03*
X1633458Y1549970D03*
X1638182D03*
X1642907D03*
X1647631D03*
X1635033Y1566336D03*
X1639757D03*
X1644481D03*
X1633458Y1563608D03*
X1638182D03*
X1642907D03*
X1647631D03*
X1635033Y1552698D03*
X1639757D03*
X1644481D03*
X1636607Y1569063D03*
X1641332D03*
X1646056D03*
X1655505Y1547243D03*
X1650781D03*
X1652356Y1549970D03*
X1657080D03*
X1649206Y1566336D03*
X1653930D03*
X1658655D03*
X1652356Y1563608D03*
X1657080D03*
X1649206Y1552698D03*
X1653930D03*
X1658655D03*
X1655505Y1569063D03*
X1660230D03*
X1650781D03*
G54D122*
X268312Y594420D03*
G54D21*
X21815Y516951D03*
X35968Y401000D03*
X51645Y1519335D03*
X41116Y1594396D03*
Y1607896D03*
Y1598896D03*
Y1603396D03*
Y1612896D03*
Y1617396D03*
X47410Y1668587D03*
Y1663587D03*
X48110Y1681645D03*
X60090Y423746D03*
X62110Y1682016D03*
X55110Y1681489D03*
X77234Y145191D03*
X77237Y149191D03*
Y153191D03*
X69708Y268223D03*
X76483Y1434000D03*
X82116Y1611896D03*
Y1625396D03*
Y1620896D03*
Y1616396D03*
X70116Y1630396D03*
X73650Y1634905D03*
X91984Y140950D03*
X84857Y382219D03*
Y391391D03*
Y395865D03*
X89983Y1417000D03*
Y1412500D03*
Y1408000D03*
Y1421500D03*
Y1435500D03*
X87388Y1519335D03*
X88679Y1549369D03*
X86179Y1544869D03*
X95250Y1716241D03*
X88403Y1706511D03*
X88240Y1716331D03*
X99541Y1353216D03*
X98983Y1426000D03*
Y1430500D03*
Y1440000D03*
Y1435500D03*
X107604Y1554069D03*
X106969Y1671361D03*
Y1667361D03*
Y1679564D03*
Y1675564D03*
X110483Y1712450D03*
X126336Y1661087D03*
X132141Y1353216D03*
X139903Y1701011D03*
X139801Y1705166D03*
X135750Y1718241D03*
X154683Y438810D03*
X144475Y521997D03*
Y530997D03*
Y534997D03*
X152730Y668361D03*
X143983Y1417500D03*
X147983Y1421500D03*
Y1425500D03*
X142750Y1726241D03*
Y1722241D03*
X171333Y395040D03*
X169349Y684799D03*
Y680799D03*
X164841Y1353216D03*
X158798Y1726500D03*
X177583Y416600D03*
X181463Y438270D03*
X179483Y672500D03*
Y676500D03*
X174983Y1711000D03*
Y1725000D03*
X195903Y140962D03*
X198619Y165325D03*
X197741Y1353216D03*
X200762Y1723000D03*
X201983Y1707000D03*
X225335Y144710D03*
X230541Y1353216D03*
X245203Y75862D03*
X237183Y142062D03*
X233503Y159071D03*
X235726Y715823D03*
X258883Y58400D03*
Y54400D03*
X257783Y73400D03*
X258883Y62400D03*
X260780Y87543D03*
X250280Y115743D03*
X270036Y151203D03*
Y147203D03*
X270086Y137302D03*
X272983Y211000D03*
X264983Y217500D03*
X263826Y583999D03*
X264141Y1307070D03*
X281939Y74536D03*
X278439Y78461D03*
X286783Y136962D03*
X279983Y215000D03*
X286774Y577698D03*
X283624Y574022D03*
X279909Y570398D03*
X286774Y581298D03*
X287450Y1342705D03*
X301149Y67128D03*
X305140Y91767D03*
X298910Y85983D03*
Y82483D03*
X297037Y1307042D03*
X320082Y95852D03*
X320086Y99837D03*
X317322Y227851D03*
Y231851D03*
X313483Y241000D03*
X311983Y263000D03*
X329129Y147120D03*
Y152120D03*
Y156120D03*
Y160120D03*
X329941Y1306985D03*
X346153Y229180D03*
X348640Y586415D03*
X341722Y702203D03*
X355416Y219343D03*
X356640Y582415D03*
Y578415D03*
X359040Y590415D03*
Y586415D03*
X362741Y1307185D03*
X378978Y149077D03*
X373946Y163173D03*
X377008Y235455D03*
X377038Y239615D03*
X365891Y294030D03*
X374782Y701935D03*
X384071Y287370D03*
X390640Y565915D03*
X390440Y571115D03*
X395323Y1326516D03*
X408624Y144300D03*
X405276Y157034D03*
Y152278D03*
X404483Y304000D03*
X402854Y555915D03*
Y561415D03*
X397088Y1611022D03*
Y1607022D03*
Y1603022D03*
Y1599022D03*
X408983Y1649500D03*
X422483Y54762D03*
X416184Y99148D03*
X417423Y226323D03*
Y230323D03*
Y240501D03*
X418198Y254165D03*
Y270165D03*
Y262165D03*
X418649Y1032304D03*
X422483Y1639000D03*
Y1634000D03*
X411983Y1641000D03*
X416983Y1649500D03*
Y1653500D03*
X434234Y1285694D03*
Y1289694D03*
X454282Y206620D03*
Y210620D03*
X454335Y283318D03*
X468482Y210620D03*
Y206620D03*
X468879Y222764D03*
Y235764D03*
Y243764D03*
X465639Y1013604D03*
Y1009864D03*
Y1006123D03*
Y1017344D03*
Y1024824D03*
Y1028564D03*
Y1021084D03*
Y1032304D03*
X467983Y1655500D03*
Y1672000D03*
X468483Y1701000D03*
Y1733500D03*
X483283Y288469D03*
X479288Y309809D03*
X475483Y1668000D03*
Y1659500D03*
Y1676000D03*
Y1697000D03*
Y1710500D03*
Y1733500D03*
X488866Y60105D03*
X489026Y55095D03*
X488756Y64965D03*
X492980Y167625D03*
X492165Y201516D03*
Y197516D03*
X497517Y233000D03*
Y243178D03*
X504259Y209285D03*
X500715Y197516D03*
X504259Y213285D03*
Y220166D03*
X514206Y280721D03*
X544679Y190256D03*
Y199256D03*
X541625Y292268D03*
X554319Y156667D03*
X546471Y222441D03*
Y235560D03*
X554421Y239566D03*
X546471Y226441D03*
X556156Y403586D03*
X548983Y459000D03*
X547220Y659489D03*
X570283Y297469D03*
X566288Y318809D03*
X561983Y473500D03*
X577486Y164356D03*
Y169415D03*
X581007Y257171D03*
X582943Y366827D03*
X586106Y415846D03*
Y427949D03*
X586125Y431976D03*
X574983Y454500D03*
X603252Y145640D03*
Y149640D03*
Y153640D03*
X594012Y213277D03*
X601206Y289721D03*
X596483Y445500D03*
Y449500D03*
X599981Y464349D03*
X593486Y474353D03*
X590654Y1266668D03*
Y1262668D03*
X603254Y1270598D03*
Y1278598D03*
Y1274598D03*
X605761Y157640D03*
X616265Y179720D03*
X608876Y260010D03*
X618943Y366827D03*
X618483Y418000D03*
X618374Y426901D03*
X630983Y427000D03*
X632486Y437881D03*
X633142Y461441D03*
X632892Y468856D03*
X622296Y1371182D03*
X622321Y1382864D03*
Y1378964D03*
X622296Y1375082D03*
X622260Y1390732D03*
X637592Y230975D03*
Y226975D03*
X645563Y401580D03*
X645507Y405449D03*
X645983Y433862D03*
Y437862D03*
Y442362D03*
Y453862D03*
Y449862D03*
X646107Y461853D03*
X645994Y457746D03*
X646124Y469863D03*
X645983Y488000D03*
X649204Y184862D03*
X651643Y307089D03*
X662483Y390000D03*
X649983Y418500D03*
X659483Y429862D03*
Y425862D03*
Y433862D03*
X649983Y422500D03*
X659483Y453862D03*
Y469862D03*
Y473862D03*
X649983Y519500D03*
X658705Y1363394D03*
X658737Y1367283D03*
X655683Y1687400D03*
X656283Y1708184D03*
Y1702400D03*
X667706Y363261D03*
X675483Y417862D03*
Y413362D03*
Y433862D03*
Y429862D03*
Y425862D03*
Y421862D03*
Y442362D03*
Y449862D03*
X675515Y486942D03*
X675772Y495084D03*
X668483Y533500D03*
X674083Y1312502D03*
X665483Y1712084D03*
X693703Y76962D03*
X683436Y119868D03*
X680788Y1635842D03*
Y1647842D03*
X693936Y91668D03*
X707097Y1371225D03*
X705093Y1564523D03*
X704983Y1556500D03*
X705093Y1576523D03*
Y1572523D03*
Y1568523D03*
Y1584523D03*
X704983Y1596500D03*
X705093Y1588523D03*
Y1592523D03*
X704983Y1604500D03*
X702211Y1623062D03*
X699822Y1681996D03*
X713204Y221862D03*
X716504Y1403571D03*
X720233Y1566333D03*
X732976Y86998D03*
X733486Y105468D03*
Y101968D03*
X727233Y1566333D03*
X728344Y1610743D03*
X728233Y1606733D03*
X741216Y111252D03*
X748728Y137864D03*
X751218Y161463D03*
X751483Y175500D03*
X739879Y1371325D03*
X749286Y1403671D03*
X754616Y115288D03*
X754618Y119172D03*
X757537Y228201D03*
X759749Y269322D03*
Y265322D03*
X766120Y1570633D03*
X755093Y1580023D03*
X766133Y1574733D03*
Y1578733D03*
Y1587733D03*
X777903Y163254D03*
X776010Y303410D03*
X775925Y308755D03*
X781983Y367500D03*
X779135Y415344D03*
X778135Y431344D03*
Y427344D03*
Y423344D03*
Y447344D03*
Y443344D03*
Y439344D03*
Y435344D03*
Y451344D03*
X791249Y274822D03*
X789110Y303410D03*
X789025Y308755D03*
X792483Y403000D03*
Y399000D03*
X792585Y419344D03*
X792483Y411500D03*
X792585Y431344D03*
Y427344D03*
Y423344D03*
X792635Y435344D03*
X792585Y443344D03*
X792635Y447344D03*
X808483Y392500D03*
X809518Y427344D03*
X809492Y435628D03*
X808392Y439628D03*
X809416Y459344D03*
Y455344D03*
X809483Y508000D03*
X807633Y1570633D03*
Y1578633D03*
Y1594633D03*
Y1582633D03*
Y1602633D03*
X815483Y392500D03*
X822983Y409500D03*
X823902Y427344D03*
Y431344D03*
Y443552D03*
X824029Y439279D03*
X823902Y435628D03*
Y449802D03*
Y459344D03*
X840309Y90451D03*
X842203Y129362D03*
Y135862D03*
X829983Y409500D03*
X840041Y435552D03*
Y439552D03*
Y443552D03*
Y459578D03*
Y455578D03*
Y463578D03*
X838483Y475000D03*
X851704Y135862D03*
Y129362D03*
X851483Y381000D03*
Y385000D03*
X855683Y401280D03*
X855745Y524413D03*
X849633Y1570633D03*
Y1578633D03*
Y1594633D03*
Y1582633D03*
Y1602633D03*
X868376Y223763D03*
X861075Y240441D03*
X868376Y227763D03*
X859286Y265057D03*
X859796Y283527D03*
Y280027D03*
X867526Y289311D03*
X861983Y391500D03*
X874203Y171362D03*
Y176862D03*
X884208Y192055D03*
X880926Y293347D03*
X880949Y297365D03*
X880983Y301500D03*
X880483Y326000D03*
X897106Y1137843D03*
X897513Y1149069D03*
Y1153497D03*
X902377Y1159831D03*
X891633Y1570633D03*
Y1578633D03*
Y1594633D03*
Y1582633D03*
Y1602633D03*
X909655Y582412D03*
X905434Y597449D03*
X906614Y611358D03*
X905283Y602182D03*
X909655Y625912D03*
X909531Y1161169D03*
X929507Y570703D03*
X944428Y185052D03*
Y189052D03*
X944131Y1137843D03*
X944538Y1149069D03*
Y1153497D03*
X933633Y1590233D03*
X948064Y590417D03*
X956556Y1161169D03*
X949402Y1159831D03*
X964608Y202096D03*
X968108Y198171D03*
X985407Y175483D03*
X987938Y264781D03*
Y275443D03*
X980208Y1055484D03*
X1001483Y152299D03*
X994483D03*
X997395Y217233D03*
X995867Y473675D03*
Y479175D03*
X999539Y521014D03*
Y516014D03*
Y526074D03*
Y531074D03*
X1012859Y175278D03*
Y171278D03*
X1016803Y194499D03*
X1017040Y425902D03*
X1014247Y460155D03*
Y456155D03*
Y452155D03*
Y464155D03*
Y468155D03*
Y476155D03*
Y472155D03*
Y493655D03*
Y488642D03*
Y480155D03*
X1015269Y550074D03*
Y545074D03*
X1030887Y287311D03*
Y298311D03*
X1024452Y378764D03*
Y383764D03*
Y388764D03*
X1024483Y402000D03*
X1024452Y393764D03*
X1031483Y566000D03*
X1046728Y406586D03*
X1042737Y516014D03*
Y521074D03*
Y526074D03*
Y534074D03*
X1045483Y538000D03*
X1044737Y544574D03*
Y549574D03*
X1044814Y553641D03*
X1071564Y369792D03*
X1068777Y475525D03*
X1077777Y471500D03*
Y467000D03*
X1077693Y483782D03*
Y487782D03*
X1068747Y483655D03*
Y487655D03*
X1071279Y1353197D03*
X1089994Y373187D03*
X1084718Y387226D03*
Y379226D03*
Y383226D03*
Y391226D03*
X1093421Y472105D03*
X1094597Y1687229D03*
Y1691229D03*
X1101931Y447355D03*
Y463355D03*
Y459355D03*
Y455355D03*
Y451355D03*
Y467355D03*
Y475355D03*
Y484391D03*
Y489391D03*
X1103879Y1353197D03*
X1101983Y1642500D03*
X1102547Y1696029D03*
X1111347Y1711244D03*
X1136579Y1353197D03*
X1161994Y73939D03*
X1169479Y1353197D03*
X1163258Y1454234D03*
X1181670Y61515D03*
Y57015D03*
X1181690Y52815D03*
X1172689Y442341D03*
Y447841D03*
Y464341D03*
Y453341D03*
Y458841D03*
Y469841D03*
Y481691D03*
X1188070Y99694D03*
X1195185Y177187D03*
Y173187D03*
X1191410Y432202D03*
Y448202D03*
Y440202D03*
Y460202D03*
X1191530Y470392D03*
X1191470Y465272D03*
X1188175Y574322D03*
X1190983Y1401000D03*
Y1396500D03*
Y1405500D03*
Y1410000D03*
X1199983Y1414500D03*
Y1419000D03*
Y1428500D03*
Y1433000D03*
X1190983Y1437500D03*
X1192520Y1693850D03*
X1199520D03*
X1195670Y1689850D03*
X1205495Y164987D03*
Y160987D03*
Y185187D03*
X1202595Y582443D03*
Y587443D03*
X1202279Y1353197D03*
X1207862Y1693859D03*
X1214862D03*
X1211012Y1689859D03*
X1202960Y1731803D03*
X1244676Y128239D03*
Y132739D03*
Y123739D03*
Y137239D03*
X1234176Y145239D03*
X1239937Y427255D03*
Y431255D03*
Y439255D03*
Y435255D03*
X1240270Y1307051D03*
X1242983Y1406500D03*
X1253045Y453182D03*
Y458182D03*
X1248483Y1410500D03*
Y1414500D03*
X1265682Y395125D03*
X1265685Y399125D03*
X1261930Y459182D03*
X1262000Y454372D03*
X1265983Y765000D03*
X1273166Y1307023D03*
X1263579Y1342686D03*
X1275594Y154030D03*
X1280432Y390884D03*
X1298176Y141739D03*
Y137739D03*
X1299090Y162051D03*
Y166051D03*
Y171551D03*
Y184051D03*
X1302134Y527418D03*
X1300215Y541634D03*
X1303749Y552813D03*
X1294817Y592871D03*
X1319324Y567148D03*
X1307206Y560209D03*
X1312170Y565771D03*
X1306070Y1306966D03*
X1321421Y1408282D03*
X1346279Y678393D03*
X1338870Y1307166D03*
X1371452Y1326497D03*
X1381198Y236594D03*
Y241594D03*
Y246594D03*
Y251594D03*
X1384976Y1670391D03*
X1391976Y1674391D03*
X1387528Y1700038D03*
X1391658Y1695238D03*
X1387528Y1712038D03*
Y1708038D03*
X1390087Y1728318D03*
X1394791Y1032303D03*
X1401116Y1622167D03*
X1408116Y1626167D03*
X1407798Y1646967D03*
X1410673Y1285765D03*
Y1289765D03*
X1421798Y1646967D03*
X1435165Y117664D03*
X1426780Y1609904D03*
X1435792Y1613904D03*
X1435980Y1623504D03*
X1426780Y1623366D03*
X1431869Y1647087D03*
X1441781Y1013603D03*
Y1009863D03*
Y1006122D03*
Y1017343D03*
Y1028563D03*
Y1021083D03*
Y1024823D03*
Y1032303D03*
X1465740Y537827D03*
X1461740Y576977D03*
X1469740Y580977D03*
Y572977D03*
Y568977D03*
Y576977D03*
X1484992Y702203D03*
X1513740Y547977D03*
Y551977D03*
X1503740Y556477D03*
X1503840Y561677D03*
X1513740Y563977D03*
X1517425Y130813D03*
X1522002Y209250D03*
Y213250D03*
Y221250D03*
Y225250D03*
Y231250D03*
Y238017D03*
Y249250D03*
Y244250D03*
Y253250D03*
X1518074Y702203D03*
X1541997Y288816D03*
X1542000Y292816D03*
Y296816D03*
X1556747Y284575D03*
X1550120Y1262314D03*
X1550160Y1270188D03*
Y1274188D03*
X1561031Y1302609D03*
X1585160Y1278988D03*
X1573775Y1271378D03*
X1578188Y1275454D03*
X1585160Y1292988D03*
X1584755Y1298278D03*
X1577890Y1288958D03*
X1590786Y225250D03*
Y214250D03*
Y229250D03*
Y234250D03*
Y239250D03*
Y244250D03*
X1601782Y536344D03*
Y531226D03*
X1591660Y1278988D03*
X1613548Y538723D03*
X1613431Y554664D03*
X1613494Y559092D03*
X1625392Y290742D03*
Y294742D03*
Y298742D03*
Y302742D03*
X1625449Y566803D03*
X1632711Y1432248D03*
X1632686Y1424466D03*
Y1428366D03*
X1632711Y1436148D03*
X1632650Y1448016D03*
X1638483Y381500D03*
X1647593Y414202D03*
X1637816Y1311874D03*
X1659631Y692328D03*
X1654830Y1370514D03*
X1649660Y1440488D03*
X1664237Y1402860D03*
X1669293Y1416678D03*
X1690116Y424694D03*
X1687612Y1370614D03*
X1687791Y1696427D03*
X1695487Y401485D03*
X1697019Y1402960D03*
X1718010Y424340D03*
Y420340D03*
X1735348Y53651D03*
Y57651D03*
X1736101Y89827D03*
X1725401Y116867D03*
X1726317Y656238D03*
X1729946Y1681465D03*
Y1676965D03*
X1743292Y89264D03*
X1746792Y85339D03*
X1742560Y668216D03*
Y664216D03*
X1738928Y1552371D03*
X1763521Y68637D03*
X1764031Y87107D03*
Y83607D03*
X1754070Y364048D03*
Y368048D03*
X1754203Y377452D03*
Y382952D03*
X1771761Y92891D03*
X1781558Y186911D03*
Y194399D03*
X1781614Y197899D03*
X1767910Y368148D03*
X1767703Y372452D03*
X1767910Y364148D03*
X1774671Y1552371D03*
X1775962Y1582405D03*
X1773462Y1577905D03*
X1767906Y1635686D03*
X1770946Y1661465D03*
Y1657465D03*
X1785161Y96927D03*
X1785119Y100939D03*
X1792873Y156834D03*
Y161834D03*
X1783987Y182463D03*
X1794887Y1587105D03*
X1825063Y151834D03*
X1826139Y388051D03*
X1825782Y427432D03*
X1825775Y431678D03*
X1847774Y165834D03*
X1847744Y170287D03*
G54D231*
X789583Y1336044D03*
X791945Y1346280D03*
Y1336044D03*
X909949Y1143551D03*
X912311Y1153787D03*
X909949D03*
X956974Y1143551D03*
X959336Y1153787D03*
X956974D03*
X1319742Y549491D03*
X1322104Y559727D03*
X1319742D03*
X1625867Y549146D03*
X1628229Y559382D03*
X1625867D03*
G54D240*
X845291Y1526035D03*
X853479D03*
X945177Y1464749D03*
X953365D03*
G54D105*
X178582Y1572490D03*
X184382D03*
X172782D03*
X178582D03*
X251487Y92733D03*
X257287D03*
Y97633D03*
X251487D03*
X329886Y598794D03*
X324086D03*
X424100Y1644500D03*
X436100Y1627500D03*
X429900Y1644500D03*
X441900Y1627500D03*
X684643Y96858D03*
X690443D03*
Y101758D03*
X684643D03*
X797536Y1364193D03*
X803336D03*
X1120110Y1580298D03*
X1125910D03*
X1180655Y1605490D03*
X1190107Y182851D03*
X1195907D03*
X1186455Y1605490D03*
D03*
X1192255D03*
X1295078Y157495D03*
X1300878D03*
X1307700Y518723D03*
X1313500D03*
X1614959Y525962D03*
X1620759D03*
X1726608Y94527D03*
X1732408D03*
Y99727D03*
X1726608D03*
G54D150*
X394824Y1634154D03*
X389824D03*
X384824D03*
Y1655020D03*
X389824D03*
X394824D03*
X399824Y1634154D03*
Y1655020D03*
X1440579Y1640337D03*
X1445579D03*
X1450579D03*
X1440579Y1661203D03*
X1450579D03*
X1445579D03*
X1455579Y1640337D03*
Y1661203D03*
G54D30*
X51437Y380803D03*
X49468D03*
Y399799D03*
X51437D03*
X61280Y380803D03*
X59311D03*
X57342D03*
X55374D03*
X53406D03*
Y399799D03*
X55374D03*
X57342D03*
X59311D03*
X61280D03*
G54D213*
X720157Y1335285D03*
Y1361269D03*
X752939Y1335385D03*
Y1361369D03*
X1667890Y1334574D03*
Y1360558D03*
X1700672Y1334674D03*
Y1360658D03*
G54D204*
X663382Y516260D03*
Y523740D03*
X673618Y520000D03*
G54D114*
X260128Y109803D03*
X263671D03*
X267214D03*
X270758D03*
X693284Y113928D03*
X696827D03*
X700370D03*
X703914D03*
X1735249Y110927D03*
X1738792D03*
X1742335D03*
X1745879D03*
G54D132*
X304992Y880671D03*
Y887049D03*
Y893427D03*
Y899805D03*
Y906182D03*
Y912560D03*
Y918938D03*
Y925316D03*
Y931694D03*
Y938072D03*
Y944450D03*
Y950828D03*
Y957206D03*
Y963584D03*
Y969962D03*
Y976340D03*
Y982718D03*
Y989096D03*
Y995474D03*
Y1001852D03*
Y1008230D03*
X319795Y874293D03*
X316094D03*
X312393D03*
X317944Y877482D03*
X314244D03*
X310543D03*
X319795Y880671D03*
X316094D03*
X312393D03*
X308693D03*
X317944Y883860D03*
X314244D03*
X310543D03*
X306842D03*
X319795Y887049D03*
X316094D03*
X312393D03*
X308693D03*
X317944Y890238D03*
X314244D03*
X310543D03*
X306842D03*
X319795Y893427D03*
X316094D03*
X312393D03*
X308693D03*
X317944Y896616D03*
X314244D03*
X310543D03*
X306842D03*
X319795Y899805D03*
X316094D03*
X312393D03*
X308693D03*
X317944Y902994D03*
X314244D03*
X310543D03*
X306842D03*
X319795Y906182D03*
X316094D03*
X312393D03*
X308693D03*
X317944Y909371D03*
X314244D03*
X310543D03*
X306842D03*
X319795Y912560D03*
X316094D03*
X312393D03*
X308693D03*
X317944Y915749D03*
X314244D03*
X310543D03*
X306842D03*
X319795Y918938D03*
X316094D03*
X312393D03*
X308693D03*
X317944Y922127D03*
X314244D03*
X310543D03*
X306842D03*
X319795Y925316D03*
X316094D03*
X312393D03*
X308693D03*
X317944Y928505D03*
X314244D03*
X310543D03*
X306842D03*
X319795Y931694D03*
X316094D03*
X312393D03*
X308693D03*
X317944Y934883D03*
X314244D03*
X310543D03*
X306842D03*
X319795Y938072D03*
X316094D03*
X312393D03*
X308693D03*
X317944Y941261D03*
X314244D03*
X310543D03*
X306842D03*
X319795Y944450D03*
X316094D03*
X312393D03*
X308693D03*
X317944Y947639D03*
X314244D03*
X310543D03*
X306842D03*
X319795Y950828D03*
X316094D03*
X312393D03*
X308693D03*
X317944Y954017D03*
X314244D03*
X310543D03*
X306842D03*
X319795Y957206D03*
X316094D03*
X312393D03*
X308693D03*
X317944Y960395D03*
X314244D03*
X310543D03*
X306842D03*
X319795Y963584D03*
X316094D03*
X312393D03*
X308693D03*
X317944Y966773D03*
X314244D03*
X310543D03*
X306842D03*
X319795Y969962D03*
X316094D03*
X312393D03*
X308693D03*
X317944Y973151D03*
X314244D03*
X310543D03*
X306842D03*
X319795Y976340D03*
X316094D03*
X312393D03*
X308693D03*
X317944Y979529D03*
X314244D03*
X310543D03*
X306842D03*
X319795Y982718D03*
X316094D03*
X312393D03*
X308693D03*
X317944Y985907D03*
X314244D03*
X310543D03*
X306842D03*
X319795Y989096D03*
X316094D03*
X312393D03*
X308693D03*
X317944Y992285D03*
X314244D03*
X310543D03*
X306842D03*
X319795Y995474D03*
X316094D03*
X312393D03*
X308693D03*
X317944Y998663D03*
X314244D03*
X310543D03*
X306842D03*
X319795Y1001852D03*
X316094D03*
X312393D03*
X308693D03*
X317944Y1005041D03*
X314244D03*
X310543D03*
X306842D03*
X319795Y1008230D03*
X316094D03*
X312393D03*
X308693D03*
X317944Y1011419D03*
X314244D03*
X310543D03*
X306842D03*
X319126Y1027009D03*
X315425D03*
X311724D03*
X308023D03*
X320976Y1030198D03*
X317275D03*
X313574D03*
X309874D03*
X306173D03*
X319126Y1033387D03*
X315425D03*
X311724D03*
X308023D03*
X320976Y1036576D03*
X317275D03*
X313574D03*
X309874D03*
X306173D03*
X319126Y1039765D03*
X315425D03*
X311724D03*
X308023D03*
X320976Y1042954D03*
X317275D03*
X313574D03*
X309874D03*
X306173D03*
X319126Y1046143D03*
X315425D03*
X311724D03*
X308023D03*
X320976Y1049332D03*
X317275D03*
X313574D03*
X309874D03*
X306173D03*
X319126Y1052521D03*
X315425D03*
X311724D03*
X308023D03*
X320976Y1055710D03*
X317275D03*
X313574D03*
X309874D03*
X306173D03*
X319126Y1058899D03*
X315425D03*
X311724D03*
X308023D03*
X320976Y1062088D03*
X317275D03*
X313574D03*
X309874D03*
X306173D03*
X319126Y1065277D03*
X315425D03*
X311724D03*
X308023D03*
X320976Y1068466D03*
X317275D03*
X313574D03*
X309874D03*
X306173D03*
X319126Y1071655D03*
X315425D03*
X311724D03*
X308023D03*
X320976Y1074844D03*
X317275D03*
X313574D03*
X309874D03*
X306173D03*
X319126Y1078033D03*
X315425D03*
X311724D03*
X308023D03*
X320976Y1081222D03*
X317275D03*
X313574D03*
X309874D03*
X306173D03*
X319126Y1084411D03*
X315425D03*
X311724D03*
X308023D03*
X320976Y1087600D03*
X317275D03*
X313574D03*
X309874D03*
X306173D03*
X319126Y1090789D03*
X315425D03*
X311724D03*
X308023D03*
X320976Y1093978D03*
X317275D03*
X313574D03*
X309874D03*
X306173D03*
X319126Y1097167D03*
X315425D03*
X311724D03*
X308023D03*
X320976Y1100356D03*
X317275D03*
X313574D03*
X309874D03*
X306173D03*
X319126Y1103545D03*
X315425D03*
X311724D03*
X308023D03*
X320976Y1106734D03*
X317275D03*
X313574D03*
X309874D03*
X306173D03*
X319126Y1109923D03*
X315425D03*
X311724D03*
X308023D03*
X320976Y1113112D03*
X317275D03*
X313574D03*
X309874D03*
X306173D03*
X319126Y1116301D03*
X315425D03*
X311724D03*
X308023D03*
X320976Y1119490D03*
X317275D03*
X313574D03*
X309874D03*
X306173D03*
X319126Y1122679D03*
X315425D03*
X311724D03*
X308023D03*
X320976Y1125868D03*
X317275D03*
X313574D03*
X309874D03*
X306173D03*
X319126Y1129057D03*
X315425D03*
X311724D03*
X308023D03*
X320976Y1132246D03*
X317275D03*
X313574D03*
X309874D03*
X306173D03*
X319126Y1135434D03*
X315425D03*
X311724D03*
X308023D03*
X320976Y1138623D03*
X317275D03*
X313574D03*
X309874D03*
X306173D03*
X319126Y1141812D03*
X315425D03*
X311724D03*
X308023D03*
X320976Y1145001D03*
X317275D03*
X313574D03*
X309874D03*
X306173D03*
X319126Y1148190D03*
X315425D03*
X311724D03*
X308023D03*
X320976Y1151379D03*
X317275D03*
X313574D03*
X309874D03*
X306173D03*
X319126Y1154568D03*
X315425D03*
X311724D03*
X308023D03*
X320976Y1157757D03*
X317275D03*
X313574D03*
X309874D03*
X306173D03*
X319126Y1160946D03*
X315425D03*
X311724D03*
X320976Y1164135D03*
X317275D03*
X313574D03*
X334598Y874293D03*
X330897D03*
X327196D03*
X332748Y877482D03*
X329047D03*
X325346D03*
X321645D03*
X334598Y880671D03*
X330897D03*
X327196D03*
X323496D03*
X332748Y883860D03*
X329047D03*
X325346D03*
X321645D03*
X334598Y887049D03*
X330897D03*
X327196D03*
X323496D03*
X332748Y890238D03*
X329047D03*
X325346D03*
X321645D03*
X334598Y893427D03*
X330897D03*
X327196D03*
X323496D03*
X332748Y896616D03*
X329047D03*
X325346D03*
X321645D03*
X334598Y899805D03*
X330897D03*
X327196D03*
X323496D03*
X332748Y902994D03*
X329047D03*
X325346D03*
X321645D03*
X334598Y906182D03*
X330897D03*
X327196D03*
X323496D03*
X332748Y909371D03*
X329047D03*
X325346D03*
X321645D03*
X334598Y912560D03*
X330897D03*
X327196D03*
X323496D03*
X332748Y915749D03*
X329047D03*
X325346D03*
X321645D03*
X334598Y918938D03*
X330897D03*
X327196D03*
X323496D03*
X332748Y922127D03*
X329047D03*
X325346D03*
X321645D03*
X334598Y925316D03*
X330897D03*
X327196D03*
X323496D03*
X332748Y928505D03*
X329047D03*
X325346D03*
X321645D03*
X334598Y931694D03*
X330897D03*
X327196D03*
X323496D03*
X332748Y934883D03*
X329047D03*
X325346D03*
X321645D03*
X334598Y938072D03*
X330897D03*
X327196D03*
X323496D03*
X332748Y941261D03*
X329047D03*
X325346D03*
X321645D03*
X334598Y944450D03*
X330897D03*
X327196D03*
X323496D03*
X332748Y947639D03*
X329047D03*
X325346D03*
X321645D03*
X334598Y950828D03*
X330897D03*
X327196D03*
X323496D03*
X332748Y954017D03*
X329047D03*
X325346D03*
X321645D03*
X334598Y957206D03*
X330897D03*
X327196D03*
X323496D03*
X332748Y960395D03*
X329047D03*
X325346D03*
X321645D03*
X334598Y963584D03*
X330897D03*
X327196D03*
X323496D03*
X332748Y966773D03*
X329047D03*
X325346D03*
X321645D03*
X334598Y969962D03*
X330897D03*
X327196D03*
X323496D03*
X332748Y973151D03*
X329047D03*
X325346D03*
X321645D03*
X334598Y976340D03*
X330897D03*
X327196D03*
X323496D03*
X332748Y979529D03*
X329047D03*
X325346D03*
X321645D03*
X334598Y982718D03*
X330897D03*
X327196D03*
X323496D03*
X332748Y985907D03*
X329047D03*
X325346D03*
X321645D03*
X334598Y989096D03*
X330897D03*
X327196D03*
X323496D03*
X332748Y992285D03*
X329047D03*
X325346D03*
X321645D03*
X334598Y995474D03*
X330897D03*
X327196D03*
X323496D03*
X332748Y998663D03*
X329047D03*
X325346D03*
X321645D03*
X334598Y1001852D03*
X330897D03*
X327196D03*
X323496D03*
X332748Y1005041D03*
X329047D03*
X325346D03*
X321645D03*
X334598Y1008230D03*
X330897D03*
X327196D03*
X323496D03*
X332748Y1011419D03*
X329047D03*
X325346D03*
X321645D03*
X333929Y1027009D03*
X330228D03*
X326527D03*
X322826D03*
X335779Y1030198D03*
X332078D03*
X328378D03*
X324677D03*
X333929Y1033387D03*
X330228D03*
X326527D03*
X322826D03*
X335779Y1036576D03*
X332078D03*
X328378D03*
X324677D03*
X333929Y1039765D03*
X330228D03*
X326527D03*
X322826D03*
X335779Y1042954D03*
X332078D03*
X328378D03*
X324677D03*
X333929Y1046143D03*
X330228D03*
X326527D03*
X322826D03*
X335779Y1049332D03*
X332078D03*
X328378D03*
X324677D03*
X333929Y1052521D03*
X330228D03*
X326527D03*
X322826D03*
X335779Y1055710D03*
X332078D03*
X328378D03*
X324677D03*
X333929Y1058899D03*
X330228D03*
X326527D03*
X322826D03*
X335779Y1062088D03*
X332078D03*
X328378D03*
X324677D03*
X333929Y1065277D03*
X330228D03*
X326527D03*
X322826D03*
X335779Y1068466D03*
X332078D03*
X328378D03*
X324677D03*
X333929Y1071655D03*
X330228D03*
X326527D03*
X322826D03*
X335779Y1074844D03*
X332078D03*
X328378D03*
X324677D03*
X333929Y1078033D03*
X330228D03*
X326527D03*
X322826D03*
X335779Y1081222D03*
X332078D03*
X328378D03*
X324677D03*
X333929Y1084411D03*
X330228D03*
X326527D03*
X322826D03*
X335779Y1087600D03*
X332078D03*
X328378D03*
X324677D03*
X333929Y1090789D03*
X330228D03*
X326527D03*
X322826D03*
X335779Y1093978D03*
X332078D03*
X328378D03*
X324677D03*
X333929Y1097167D03*
X330228D03*
X326527D03*
X322826D03*
X335779Y1100356D03*
X332078D03*
X328378D03*
X324677D03*
X333929Y1103545D03*
X330228D03*
X326527D03*
X322826D03*
X335779Y1106734D03*
X332078D03*
X328378D03*
X324677D03*
X333929Y1109923D03*
X330228D03*
X326527D03*
X322826D03*
X335779Y1113112D03*
X332078D03*
X328378D03*
X324677D03*
X333929Y1116301D03*
X330228D03*
X326527D03*
X322826D03*
X335779Y1119490D03*
X332078D03*
X328378D03*
X324677D03*
X333929Y1122679D03*
X330228D03*
X326527D03*
X322826D03*
X335779Y1125868D03*
X332078D03*
X328378D03*
X324677D03*
X333929Y1129057D03*
X330228D03*
X326527D03*
X322826D03*
X335779Y1132246D03*
X332078D03*
X328378D03*
X324677D03*
X333929Y1135434D03*
X330228D03*
X326527D03*
X322826D03*
X335779Y1138623D03*
X332078D03*
X328378D03*
X324677D03*
X333929Y1141812D03*
X330228D03*
X326527D03*
X322826D03*
X335779Y1145001D03*
X332078D03*
X328378D03*
X324677D03*
X333929Y1148190D03*
X330228D03*
X326527D03*
X322826D03*
X335779Y1151379D03*
X332078D03*
X328378D03*
X324677D03*
X333929Y1154568D03*
X330228D03*
X326527D03*
X322826D03*
X335779Y1157757D03*
X332078D03*
X328378D03*
X324677D03*
X333929Y1160946D03*
X330228D03*
X326527D03*
X322826D03*
X335779Y1164135D03*
X332078D03*
X328378D03*
X349401Y874293D03*
X342000D03*
X338299D03*
X347551Y877482D03*
X343850D03*
X340149D03*
X336448D03*
X349401Y880671D03*
X345700D03*
X342000D03*
X338299D03*
X347551Y883860D03*
X343850D03*
X340149D03*
X336448D03*
X349401Y887049D03*
X345700D03*
X342000D03*
X338299D03*
X347551Y890238D03*
X343850D03*
X340149D03*
X336448D03*
X349401Y893427D03*
X345700D03*
X342000D03*
X338299D03*
X347551Y896616D03*
X343850D03*
X340149D03*
X336448D03*
X349401Y899805D03*
X345700D03*
X342000D03*
X338299D03*
X347551Y902994D03*
X343850D03*
X340149D03*
X336448D03*
X349401Y906182D03*
X345700D03*
X342000D03*
X338299D03*
X347551Y909371D03*
X343850D03*
X340149D03*
X336448D03*
X349401Y912560D03*
X345700D03*
X342000D03*
X338299D03*
X347551Y915749D03*
X343850D03*
X340149D03*
X336448D03*
X349401Y918938D03*
X345700D03*
X342000D03*
X338299D03*
X347551Y922127D03*
X343850D03*
X340149D03*
X336448D03*
X349401Y925316D03*
X345700D03*
X342000D03*
X338299D03*
X347551Y928505D03*
X343850D03*
X340149D03*
X336448D03*
X349401Y931694D03*
X345700D03*
X342000D03*
X338299D03*
X347551Y934883D03*
X343850D03*
X340149D03*
X336448D03*
X349401Y938072D03*
X345700D03*
X342000D03*
X338299D03*
X347551Y941261D03*
X343850D03*
X340149D03*
X336448D03*
X349401Y944450D03*
X345700D03*
X342000D03*
X338299D03*
X347551Y947639D03*
X343850D03*
X340149D03*
X336448D03*
X349401Y950828D03*
X345700D03*
X342000D03*
X338299D03*
X347551Y954017D03*
X343850D03*
X340149D03*
X336448D03*
X349401Y957206D03*
X345700D03*
X342000D03*
X338299D03*
X347551Y960395D03*
X343850D03*
X340149D03*
X336448D03*
X349401Y963584D03*
X345700D03*
X342000D03*
X338299D03*
X347551Y966773D03*
X343850D03*
X340149D03*
X336448D03*
X349401Y969962D03*
X345700D03*
X342000D03*
X338299D03*
X347551Y973151D03*
X343850D03*
X340149D03*
X336448D03*
X349401Y976340D03*
X345700D03*
X342000D03*
X338299D03*
X347551Y979529D03*
X343850D03*
X340149D03*
X336448D03*
X349401Y982718D03*
X345700D03*
X342000D03*
X338299D03*
X347551Y985907D03*
X343850D03*
X340149D03*
X336448D03*
X349401Y989096D03*
X345700D03*
X342000D03*
X338299D03*
X347551Y992285D03*
X343850D03*
X340149D03*
X336448D03*
X349401Y995474D03*
X345700D03*
X342000D03*
X338299D03*
X347551Y998663D03*
X343850D03*
X340149D03*
X336448D03*
X349401Y1001852D03*
X345700D03*
X342000D03*
X338299D03*
X347551Y1005041D03*
X343850D03*
X340149D03*
X336448D03*
X349401Y1008230D03*
X345700D03*
X342000D03*
X338299D03*
X347551Y1011419D03*
X343850D03*
X340149D03*
X336448D03*
X348732Y1027009D03*
X345031D03*
X341330D03*
X337629D03*
X350582Y1030198D03*
X346881D03*
X343181D03*
X339480D03*
X348732Y1033387D03*
X345031D03*
X341330D03*
X337629D03*
X350582Y1036576D03*
X346881D03*
X343181D03*
X339480D03*
X348732Y1039765D03*
X345031D03*
X341330D03*
X337629D03*
X350582Y1042954D03*
X346881D03*
X343181D03*
X339480D03*
X348732Y1046143D03*
X345031D03*
X341330D03*
X337629D03*
X350582Y1049332D03*
X346881D03*
X343181D03*
X339480D03*
X348732Y1052521D03*
X345031D03*
X341330D03*
X337629D03*
X350582Y1055710D03*
X346881D03*
X343181D03*
X339480D03*
X348732Y1058899D03*
X345031D03*
X341330D03*
X337629D03*
X350582Y1062088D03*
X346881D03*
X343181D03*
X339480D03*
X348732Y1065277D03*
X345031D03*
X341330D03*
X337629D03*
X350582Y1068466D03*
X346881D03*
X343181D03*
X339480D03*
X348732Y1071655D03*
X345031D03*
X341330D03*
X337629D03*
X350582Y1074844D03*
X346881D03*
X343181D03*
X339480D03*
X348732Y1078033D03*
X345031D03*
X341330D03*
X337629D03*
X350582Y1081222D03*
X346881D03*
X343181D03*
X339480D03*
X348732Y1084411D03*
X345031D03*
X341330D03*
X337629D03*
X350582Y1087600D03*
X346881D03*
X343181D03*
X339480D03*
X348732Y1090789D03*
X345031D03*
X341330D03*
X337629D03*
X350582Y1093978D03*
X346881D03*
X343181D03*
X339480D03*
X348732Y1097167D03*
X345031D03*
X341330D03*
X337629D03*
X350582Y1100356D03*
X346881D03*
X343181D03*
X339480D03*
X348732Y1103545D03*
X345031D03*
X341330D03*
X337629D03*
X350582Y1106734D03*
X346881D03*
X343181D03*
X339480D03*
X348732Y1109923D03*
X345031D03*
X341330D03*
X337629D03*
X350582Y1113112D03*
X346881D03*
X343181D03*
X339480D03*
X348732Y1116301D03*
X345031D03*
X341330D03*
X337629D03*
X350582Y1119490D03*
X346881D03*
X343181D03*
X339480D03*
X348732Y1122679D03*
X345031D03*
X341330D03*
X337629D03*
X350582Y1125868D03*
X346881D03*
X343181D03*
X339480D03*
X348732Y1129057D03*
X345031D03*
X341330D03*
X337629D03*
X350582Y1132246D03*
X346881D03*
X343181D03*
X339480D03*
X348732Y1135434D03*
X345031D03*
X341330D03*
X337629D03*
X350582Y1138623D03*
X346881D03*
X343181D03*
X339480D03*
X348732Y1141812D03*
X345031D03*
X341330D03*
X337629D03*
X350582Y1145001D03*
X346881D03*
X343181D03*
X339480D03*
X348732Y1148190D03*
X345031D03*
X341330D03*
X337629D03*
X350582Y1151379D03*
X346881D03*
X343181D03*
X339480D03*
X348732Y1154568D03*
X345031D03*
X341330D03*
X337629D03*
X350582Y1157757D03*
X346881D03*
X343181D03*
X339480D03*
X348732Y1160946D03*
X345031D03*
X341330D03*
X337629D03*
X350582Y1164135D03*
X343181D03*
X339480D03*
X364204Y874293D03*
X360504D03*
X356803D03*
X353102D03*
X362354Y877482D03*
X358653D03*
X354952D03*
X351252D03*
X364204Y880671D03*
X360504D03*
X356803D03*
X353102D03*
X362354Y883860D03*
X358653D03*
X354952D03*
X351252D03*
X364204Y887049D03*
X360504D03*
X356803D03*
X353102D03*
X362354Y890238D03*
X358653D03*
X354952D03*
X351252D03*
X364204Y893427D03*
X360504D03*
X356803D03*
X353102D03*
X362354Y896616D03*
X358653D03*
X354952D03*
X351252D03*
X364204Y899805D03*
X360504D03*
X356803D03*
X353102D03*
X362354Y902994D03*
X358653D03*
X354952D03*
X351252D03*
X364204Y906182D03*
X360504D03*
X356803D03*
X353102D03*
X362354Y909371D03*
X358653D03*
X354952D03*
X351252D03*
X364204Y912560D03*
X360504D03*
X356803D03*
X353102D03*
X362354Y915749D03*
X358653D03*
X354952D03*
X351252D03*
X364204Y918938D03*
X360504D03*
X356803D03*
X353102D03*
X362354Y922127D03*
X358653D03*
X354952D03*
X351252D03*
X364204Y925316D03*
X360504D03*
X356803D03*
X353102D03*
X362354Y928505D03*
X358653D03*
X354952D03*
X351252D03*
X364204Y931694D03*
X360504D03*
X356803D03*
X353102D03*
X362354Y934883D03*
X358653D03*
X354952D03*
X351252D03*
X364204Y938072D03*
X360504D03*
X356803D03*
X353102D03*
X362354Y941261D03*
X358653D03*
X354952D03*
X351252D03*
X364204Y944450D03*
X360504D03*
X356803D03*
X353102D03*
X362354Y947639D03*
X358653D03*
X354952D03*
X351252D03*
X364204Y950828D03*
X360504D03*
X356803D03*
X353102D03*
X362354Y954017D03*
X358653D03*
X354952D03*
X351252D03*
X364204Y957206D03*
X360504D03*
X356803D03*
X353102D03*
X362354Y960395D03*
X358653D03*
X354952D03*
X351252D03*
X364204Y963584D03*
X360504D03*
X356803D03*
X353102D03*
X362354Y966773D03*
X358653D03*
X354952D03*
X351252D03*
X364204Y969962D03*
X360504D03*
X356803D03*
X353102D03*
X362354Y973151D03*
X358653D03*
X354952D03*
X351252D03*
X364204Y976340D03*
X360504D03*
X356803D03*
X353102D03*
X362354Y979529D03*
X358653D03*
X354952D03*
X351252D03*
X364204Y982718D03*
X360504D03*
X356803D03*
X353102D03*
X362354Y985907D03*
X358653D03*
X354952D03*
X351252D03*
X364204Y989096D03*
X360504D03*
X356803D03*
X353102D03*
X362354Y992285D03*
X358653D03*
X354952D03*
X351252D03*
X364204Y995474D03*
X360504D03*
X356803D03*
X353102D03*
X362354Y998663D03*
X358653D03*
X354952D03*
X351252D03*
X364204Y1001852D03*
X360504D03*
X356803D03*
X353102D03*
X362354Y1005041D03*
X358653D03*
X354952D03*
X351252D03*
X364204Y1008230D03*
X360504D03*
X356803D03*
X353102D03*
X362354Y1011419D03*
X358653D03*
X354952D03*
X351252D03*
X363535Y1027009D03*
X359834D03*
X356133D03*
X352433D03*
X365385Y1030198D03*
X361685D03*
X357984D03*
X354283D03*
X363535Y1033387D03*
X359834D03*
X356133D03*
X352433D03*
X365385Y1036576D03*
X361685D03*
X357984D03*
X354283D03*
X363535Y1039765D03*
X359834D03*
X356133D03*
X352433D03*
X365385Y1042954D03*
X361685D03*
X357984D03*
X354283D03*
X363535Y1046143D03*
X359834D03*
X356133D03*
X352433D03*
X365385Y1049332D03*
X361685D03*
X357984D03*
X354283D03*
X363535Y1052521D03*
X359834D03*
X356133D03*
X352433D03*
X365385Y1055710D03*
X361685D03*
X357984D03*
X354283D03*
X363535Y1058899D03*
X359834D03*
X356133D03*
X352433D03*
X365385Y1062088D03*
X361685D03*
X357984D03*
X354283D03*
X363535Y1065277D03*
X359834D03*
X356133D03*
X352433D03*
X365385Y1068466D03*
X361685D03*
X357984D03*
X354283D03*
X363535Y1071655D03*
X359834D03*
X356133D03*
X352433D03*
X365385Y1074844D03*
X361685D03*
X357984D03*
X354283D03*
X363535Y1078033D03*
X359834D03*
X356133D03*
X352433D03*
X365385Y1081222D03*
X361685D03*
X357984D03*
X354283D03*
X363535Y1084411D03*
X359834D03*
X356133D03*
X352433D03*
X365385Y1087600D03*
X361685D03*
X357984D03*
X354283D03*
X363535Y1090789D03*
X359834D03*
X356133D03*
X352433D03*
X365385Y1093978D03*
X361685D03*
X357984D03*
X354283D03*
X363535Y1097167D03*
X359834D03*
X356133D03*
X352433D03*
X365385Y1100356D03*
X361685D03*
X357984D03*
X354283D03*
X363535Y1103545D03*
X359834D03*
X356133D03*
X352433D03*
X365385Y1106734D03*
X361685D03*
X357984D03*
X354283D03*
X363535Y1109923D03*
X359834D03*
X356133D03*
X352433D03*
X365385Y1113112D03*
X361685D03*
X357984D03*
X354283D03*
X363535Y1116301D03*
X359834D03*
X356133D03*
X352433D03*
X365385Y1119490D03*
X361685D03*
X357984D03*
X354283D03*
X363535Y1122679D03*
X359834D03*
X356133D03*
X352433D03*
X365385Y1125868D03*
X361685D03*
X357984D03*
X354283D03*
X363535Y1129057D03*
X359834D03*
X356133D03*
X352433D03*
X365385Y1132246D03*
X361685D03*
X357984D03*
X354283D03*
X363535Y1135434D03*
X359834D03*
X356133D03*
X352433D03*
X365385Y1138623D03*
X361685D03*
X357984D03*
X354283D03*
X363535Y1141812D03*
X359834D03*
X356133D03*
X352433D03*
X365385Y1145001D03*
X361685D03*
X357984D03*
X354283D03*
X363535Y1148190D03*
X359834D03*
X356133D03*
X352433D03*
X365385Y1151379D03*
X361685D03*
X357984D03*
X354283D03*
X363535Y1154568D03*
X359834D03*
X356133D03*
X352433D03*
X365385Y1157757D03*
X361685D03*
X357984D03*
X354283D03*
X363535Y1160946D03*
X359834D03*
X356133D03*
X352433D03*
X365385Y1164135D03*
X361685D03*
X357984D03*
X354283D03*
X379007Y874293D03*
X375307D03*
X371606D03*
X377157Y877482D03*
X373456D03*
X369755D03*
X366055D03*
X379007Y880671D03*
X375307D03*
X371606D03*
X367905D03*
X377157Y883860D03*
X373456D03*
X369755D03*
X366055D03*
X379007Y887049D03*
X375307D03*
X371606D03*
X367905D03*
X377157Y890238D03*
X373456D03*
X369755D03*
X366055D03*
X379007Y893427D03*
X375307D03*
X371606D03*
X367905D03*
X377157Y896616D03*
X373456D03*
X369755D03*
X366055D03*
X379007Y899805D03*
X375307D03*
X371606D03*
X367905D03*
X377157Y902994D03*
X373456D03*
X369755D03*
X366055D03*
X379007Y906182D03*
X375307D03*
X371606D03*
X367905D03*
X377157Y909371D03*
X373456D03*
X369755D03*
X366055D03*
X379007Y912560D03*
X375307D03*
X371606D03*
X367905D03*
X377157Y915749D03*
X373456D03*
X369755D03*
X366055D03*
X379007Y918938D03*
X375307D03*
X371606D03*
X367905D03*
X377157Y922127D03*
X373456D03*
X369755D03*
X366055D03*
X379007Y925316D03*
X375307D03*
X371606D03*
X367905D03*
X377157Y928505D03*
X373456D03*
X369755D03*
X366055D03*
X379007Y931694D03*
X375307D03*
X371606D03*
X367905D03*
X377157Y934883D03*
X373456D03*
X369755D03*
X366055D03*
X379007Y938072D03*
X375307D03*
X371606D03*
X367905D03*
X377157Y941261D03*
X373456D03*
X369755D03*
X366055D03*
X379007Y944450D03*
X375307D03*
X371606D03*
X367905D03*
X377157Y947639D03*
X373456D03*
X369755D03*
X366055D03*
X379007Y950828D03*
X375307D03*
X371606D03*
X367905D03*
X377157Y954017D03*
X373456D03*
X369755D03*
X366055D03*
X379007Y957206D03*
X375307D03*
X371606D03*
X367905D03*
X377157Y960395D03*
X373456D03*
X369755D03*
X366055D03*
X379007Y963584D03*
X375307D03*
X371606D03*
X367905D03*
X377157Y966773D03*
X373456D03*
X369755D03*
X366055D03*
X379007Y969962D03*
X375307D03*
X371606D03*
X367905D03*
X377157Y973151D03*
X373456D03*
X369755D03*
X366055D03*
X379007Y976340D03*
X375307D03*
X371606D03*
X367905D03*
X377157Y979529D03*
X373456D03*
X369755D03*
X366055D03*
X379007Y982718D03*
X375307D03*
X371606D03*
X367905D03*
X377157Y985907D03*
X373456D03*
X369755D03*
X366055D03*
X379007Y989096D03*
X375307D03*
X371606D03*
X367905D03*
X377157Y992285D03*
X373456D03*
X369755D03*
X366055D03*
X379007Y995474D03*
X375307D03*
X371606D03*
X367905D03*
X377157Y998663D03*
X373456D03*
X369755D03*
X366055D03*
X379007Y1001852D03*
X375307D03*
X371606D03*
X367905D03*
X377157Y1005041D03*
X373456D03*
X369755D03*
X366055D03*
X379007Y1008230D03*
X375307D03*
X371606D03*
X367905D03*
X377157Y1011419D03*
X373456D03*
X369755D03*
X366055D03*
X378338Y1027009D03*
X374637D03*
X370937D03*
X367236D03*
X380189Y1030198D03*
X376488D03*
X372787D03*
X369086D03*
X378338Y1033387D03*
X374637D03*
X370937D03*
X367236D03*
X380189Y1036576D03*
X376488D03*
X372787D03*
X369086D03*
X378338Y1039765D03*
X374637D03*
X370937D03*
X367236D03*
X380189Y1042954D03*
X376488D03*
X372787D03*
X369086D03*
X378338Y1046143D03*
X374637D03*
X370937D03*
X367236D03*
X380189Y1049332D03*
X376488D03*
X372787D03*
X369086D03*
X378338Y1052521D03*
X374637D03*
X370937D03*
X367236D03*
X380189Y1055710D03*
X376488D03*
X372787D03*
X369086D03*
X378338Y1058899D03*
X374637D03*
X370937D03*
X367236D03*
X380189Y1062088D03*
X376488D03*
X372787D03*
X369086D03*
X378338Y1065277D03*
X374637D03*
X370937D03*
X367236D03*
X380189Y1068466D03*
X376488D03*
X372787D03*
X369086D03*
X378338Y1071655D03*
X374637D03*
X370937D03*
X367236D03*
X380189Y1074844D03*
X376488D03*
X372787D03*
X369086D03*
X378338Y1078033D03*
X374637D03*
X370937D03*
X367236D03*
X380189Y1081222D03*
X376488D03*
X372787D03*
X369086D03*
X378338Y1084411D03*
X374637D03*
X370937D03*
X367236D03*
X380189Y1087600D03*
X376488D03*
X372787D03*
X369086D03*
X378338Y1090789D03*
X374637D03*
X370937D03*
X367236D03*
X380189Y1093978D03*
X376488D03*
X372787D03*
X369086D03*
X378338Y1097167D03*
X374637D03*
X370937D03*
X367236D03*
X380189Y1100356D03*
X376488D03*
X372787D03*
X369086D03*
X378338Y1103545D03*
X374637D03*
X370937D03*
X367236D03*
X380189Y1106734D03*
X376488D03*
X372787D03*
X369086D03*
X378338Y1109923D03*
X374637D03*
X370937D03*
X367236D03*
X380189Y1113112D03*
X376488D03*
X372787D03*
X369086D03*
X378338Y1116301D03*
X374637D03*
X370937D03*
X367236D03*
X380189Y1119490D03*
X376488D03*
X372787D03*
X369086D03*
X378338Y1122679D03*
X374637D03*
X370937D03*
X367236D03*
X380189Y1125868D03*
X376488D03*
X372787D03*
X369086D03*
X378338Y1129057D03*
X374637D03*
X370937D03*
X367236D03*
X380189Y1132246D03*
X376488D03*
X372787D03*
X369086D03*
X378338Y1135434D03*
X374637D03*
X370937D03*
X367236D03*
X380189Y1138623D03*
X376488D03*
X372787D03*
X369086D03*
X378338Y1141812D03*
X374637D03*
X370937D03*
X367236D03*
X380189Y1145001D03*
X376488D03*
X372787D03*
X369086D03*
X378338Y1148190D03*
X374637D03*
X370937D03*
X367236D03*
X380189Y1151379D03*
X376488D03*
X372787D03*
X369086D03*
X378338Y1154568D03*
X374637D03*
X370937D03*
X367236D03*
X380189Y1157757D03*
X376488D03*
X372787D03*
X369086D03*
X378338Y1160946D03*
X374637D03*
X370937D03*
X367236D03*
X380189Y1164135D03*
X376488D03*
X372787D03*
X393811Y874293D03*
X386409D03*
X382708D03*
X391960Y877482D03*
X388259D03*
X384559D03*
X380858D03*
X393811Y880671D03*
X390110D03*
X386409D03*
X382708D03*
X391960Y883860D03*
X388259D03*
X384559D03*
X380858D03*
X393811Y887049D03*
X390110D03*
X386409D03*
X382708D03*
X391960Y890238D03*
X388259D03*
X384559D03*
X380858D03*
X393811Y893427D03*
X390110D03*
X386409D03*
X382708D03*
X391960Y896616D03*
X388259D03*
X384559D03*
X380858D03*
X393811Y899805D03*
X390110D03*
X386409D03*
X382708D03*
X391960Y902994D03*
X388259D03*
X384559D03*
X380858D03*
X393811Y906182D03*
X390110D03*
X386409D03*
X382708D03*
X391960Y909371D03*
X388259D03*
X384559D03*
X380858D03*
X393811Y912560D03*
X390110D03*
X386409D03*
X382708D03*
X391960Y915749D03*
X388259D03*
X384559D03*
X380858D03*
X393811Y918938D03*
X390110D03*
X386409D03*
X382708D03*
X391960Y922127D03*
X388259D03*
X384559D03*
X380858D03*
X393811Y925316D03*
X390110D03*
X386409D03*
X382708D03*
X391960Y928505D03*
X388259D03*
X384559D03*
X380858D03*
X393811Y931694D03*
X390110D03*
X386409D03*
X382708D03*
X391960Y934883D03*
X388259D03*
X384559D03*
X380858D03*
X393811Y938072D03*
X390110D03*
X386409D03*
X382708D03*
X391960Y941261D03*
X388259D03*
X384559D03*
X380858D03*
X393811Y944450D03*
X390110D03*
X386409D03*
X382708D03*
X391960Y947639D03*
X388259D03*
X384559D03*
X380858D03*
X393811Y950828D03*
X390110D03*
X386409D03*
X382708D03*
X391960Y954017D03*
X388259D03*
X384559D03*
X380858D03*
X393811Y957206D03*
X390110D03*
X386409D03*
X382708D03*
X391960Y960395D03*
X388259D03*
X384559D03*
X380858D03*
X393811Y963584D03*
X390110D03*
X386409D03*
X382708D03*
X391960Y966773D03*
X388259D03*
X384559D03*
X380858D03*
X393811Y969962D03*
X390110D03*
X386409D03*
X382708D03*
X391960Y973151D03*
X388259D03*
X384559D03*
X380858D03*
X393811Y976340D03*
X390110D03*
X386409D03*
X382708D03*
X391960Y979529D03*
X388259D03*
X384559D03*
X380858D03*
X393811Y982718D03*
X390110D03*
X386409D03*
X382708D03*
X391960Y985907D03*
X388259D03*
X384559D03*
X380858D03*
X393811Y989096D03*
X390110D03*
X386409D03*
X382708D03*
X391960Y992285D03*
X388259D03*
X384559D03*
X380858D03*
X393811Y995474D03*
X390110D03*
X386409D03*
X382708D03*
X391960Y998663D03*
X388259D03*
X384559D03*
X380858D03*
X393811Y1001852D03*
X390110D03*
X386409D03*
X382708D03*
X391960Y1005041D03*
X388259D03*
X384559D03*
X380858D03*
X393811Y1008230D03*
X390110D03*
X386409D03*
X382708D03*
X391960Y1011419D03*
X388259D03*
X384559D03*
X380858D03*
X393141Y1027009D03*
X389441D03*
X385740D03*
X382039D03*
X394992Y1030198D03*
X391291D03*
X387590D03*
X383889D03*
X393141Y1033387D03*
X389441D03*
X385740D03*
X382039D03*
X394992Y1036576D03*
X391291D03*
X387590D03*
X383889D03*
X393141Y1039765D03*
X389441D03*
X385740D03*
X382039D03*
X394992Y1042954D03*
X391291D03*
X387590D03*
X383889D03*
X393141Y1046143D03*
X389441D03*
X385740D03*
X382039D03*
X394992Y1049332D03*
X391291D03*
X387590D03*
X383889D03*
X393141Y1052521D03*
X389441D03*
X385740D03*
X382039D03*
X394992Y1055710D03*
X391291D03*
X387590D03*
X383889D03*
X393141Y1058899D03*
X389441D03*
X385740D03*
X382039D03*
X394992Y1062088D03*
X391291D03*
X387590D03*
X383889D03*
X393141Y1065277D03*
X389441D03*
X385740D03*
X382039D03*
X394992Y1068466D03*
X391291D03*
X387590D03*
X383889D03*
X393141Y1071655D03*
X389441D03*
X385740D03*
X382039D03*
X394992Y1074844D03*
X391291D03*
X387590D03*
X383889D03*
X393141Y1078033D03*
X389441D03*
X385740D03*
X382039D03*
X394992Y1081222D03*
X391291D03*
X387590D03*
X383889D03*
X393141Y1084411D03*
X389441D03*
X385740D03*
X382039D03*
X394992Y1087600D03*
X391291D03*
X387590D03*
X383889D03*
X393141Y1090789D03*
X389441D03*
X385740D03*
X382039D03*
X394992Y1093978D03*
X391291D03*
X387590D03*
X383889D03*
X393141Y1097167D03*
X389441D03*
X385740D03*
X382039D03*
X394992Y1100356D03*
X391291D03*
X387590D03*
X383889D03*
X393141Y1103545D03*
X389441D03*
X385740D03*
X382039D03*
X394992Y1106734D03*
X391291D03*
X387590D03*
X383889D03*
X393141Y1109923D03*
X389441D03*
X385740D03*
X382039D03*
X394992Y1113112D03*
X391291D03*
X387590D03*
X383889D03*
X393141Y1116301D03*
X389441D03*
X385740D03*
X382039D03*
X394992Y1119490D03*
X391291D03*
X387590D03*
X383889D03*
X393141Y1122679D03*
X389441D03*
X385740D03*
X382039D03*
X394992Y1125868D03*
X391291D03*
X387590D03*
X383889D03*
X393141Y1129057D03*
X389441D03*
X385740D03*
X382039D03*
X394992Y1132246D03*
X391291D03*
X387590D03*
X383889D03*
X393141Y1135434D03*
X389441D03*
X385740D03*
X382039D03*
X394992Y1138623D03*
X391291D03*
X387590D03*
X383889D03*
X393141Y1141812D03*
X389441D03*
X385740D03*
X382039D03*
X394992Y1145001D03*
X391291D03*
X387590D03*
X383889D03*
X393141Y1148190D03*
X389441D03*
X385740D03*
X382039D03*
X394992Y1151379D03*
X391291D03*
X387590D03*
X383889D03*
X393141Y1154568D03*
X389441D03*
X385740D03*
X382039D03*
X394992Y1157757D03*
X391291D03*
X387590D03*
X383889D03*
X393141Y1160946D03*
X389441D03*
X385740D03*
X382039D03*
X394992Y1164135D03*
X387590D03*
X383889D03*
X408614Y874293D03*
X404913D03*
X401212D03*
X397511D03*
X410464Y877482D03*
X406763D03*
X403063D03*
X399362D03*
X395661D03*
X408614Y880671D03*
X404913D03*
X401212D03*
X397511D03*
X410464Y883860D03*
X406763D03*
X403063D03*
X399362D03*
X395661D03*
X408614Y887049D03*
X404913D03*
X401212D03*
X397511D03*
X410464Y890238D03*
X406763D03*
X403063D03*
X399362D03*
X395661D03*
X408614Y893427D03*
X404913D03*
X401212D03*
X397511D03*
X410464Y896616D03*
X406763D03*
X403063D03*
X399362D03*
X395661D03*
X408614Y899805D03*
X404913D03*
X401212D03*
X397511D03*
X410464Y902994D03*
X406763D03*
X403063D03*
X399362D03*
X395661D03*
X408614Y906182D03*
X404913D03*
X401212D03*
X397511D03*
X410464Y909371D03*
X406763D03*
X403063D03*
X399362D03*
X395661D03*
X408614Y912560D03*
X404913D03*
X401212D03*
X397511D03*
X410464Y915749D03*
X406763D03*
X403063D03*
X399362D03*
X395661D03*
X408614Y918938D03*
X404913D03*
X401212D03*
X397511D03*
X410464Y922127D03*
X406763D03*
X403063D03*
X399362D03*
X395661D03*
X408614Y925316D03*
X404913D03*
X401212D03*
X397511D03*
X410464Y928505D03*
X406763D03*
X403063D03*
X399362D03*
X395661D03*
X408614Y931694D03*
X404913D03*
X401212D03*
X397511D03*
X410464Y934883D03*
X406763D03*
X403063D03*
X399362D03*
X395661D03*
X408614Y938072D03*
X404913D03*
X401212D03*
X397511D03*
X410464Y941261D03*
X406763D03*
X403063D03*
X399362D03*
X395661D03*
X408614Y944450D03*
X404913D03*
X401212D03*
X397511D03*
X410464Y947639D03*
X406763D03*
X403063D03*
X399362D03*
X395661D03*
X408614Y950828D03*
X404913D03*
X401212D03*
X397511D03*
X410464Y954017D03*
X406763D03*
X403063D03*
X399362D03*
X395661D03*
X408614Y957206D03*
X404913D03*
X401212D03*
X397511D03*
X410464Y960395D03*
X406763D03*
X403063D03*
X399362D03*
X395661D03*
X408614Y963584D03*
X404913D03*
X401212D03*
X397511D03*
X410464Y966773D03*
X406763D03*
X403063D03*
X399362D03*
X395661D03*
X408614Y969962D03*
X404913D03*
X401212D03*
X397511D03*
X410464Y973151D03*
X406763D03*
X403063D03*
X399362D03*
X395661D03*
X408614Y976340D03*
X404913D03*
X401212D03*
X397511D03*
X410464Y979529D03*
X406763D03*
X403063D03*
X399362D03*
X395661D03*
X408614Y982718D03*
X404913D03*
X401212D03*
X397511D03*
X410464Y985907D03*
X406763D03*
X403063D03*
X399362D03*
X395661D03*
X408614Y989096D03*
X404913D03*
X401212D03*
X397511D03*
X410464Y992285D03*
X406763D03*
X403063D03*
X399362D03*
X395661D03*
X404913Y995474D03*
X401212D03*
X397511D03*
X403063Y998663D03*
X399362D03*
X395661D03*
X404913Y1001852D03*
X401212D03*
X397511D03*
X403063Y1005041D03*
X399362D03*
X395661D03*
X404913Y1008230D03*
X401212D03*
X397511D03*
X403063Y1011419D03*
X399362D03*
X395661D03*
X404244Y1027009D03*
X400543D03*
X396842D03*
X406094Y1030198D03*
X402393D03*
X398693D03*
X404244Y1033387D03*
X400543D03*
X396842D03*
X406094Y1036576D03*
X402393D03*
X398693D03*
X404244Y1039765D03*
X400543D03*
X396842D03*
X406094Y1042954D03*
X402393D03*
X398693D03*
X407944Y1046143D03*
X404244D03*
X400543D03*
X396842D03*
X409795Y1049332D03*
X406094D03*
X402393D03*
X398693D03*
X407944Y1052521D03*
X404244D03*
X400543D03*
X396842D03*
X409795Y1055710D03*
X406094D03*
X402393D03*
X398693D03*
X407944Y1058899D03*
X404244D03*
X400543D03*
X396842D03*
X409795Y1062088D03*
X406094D03*
X402393D03*
X398693D03*
X407944Y1065277D03*
X404244D03*
X400543D03*
X396842D03*
X409795Y1068466D03*
X406094D03*
X402393D03*
X398693D03*
X407944Y1071655D03*
X404244D03*
X400543D03*
X396842D03*
X409795Y1074844D03*
X406094D03*
X402393D03*
X398693D03*
X407944Y1078033D03*
X404244D03*
X400543D03*
X396842D03*
X409795Y1081222D03*
X406094D03*
X402393D03*
X398693D03*
X407944Y1084411D03*
X404244D03*
X400543D03*
X396842D03*
X409795Y1087600D03*
X406094D03*
X402393D03*
X398693D03*
X407944Y1090789D03*
X404244D03*
X400543D03*
X396842D03*
X409795Y1093978D03*
X406094D03*
X402393D03*
X398693D03*
X407944Y1097167D03*
X404244D03*
X400543D03*
X396842D03*
X409795Y1100356D03*
X406094D03*
X402393D03*
X398693D03*
X407944Y1103545D03*
X404244D03*
X400543D03*
X396842D03*
X409795Y1106734D03*
X406094D03*
X402393D03*
X398693D03*
X407944Y1109923D03*
X404244D03*
X400543D03*
X396842D03*
X409795Y1113112D03*
X406094D03*
X402393D03*
X398693D03*
X407944Y1116301D03*
X404244D03*
X400543D03*
X396842D03*
X409795Y1119490D03*
X406094D03*
X402393D03*
X398693D03*
X407944Y1122679D03*
X404244D03*
X400543D03*
X396842D03*
X409795Y1125868D03*
X406094D03*
X402393D03*
X398693D03*
X407944Y1129057D03*
X404244D03*
X400543D03*
X396842D03*
X409795Y1132246D03*
X406094D03*
X402393D03*
X398693D03*
X407944Y1135434D03*
X404244D03*
X400543D03*
X396842D03*
X409795Y1138623D03*
X406094D03*
X402393D03*
X398693D03*
X407944Y1141812D03*
X404244D03*
X400543D03*
X396842D03*
X409795Y1145001D03*
X406094D03*
X402393D03*
X398693D03*
X407944Y1148190D03*
X404244D03*
X400543D03*
X396842D03*
X409795Y1151379D03*
X406094D03*
X402393D03*
X398693D03*
X407944Y1154568D03*
X404244D03*
X400543D03*
X396842D03*
X409795Y1157757D03*
X406094D03*
X402393D03*
X398693D03*
X407944Y1160946D03*
X404244D03*
X400543D03*
X396842D03*
X409795Y1164135D03*
X406094D03*
X402393D03*
X398693D03*
X423417Y874293D03*
X419716D03*
X416015D03*
X425267Y877482D03*
X421567D03*
X417866D03*
X414165D03*
X423417Y880671D03*
X419716D03*
X416015D03*
X412315D03*
X425267Y883860D03*
X421567D03*
X417866D03*
X414165D03*
X423417Y887049D03*
X419716D03*
X416015D03*
X412315D03*
X425267Y890238D03*
X421567D03*
X417866D03*
X414165D03*
X423417Y893427D03*
X419716D03*
X416015D03*
X412315D03*
X425267Y896616D03*
X421567D03*
X417866D03*
X414165D03*
X423417Y899805D03*
X419716D03*
X416015D03*
X412315D03*
X425267Y902994D03*
X421567D03*
X417866D03*
X414165D03*
X423417Y906182D03*
X419716D03*
X416015D03*
X412315D03*
X425267Y909371D03*
X421567D03*
X417866D03*
X414165D03*
X423417Y912560D03*
X419716D03*
X416015D03*
X412315D03*
X425267Y915749D03*
X421567D03*
X417866D03*
X414165D03*
X423417Y918938D03*
X419716D03*
X416015D03*
X412315D03*
X425267Y922127D03*
X421567D03*
X417866D03*
X414165D03*
X423417Y925316D03*
X419716D03*
X416015D03*
X412315D03*
X425267Y928505D03*
X421567D03*
X417866D03*
X414165D03*
X423417Y931694D03*
X419716D03*
X416015D03*
X412315D03*
X425267Y934883D03*
X421567D03*
X417866D03*
X414165D03*
X423417Y938072D03*
X419716D03*
X416015D03*
X412315D03*
X425267Y941261D03*
X421567D03*
X417866D03*
X414165D03*
X423417Y944450D03*
X419716D03*
X416015D03*
X412315D03*
X425267Y947639D03*
X421567D03*
X417866D03*
X414165D03*
X423417Y950828D03*
X419716D03*
X416015D03*
X412315D03*
X425267Y954017D03*
X421567D03*
X417866D03*
X414165D03*
X423417Y957206D03*
X419716D03*
X416015D03*
X412315D03*
X425267Y960395D03*
X421567D03*
X417866D03*
X414165D03*
X423417Y963584D03*
X419716D03*
X416015D03*
X412315D03*
X425267Y966773D03*
X421567D03*
X417866D03*
X414165D03*
X423417Y969962D03*
X419716D03*
X416015D03*
X412315D03*
X425267Y973151D03*
X421567D03*
X417866D03*
X414165D03*
X423417Y976340D03*
X419716D03*
X416015D03*
X412315D03*
X425267Y979529D03*
X421567D03*
X417866D03*
X414165D03*
X423417Y982718D03*
X419716D03*
X416015D03*
X412315D03*
X425267Y985907D03*
X421567D03*
X417866D03*
X414165D03*
X423417Y989096D03*
X419716D03*
X416015D03*
X412315D03*
X425267Y992285D03*
X421567D03*
X417866D03*
X414165D03*
X422748Y1046143D03*
X419047D03*
X415346D03*
X411645D03*
X424598Y1049332D03*
X420897D03*
X417196D03*
X413496D03*
X422748Y1052521D03*
X419047D03*
X415346D03*
X411645D03*
X424598Y1055710D03*
X420897D03*
X417196D03*
X413496D03*
X422748Y1058899D03*
X419047D03*
X415346D03*
X411645D03*
X424598Y1062088D03*
X420897D03*
X417196D03*
X413496D03*
X422748Y1065277D03*
X419047D03*
X415346D03*
X411645D03*
X424598Y1068466D03*
X420897D03*
X417196D03*
X413496D03*
X422748Y1071655D03*
X419047D03*
X415346D03*
X411645D03*
X424598Y1074844D03*
X420897D03*
X417196D03*
X413496D03*
X422748Y1078033D03*
X419047D03*
X415346D03*
X411645D03*
X424598Y1081222D03*
X420897D03*
X417196D03*
X413496D03*
X422748Y1084411D03*
X419047D03*
X415346D03*
X411645D03*
X424598Y1087600D03*
X420897D03*
X417196D03*
X413496D03*
X422748Y1090789D03*
X419047D03*
X415346D03*
X411645D03*
X424598Y1093978D03*
X420897D03*
X417196D03*
X413496D03*
X422748Y1097167D03*
X419047D03*
X415346D03*
X411645D03*
X424598Y1100356D03*
X420897D03*
X417196D03*
X413496D03*
X422748Y1103545D03*
X419047D03*
X415346D03*
X411645D03*
X424598Y1106734D03*
X420897D03*
X417196D03*
X413496D03*
X422748Y1109923D03*
X419047D03*
X415346D03*
X411645D03*
X424598Y1113112D03*
X420897D03*
X417196D03*
X413496D03*
X422748Y1116301D03*
X419047D03*
X415346D03*
X411645D03*
X424598Y1119490D03*
X420897D03*
X417196D03*
X413496D03*
X422748Y1122679D03*
X419047D03*
X415346D03*
X411645D03*
X424598Y1125868D03*
X420897D03*
X417196D03*
X413496D03*
X422748Y1129057D03*
X419047D03*
X415346D03*
X411645D03*
X424598Y1132246D03*
X420897D03*
X417196D03*
X413496D03*
X422748Y1135434D03*
X419047D03*
X415346D03*
X411645D03*
X424598Y1138623D03*
X420897D03*
X417196D03*
X413496D03*
X422748Y1141812D03*
X419047D03*
X415346D03*
X411645D03*
X424598Y1145001D03*
X420897D03*
X417196D03*
X413496D03*
X422748Y1148190D03*
X419047D03*
X415346D03*
X411645D03*
X424598Y1151379D03*
X420897D03*
X417196D03*
X413496D03*
X422748Y1154568D03*
X419047D03*
X415346D03*
X411645D03*
X424598Y1157757D03*
X420897D03*
X417196D03*
X413496D03*
X422748Y1160946D03*
X419047D03*
X415346D03*
X411645D03*
X424598Y1164135D03*
X420897D03*
X417196D03*
X430818Y874293D03*
X427118D03*
X436370Y877482D03*
X432669D03*
X428968D03*
X434519Y880671D03*
X430818D03*
X427118D03*
X436370Y883860D03*
X432669D03*
X428968D03*
X434519Y887049D03*
X430818D03*
X427118D03*
X436370Y890238D03*
X432669D03*
X428968D03*
X434519Y893427D03*
X430818D03*
X427118D03*
X436370Y896616D03*
X432669D03*
X428968D03*
X434519Y899805D03*
X430818D03*
X427118D03*
X436370Y902994D03*
X432669D03*
X428968D03*
X434519Y906182D03*
X430818D03*
X427118D03*
X436370Y909371D03*
X432669D03*
X428968D03*
X434519Y912560D03*
X430818D03*
X427118D03*
X436370Y915749D03*
X432669D03*
X428968D03*
X434519Y918938D03*
X430818D03*
X427118D03*
X436370Y922127D03*
X432669D03*
X428968D03*
X434519Y925316D03*
X430818D03*
X427118D03*
X436370Y928505D03*
X432669D03*
X428968D03*
X434519Y931694D03*
X430818D03*
X427118D03*
X436370Y934883D03*
X432669D03*
X428968D03*
X434519Y938072D03*
X430818D03*
X427118D03*
X436370Y941261D03*
X432669D03*
X428968D03*
X434519Y944450D03*
X430818D03*
X427118D03*
X436370Y947639D03*
X432669D03*
X428968D03*
X434519Y950828D03*
X430818D03*
X427118D03*
X436370Y954017D03*
X432669D03*
X428968D03*
X434519Y957206D03*
X430818D03*
X427118D03*
X436370Y960395D03*
X432669D03*
X428968D03*
X434519Y963584D03*
X430818D03*
X427118D03*
X436370Y966773D03*
X432669D03*
X428968D03*
X434519Y969962D03*
X430818D03*
X427118D03*
X436370Y973151D03*
X432669D03*
X428968D03*
X434519Y976340D03*
X430818D03*
X427118D03*
X436370Y979529D03*
X432669D03*
X428968D03*
X434519Y982718D03*
X430818D03*
X427118D03*
X436370Y985907D03*
X432669D03*
X428968D03*
X434519Y989096D03*
X430818D03*
X427118D03*
X436370Y992285D03*
X432669D03*
X428968D03*
X437551Y1046143D03*
X433850D03*
X430149D03*
X426448D03*
X435700Y1049332D03*
X432000D03*
X428299D03*
X437551Y1052521D03*
X433850D03*
X430149D03*
X426448D03*
X435700Y1055710D03*
X432000D03*
X428299D03*
X437551Y1058899D03*
X433850D03*
X430149D03*
X426448D03*
X435700Y1062088D03*
X432000D03*
X428299D03*
X437551Y1065277D03*
X433850D03*
X430149D03*
X426448D03*
X435700Y1068466D03*
X432000D03*
X428299D03*
X437551Y1071655D03*
X433850D03*
X430149D03*
X426448D03*
X435700Y1074844D03*
X432000D03*
X428299D03*
X437551Y1078033D03*
X433850D03*
X430149D03*
X426448D03*
X435700Y1081222D03*
X432000D03*
X428299D03*
X437551Y1084411D03*
X433850D03*
X430149D03*
X426448D03*
X435700Y1087600D03*
X432000D03*
X428299D03*
X437551Y1090789D03*
X433850D03*
X430149D03*
X426448D03*
X435700Y1093978D03*
X432000D03*
X428299D03*
X437551Y1097167D03*
X433850D03*
X430149D03*
X426448D03*
X435700Y1100356D03*
X432000D03*
X428299D03*
X437551Y1103545D03*
X433850D03*
X430149D03*
X426448D03*
X435700Y1106734D03*
X432000D03*
X428299D03*
X437551Y1109923D03*
X433850D03*
X430149D03*
X426448D03*
X435700Y1113112D03*
X432000D03*
X428299D03*
X437551Y1116301D03*
X433850D03*
X430149D03*
X426448D03*
X435700Y1119490D03*
X432000D03*
X428299D03*
X437551Y1122679D03*
X433850D03*
X430149D03*
X426448D03*
X435700Y1125868D03*
X432000D03*
X428299D03*
X437551Y1129057D03*
X433850D03*
X430149D03*
X426448D03*
X435700Y1132246D03*
X432000D03*
X428299D03*
X437551Y1135434D03*
X433850D03*
X430149D03*
X426448D03*
X435700Y1138623D03*
X432000D03*
X428299D03*
X437551Y1141812D03*
X433850D03*
X430149D03*
X426448D03*
X435700Y1145001D03*
X432000D03*
X428299D03*
X437551Y1148190D03*
X433850D03*
X430149D03*
X426448D03*
X435700Y1151379D03*
X432000D03*
X428299D03*
X437551Y1154568D03*
X433850D03*
X430149D03*
X426448D03*
X435700Y1157757D03*
X432000D03*
X428299D03*
X437551Y1160946D03*
X433850D03*
X430149D03*
X426448D03*
X432000Y1164135D03*
X428299D03*
X453023Y874293D03*
X449322D03*
X454874Y877482D03*
X451173D03*
X447472D03*
X443771D03*
X453023Y880671D03*
X449322D03*
X445622D03*
X454874Y883860D03*
X451173D03*
X447472D03*
X443771D03*
X453023Y887049D03*
X449322D03*
X445622D03*
X454874Y890238D03*
X451173D03*
X447472D03*
X443771D03*
X453023Y893427D03*
X449322D03*
X445622D03*
X454874Y896616D03*
X451173D03*
X447472D03*
X443771D03*
X453023Y899805D03*
X449322D03*
X445622D03*
X454874Y902994D03*
X451173D03*
X447472D03*
X443771D03*
X453023Y906182D03*
X449322D03*
X445622D03*
X454874Y909371D03*
X451173D03*
X447472D03*
X443771D03*
X453023Y912560D03*
X449322D03*
X445622D03*
X454874Y915749D03*
X451173D03*
X447472D03*
X443771D03*
X453023Y918938D03*
X449322D03*
X445622D03*
X454874Y922127D03*
X451173D03*
X447472D03*
X443771D03*
X453023Y925316D03*
X449322D03*
X445622D03*
X454874Y928505D03*
X451173D03*
X447472D03*
X443771D03*
X453023Y931694D03*
X449322D03*
X445622D03*
X454874Y934883D03*
X451173D03*
X447472D03*
X443771D03*
X453023Y938072D03*
X449322D03*
X445622D03*
X454874Y941261D03*
X451173D03*
X447472D03*
X443771D03*
X453023Y944450D03*
X449322D03*
X445622D03*
X454874Y947639D03*
X451173D03*
X447472D03*
X443771D03*
X453023Y950828D03*
X449322D03*
X445622D03*
X454874Y954017D03*
X451173D03*
X447472D03*
X443771D03*
X453023Y957206D03*
X449322D03*
X445622D03*
X454874Y960395D03*
X451173D03*
X447472D03*
X443771D03*
X453023Y963584D03*
X449322D03*
X445622D03*
X454874Y966773D03*
X451173D03*
X447472D03*
X443771D03*
X453023Y969962D03*
X449322D03*
X445622D03*
X454874Y973151D03*
X451173D03*
X447472D03*
X443771D03*
X453023Y976340D03*
X449322D03*
X445622D03*
X454874Y979529D03*
X451173D03*
X447472D03*
X443771D03*
X453023Y982718D03*
X449322D03*
X445622D03*
X454874Y985907D03*
X451173D03*
X447472D03*
X443771D03*
X453023Y989096D03*
X449322D03*
X445622D03*
X454874Y992285D03*
X451173D03*
X447472D03*
X443771D03*
X452354Y1046143D03*
X448653D03*
X444952D03*
X454204Y1049332D03*
X450504D03*
X446803D03*
X452354Y1052521D03*
X448653D03*
X444952D03*
X454204Y1055710D03*
X450504D03*
X446803D03*
X452354Y1058899D03*
X448653D03*
X444952D03*
X454204Y1062088D03*
X450504D03*
X446803D03*
X452354Y1065277D03*
X448653D03*
X444952D03*
X454204Y1068466D03*
X450504D03*
X446803D03*
X452354Y1071655D03*
X448653D03*
X444952D03*
X454204Y1074844D03*
X450504D03*
X446803D03*
X452354Y1078033D03*
X448653D03*
X444952D03*
X454204Y1081222D03*
X450504D03*
X446803D03*
X452354Y1084411D03*
X448653D03*
X444952D03*
X454204Y1087600D03*
X450504D03*
X446803D03*
X452354Y1090789D03*
X448653D03*
X444952D03*
X454204Y1093978D03*
X450504D03*
X446803D03*
X452354Y1097167D03*
X448653D03*
X444952D03*
X454204Y1100356D03*
X450504D03*
X446803D03*
X452354Y1103545D03*
X448653D03*
X444952D03*
X454204Y1106734D03*
X450504D03*
X446803D03*
X452354Y1109923D03*
X448653D03*
X444952D03*
X454204Y1113112D03*
X450504D03*
X446803D03*
X452354Y1116301D03*
X448653D03*
X444952D03*
X454204Y1119490D03*
X450504D03*
X446803D03*
X452354Y1122679D03*
X448653D03*
X444952D03*
X454204Y1125868D03*
X450504D03*
X446803D03*
X452354Y1129057D03*
X448653D03*
X444952D03*
X454204Y1132246D03*
X450504D03*
X446803D03*
X452354Y1135434D03*
X448653D03*
X444952D03*
X454204Y1138623D03*
X450504D03*
X446803D03*
X452354Y1141812D03*
X448653D03*
X444952D03*
X454204Y1145001D03*
X450504D03*
X446803D03*
X452354Y1148190D03*
X448653D03*
X444952D03*
X454204Y1151379D03*
X450504D03*
X446803D03*
X452354Y1154568D03*
X448653D03*
X444952D03*
X454204Y1157757D03*
X450504D03*
X446803D03*
X452354Y1160946D03*
X448653D03*
X444952D03*
X454204Y1164135D03*
X450504D03*
X464126Y874293D03*
X460425D03*
X456724D03*
X469677Y877482D03*
X465976D03*
X462275D03*
X458574D03*
X467826Y880671D03*
X464126D03*
X460425D03*
X456724D03*
X469677Y883860D03*
X465976D03*
X462275D03*
X458574D03*
X467826Y887049D03*
X464126D03*
X460425D03*
X456724D03*
X469677Y890238D03*
X465976D03*
X462275D03*
X458574D03*
X467826Y893427D03*
X464126D03*
X460425D03*
X456724D03*
X469677Y896616D03*
X465976D03*
X462275D03*
X458574D03*
X467826Y899805D03*
X464126D03*
X460425D03*
X456724D03*
X469677Y902994D03*
X465976D03*
X462275D03*
X458574D03*
X467826Y906182D03*
X464126D03*
X460425D03*
X456724D03*
X469677Y909371D03*
X465976D03*
X462275D03*
X458574D03*
X467826Y912560D03*
X464126D03*
X460425D03*
X456724D03*
X469677Y915749D03*
X465976D03*
X462275D03*
X458574D03*
X467826Y918938D03*
X464126D03*
X460425D03*
X456724D03*
X469677Y922127D03*
X465976D03*
X462275D03*
X458574D03*
X467826Y925316D03*
X464126D03*
X460425D03*
X456724D03*
X469677Y928505D03*
X465976D03*
X462275D03*
X458574D03*
X467826Y931694D03*
X464126D03*
X460425D03*
X456724D03*
X469677Y934883D03*
X465976D03*
X462275D03*
X458574D03*
X467826Y938072D03*
X464126D03*
X460425D03*
X456724D03*
X469677Y941261D03*
X465976D03*
X462275D03*
X458574D03*
X467826Y944450D03*
X464126D03*
X460425D03*
X456724D03*
X469677Y947639D03*
X465976D03*
X462275D03*
X458574D03*
X467826Y950828D03*
X464126D03*
X460425D03*
X456724D03*
X469677Y954017D03*
X465976D03*
X462275D03*
X458574D03*
X467826Y957206D03*
X464126D03*
X460425D03*
X456724D03*
X469677Y960395D03*
X465976D03*
X462275D03*
X458574D03*
X467826Y963584D03*
X464126D03*
X460425D03*
X456724D03*
X469677Y966773D03*
X465976D03*
X462275D03*
X458574D03*
X467826Y969962D03*
X464126D03*
X460425D03*
X456724D03*
X469677Y973151D03*
X465976D03*
X462275D03*
X458574D03*
X467826Y976340D03*
X464126D03*
X460425D03*
X456724D03*
X469677Y979529D03*
X465976D03*
X462275D03*
X458574D03*
X467826Y982718D03*
X464126D03*
X460425D03*
X456724D03*
X469677Y985907D03*
X465976D03*
X462275D03*
X458574D03*
X467826Y989096D03*
X464126D03*
X460425D03*
X456724D03*
X469677Y992285D03*
X465976D03*
X462275D03*
X458574D03*
X467157Y1046143D03*
X463456D03*
X459755D03*
X456055D03*
X469007Y1049332D03*
X465307D03*
X461606D03*
X457905D03*
X467157Y1052521D03*
X463456D03*
X459755D03*
X456055D03*
X469007Y1055710D03*
X465307D03*
X461606D03*
X457905D03*
X467157Y1058899D03*
X463456D03*
X459755D03*
X456055D03*
X469007Y1062088D03*
X465307D03*
X461606D03*
X457905D03*
X467157Y1065277D03*
X463456D03*
X459755D03*
X456055D03*
X469007Y1068466D03*
X465307D03*
X461606D03*
X457905D03*
X467157Y1071655D03*
X463456D03*
X459755D03*
X456055D03*
X469007Y1074844D03*
X465307D03*
X461606D03*
X457905D03*
X467157Y1078033D03*
X463456D03*
X459755D03*
X456055D03*
X469007Y1081222D03*
X465307D03*
X461606D03*
X457905D03*
X467157Y1084411D03*
X463456D03*
X459755D03*
X456055D03*
X469007Y1087600D03*
X465307D03*
X461606D03*
X457905D03*
X467157Y1090789D03*
X463456D03*
X459755D03*
X456055D03*
X469007Y1093978D03*
X465307D03*
X461606D03*
X457905D03*
X467157Y1097167D03*
X463456D03*
X459755D03*
X456055D03*
X469007Y1100356D03*
X465307D03*
X461606D03*
X457905D03*
X467157Y1103545D03*
X463456D03*
X459755D03*
X456055D03*
X469007Y1106734D03*
X465307D03*
X461606D03*
X457905D03*
X467157Y1109923D03*
X463456D03*
X459755D03*
X456055D03*
X469007Y1113112D03*
X465307D03*
X461606D03*
X457905D03*
X467157Y1116301D03*
X463456D03*
X459755D03*
X456055D03*
X469007Y1119490D03*
X465307D03*
X461606D03*
X457905D03*
X467157Y1122679D03*
X463456D03*
X459755D03*
X456055D03*
X469007Y1125868D03*
X465307D03*
X461606D03*
X457905D03*
X467157Y1129057D03*
X463456D03*
X459755D03*
X456055D03*
X469007Y1132246D03*
X465307D03*
X461606D03*
X457905D03*
X467157Y1135434D03*
X463456D03*
X459755D03*
X456055D03*
X469007Y1138623D03*
X465307D03*
X461606D03*
X457905D03*
X467157Y1141812D03*
X463456D03*
X459755D03*
X456055D03*
X469007Y1145001D03*
X465307D03*
X461606D03*
X457905D03*
X467157Y1148190D03*
X463456D03*
X459755D03*
X456055D03*
X469007Y1151379D03*
X465307D03*
X461606D03*
X457905D03*
X467157Y1154568D03*
X463456D03*
X459755D03*
X456055D03*
X469007Y1157757D03*
X465307D03*
X461606D03*
X457905D03*
X467157Y1160946D03*
X463456D03*
X459755D03*
X456055D03*
X465307Y1164135D03*
X461606D03*
X457905D03*
X482629Y874293D03*
X478929D03*
X475228D03*
X471527D03*
X484480Y877482D03*
X480779D03*
X477078D03*
X473378D03*
X482629Y880671D03*
X478929D03*
X475228D03*
X471527D03*
X484480Y883860D03*
X480779D03*
X477078D03*
X473378D03*
X482629Y887049D03*
X478929D03*
X475228D03*
X471527D03*
X484480Y890238D03*
X480779D03*
X477078D03*
X473378D03*
X482629Y893427D03*
X478929D03*
X475228D03*
X471527D03*
X484480Y896616D03*
X480779D03*
X477078D03*
X473378D03*
X482629Y899805D03*
X478929D03*
X475228D03*
X471527D03*
X484480Y902994D03*
X480779D03*
X477078D03*
X473378D03*
X482629Y906182D03*
X478929D03*
X475228D03*
X471527D03*
X484480Y909371D03*
X480779D03*
X477078D03*
X473378D03*
X482629Y912560D03*
X478929D03*
X475228D03*
X471527D03*
X484480Y915749D03*
X480779D03*
X477078D03*
X473378D03*
X482629Y918938D03*
X478929D03*
X475228D03*
X471527D03*
X484480Y922127D03*
X480779D03*
X477078D03*
X473378D03*
X482629Y925316D03*
X478929D03*
X475228D03*
X471527D03*
X484480Y928505D03*
X480779D03*
X477078D03*
X473378D03*
X482629Y931694D03*
X478929D03*
X475228D03*
X471527D03*
X484480Y934883D03*
X480779D03*
X477078D03*
X473378D03*
X482629Y938072D03*
X478929D03*
X475228D03*
X471527D03*
X484480Y941261D03*
X480779D03*
X477078D03*
X473378D03*
X482629Y944450D03*
X478929D03*
X475228D03*
X471527D03*
X484480Y947639D03*
X480779D03*
X477078D03*
X473378D03*
X482629Y950828D03*
X478929D03*
X475228D03*
X471527D03*
X484480Y954017D03*
X480779D03*
X477078D03*
X473378D03*
X482629Y957206D03*
X478929D03*
X475228D03*
X471527D03*
X484480Y960395D03*
X480779D03*
X477078D03*
X473378D03*
X482629Y963584D03*
X478929D03*
X475228D03*
X471527D03*
X484480Y966773D03*
X480779D03*
X477078D03*
X473378D03*
X482629Y969962D03*
X478929D03*
X475228D03*
X471527D03*
X484480Y973151D03*
X480779D03*
X477078D03*
X473378D03*
X482629Y976340D03*
X478929D03*
X475228D03*
X471527D03*
X484480Y979529D03*
X480779D03*
X477078D03*
X473378D03*
X482629Y982718D03*
X478929D03*
X475228D03*
X471527D03*
X484480Y985907D03*
X480779D03*
X477078D03*
X473378D03*
X482629Y989096D03*
X478929D03*
X475228D03*
X471527D03*
X484480Y992285D03*
X480779D03*
X477078D03*
X473378D03*
X482629Y995474D03*
X478929D03*
X475228D03*
X484480Y998663D03*
X480779D03*
X477078D03*
X482629Y1001852D03*
X478929D03*
X475228D03*
X484480Y1005041D03*
X480779D03*
X477078D03*
X482629Y1008230D03*
X478929D03*
X475228D03*
X484480Y1011419D03*
X480779D03*
X477078D03*
X481960Y1027009D03*
X478259D03*
X483811Y1030198D03*
X480110D03*
X476409D03*
X481960Y1033387D03*
X478259D03*
X483811Y1036576D03*
X480110D03*
X476409D03*
X481960Y1039765D03*
X478259D03*
X483811Y1042954D03*
X480110D03*
X476409D03*
X481960Y1046143D03*
X478259D03*
X474559D03*
X470858D03*
X483811Y1049332D03*
X480110D03*
X476409D03*
X472708D03*
X481960Y1052521D03*
X478259D03*
X474559D03*
X470858D03*
X483811Y1055710D03*
X480110D03*
X476409D03*
X472708D03*
X481960Y1058899D03*
X478259D03*
X474559D03*
X470858D03*
X483811Y1062088D03*
X480110D03*
X476409D03*
X472708D03*
X481960Y1065277D03*
X478259D03*
X474559D03*
X470858D03*
X483811Y1068466D03*
X480110D03*
X476409D03*
X472708D03*
X481960Y1071655D03*
X478259D03*
X474559D03*
X470858D03*
X483811Y1074844D03*
X480110D03*
X476409D03*
X472708D03*
X481960Y1078033D03*
X478259D03*
X474559D03*
X470858D03*
X483811Y1081222D03*
X480110D03*
X476409D03*
X472708D03*
X481960Y1084411D03*
X478259D03*
X474559D03*
X470858D03*
X483811Y1087600D03*
X480110D03*
X476409D03*
X472708D03*
X481960Y1090789D03*
X478259D03*
X474559D03*
X470858D03*
X483811Y1093978D03*
X480110D03*
X476409D03*
X472708D03*
X481960Y1097167D03*
X478259D03*
X474559D03*
X470858D03*
X483811Y1100356D03*
X480110D03*
X476409D03*
X472708D03*
X481960Y1103545D03*
X478259D03*
X474559D03*
X470858D03*
X483811Y1106734D03*
X480110D03*
X476409D03*
X472708D03*
X481960Y1109923D03*
X478259D03*
X474559D03*
X470858D03*
X483811Y1113112D03*
X480110D03*
X476409D03*
X472708D03*
X481960Y1116301D03*
X478259D03*
X474559D03*
X470858D03*
X483811Y1119490D03*
X480110D03*
X476409D03*
X472708D03*
X481960Y1122679D03*
X478259D03*
X474559D03*
X470858D03*
X483811Y1125868D03*
X480110D03*
X476409D03*
X472708D03*
X481960Y1129057D03*
X478259D03*
X474559D03*
X470858D03*
X483811Y1132246D03*
X480110D03*
X476409D03*
X472708D03*
X481960Y1135434D03*
X478259D03*
X474559D03*
X470858D03*
X483811Y1138623D03*
X480110D03*
X476409D03*
X472708D03*
X481960Y1141812D03*
X478259D03*
X474559D03*
X470858D03*
X483811Y1145001D03*
X480110D03*
X476409D03*
X472708D03*
X481960Y1148190D03*
X478259D03*
X474559D03*
X470858D03*
X483811Y1151379D03*
X480110D03*
X476409D03*
X472708D03*
X481960Y1154568D03*
X478259D03*
X474559D03*
X470858D03*
X483811Y1157757D03*
X480110D03*
X476409D03*
X472708D03*
X481960Y1160946D03*
X478259D03*
X474559D03*
X470858D03*
X483811Y1164135D03*
X480110D03*
X476409D03*
X472708D03*
X497433Y874293D03*
X493732D03*
X486330D03*
X499283Y877482D03*
X495582D03*
X491881D03*
X488181D03*
X497433Y880671D03*
X493732D03*
X490031D03*
X486330D03*
X499283Y883860D03*
X495582D03*
X491881D03*
X488181D03*
X497433Y887049D03*
X493732D03*
X490031D03*
X486330D03*
X499283Y890238D03*
X495582D03*
X491881D03*
X488181D03*
X497433Y893427D03*
X493732D03*
X490031D03*
X486330D03*
X499283Y896616D03*
X495582D03*
X491881D03*
X488181D03*
X497433Y899805D03*
X493732D03*
X490031D03*
X486330D03*
X499283Y902994D03*
X495582D03*
X491881D03*
X488181D03*
X497433Y906182D03*
X493732D03*
X490031D03*
X486330D03*
X499283Y909371D03*
X495582D03*
X491881D03*
X488181D03*
X497433Y912560D03*
X493732D03*
X490031D03*
X486330D03*
X499283Y915749D03*
X495582D03*
X491881D03*
X488181D03*
X497433Y918938D03*
X493732D03*
X490031D03*
X486330D03*
X499283Y922127D03*
X495582D03*
X491881D03*
X488181D03*
X497433Y925316D03*
X493732D03*
X490031D03*
X486330D03*
X499283Y928505D03*
X495582D03*
X491881D03*
X488181D03*
X497433Y931694D03*
X493732D03*
X490031D03*
X486330D03*
X499283Y934883D03*
X495582D03*
X491881D03*
X488181D03*
X497433Y938072D03*
X493732D03*
X490031D03*
X486330D03*
X499283Y941261D03*
X495582D03*
X491881D03*
X488181D03*
X497433Y944450D03*
X493732D03*
X490031D03*
X486330D03*
X499283Y947639D03*
X495582D03*
X491881D03*
X488181D03*
X497433Y950828D03*
X493732D03*
X490031D03*
X486330D03*
X499283Y954017D03*
X495582D03*
X491881D03*
X488181D03*
X497433Y957206D03*
X493732D03*
X490031D03*
X486330D03*
X499283Y960395D03*
X495582D03*
X491881D03*
X488181D03*
X497433Y963584D03*
X493732D03*
X490031D03*
X486330D03*
X499283Y966773D03*
X495582D03*
X491881D03*
X488181D03*
X497433Y969962D03*
X493732D03*
X490031D03*
X486330D03*
X499283Y973151D03*
X495582D03*
X491881D03*
X488181D03*
X497433Y976340D03*
X493732D03*
X490031D03*
X486330D03*
X499283Y979529D03*
X495582D03*
X491881D03*
X488181D03*
X497433Y982718D03*
X493732D03*
X490031D03*
X486330D03*
X499283Y985907D03*
X495582D03*
X491881D03*
X488181D03*
X497433Y989096D03*
X493732D03*
X490031D03*
X486330D03*
X499283Y992285D03*
X495582D03*
X491881D03*
X488181D03*
X497433Y995474D03*
X493732D03*
X490031D03*
X486330D03*
X499283Y998663D03*
X495582D03*
X491881D03*
X488181D03*
X497433Y1001852D03*
X493732D03*
X490031D03*
X486330D03*
X499283Y1005041D03*
X495582D03*
X491881D03*
X488181D03*
X497433Y1008230D03*
X493732D03*
X490031D03*
X486330D03*
X499283Y1011419D03*
X495582D03*
X491881D03*
X488181D03*
X496763Y1027009D03*
X493063D03*
X489362D03*
X485661D03*
X498614Y1030198D03*
X494913D03*
X491212D03*
X487511D03*
X496763Y1033387D03*
X493063D03*
X489362D03*
X485661D03*
X498614Y1036576D03*
X494913D03*
X491212D03*
X487511D03*
X496763Y1039765D03*
X493063D03*
X489362D03*
X485661D03*
X498614Y1042954D03*
X494913D03*
X491212D03*
X487511D03*
X496763Y1046143D03*
X493063D03*
X489362D03*
X485661D03*
X498614Y1049332D03*
X494913D03*
X491212D03*
X487511D03*
X496763Y1052521D03*
X493063D03*
X489362D03*
X485661D03*
X498614Y1055710D03*
X494913D03*
X491212D03*
X487511D03*
X496763Y1058899D03*
X493063D03*
X489362D03*
X485661D03*
X498614Y1062088D03*
X494913D03*
X491212D03*
X487511D03*
X496763Y1065277D03*
X493063D03*
X489362D03*
X485661D03*
X498614Y1068466D03*
X494913D03*
X491212D03*
X487511D03*
X496763Y1071655D03*
X493063D03*
X489362D03*
X485661D03*
X498614Y1074844D03*
X494913D03*
X491212D03*
X487511D03*
X496763Y1078033D03*
X493063D03*
X489362D03*
X485661D03*
X498614Y1081222D03*
X494913D03*
X491212D03*
X487511D03*
X496763Y1084411D03*
X493063D03*
X489362D03*
X485661D03*
X498614Y1087600D03*
X494913D03*
X491212D03*
X487511D03*
X496763Y1090789D03*
X493063D03*
X489362D03*
X485661D03*
X498614Y1093978D03*
X494913D03*
X491212D03*
X487511D03*
X496763Y1097167D03*
X493063D03*
X489362D03*
X485661D03*
X498614Y1100356D03*
X494913D03*
X491212D03*
X487511D03*
X496763Y1103545D03*
X493063D03*
X489362D03*
X485661D03*
X498614Y1106734D03*
X494913D03*
X491212D03*
X487511D03*
X496763Y1109923D03*
X493063D03*
X489362D03*
X485661D03*
X498614Y1113112D03*
X494913D03*
X491212D03*
X487511D03*
X496763Y1116301D03*
X493063D03*
X489362D03*
X485661D03*
X498614Y1119490D03*
X494913D03*
X491212D03*
X487511D03*
X496763Y1122679D03*
X493063D03*
X489362D03*
X485661D03*
X498614Y1125868D03*
X494913D03*
X491212D03*
X487511D03*
X496763Y1129057D03*
X493063D03*
X489362D03*
X485661D03*
X498614Y1132246D03*
X494913D03*
X491212D03*
X487511D03*
X496763Y1135434D03*
X493063D03*
X489362D03*
X485661D03*
X498614Y1138623D03*
X494913D03*
X491212D03*
X487511D03*
X496763Y1141812D03*
X493063D03*
X489362D03*
X485661D03*
X498614Y1145001D03*
X494913D03*
X491212D03*
X487511D03*
X496763Y1148190D03*
X493063D03*
X489362D03*
X485661D03*
X498614Y1151379D03*
X494913D03*
X491212D03*
X487511D03*
X496763Y1154568D03*
X493063D03*
X489362D03*
X485661D03*
X498614Y1157757D03*
X494913D03*
X491212D03*
X487511D03*
X496763Y1160946D03*
X493063D03*
X489362D03*
X485661D03*
X498614Y1164135D03*
X494913D03*
X487511D03*
X508535Y874293D03*
X504834D03*
X501133D03*
X514086Y877482D03*
X510385D03*
X506685D03*
X502984D03*
X512236Y880671D03*
X508535D03*
X504834D03*
X501133D03*
X514086Y883860D03*
X510385D03*
X506685D03*
X502984D03*
X512236Y887049D03*
X508535D03*
X504834D03*
X501133D03*
X514086Y890238D03*
X510385D03*
X506685D03*
X502984D03*
X512236Y893427D03*
X508535D03*
X504834D03*
X501133D03*
X514086Y896616D03*
X510385D03*
X506685D03*
X502984D03*
X512236Y899805D03*
X508535D03*
X504834D03*
X501133D03*
X514086Y902994D03*
X510385D03*
X506685D03*
X502984D03*
X512236Y906182D03*
X508535D03*
X504834D03*
X501133D03*
X514086Y909371D03*
X510385D03*
X506685D03*
X502984D03*
X512236Y912560D03*
X508535D03*
X504834D03*
X501133D03*
X514086Y915749D03*
X510385D03*
X506685D03*
X502984D03*
X512236Y918938D03*
X508535D03*
X504834D03*
X501133D03*
X514086Y922127D03*
X510385D03*
X506685D03*
X502984D03*
X512236Y925316D03*
X508535D03*
X504834D03*
X501133D03*
X514086Y928505D03*
X510385D03*
X506685D03*
X502984D03*
X512236Y931694D03*
X508535D03*
X504834D03*
X501133D03*
X514086Y934883D03*
X510385D03*
X506685D03*
X502984D03*
X512236Y938072D03*
X508535D03*
X504834D03*
X501133D03*
X514086Y941261D03*
X510385D03*
X506685D03*
X502984D03*
X512236Y944450D03*
X508535D03*
X504834D03*
X501133D03*
X514086Y947639D03*
X510385D03*
X506685D03*
X502984D03*
X512236Y950828D03*
X508535D03*
X504834D03*
X501133D03*
X514086Y954017D03*
X510385D03*
X506685D03*
X502984D03*
X512236Y957206D03*
X508535D03*
X504834D03*
X501133D03*
X514086Y960395D03*
X510385D03*
X506685D03*
X502984D03*
X512236Y963584D03*
X508535D03*
X504834D03*
X501133D03*
X514086Y966773D03*
X510385D03*
X506685D03*
X502984D03*
X512236Y969962D03*
X508535D03*
X504834D03*
X501133D03*
X514086Y973151D03*
X510385D03*
X506685D03*
X502984D03*
X512236Y976340D03*
X508535D03*
X504834D03*
X501133D03*
X514086Y979529D03*
X510385D03*
X506685D03*
X502984D03*
X512236Y982718D03*
X508535D03*
X504834D03*
X501133D03*
X514086Y985907D03*
X510385D03*
X506685D03*
X502984D03*
X512236Y989096D03*
X508535D03*
X504834D03*
X501133D03*
X514086Y992285D03*
X510385D03*
X506685D03*
X502984D03*
X512236Y995474D03*
X508535D03*
X504834D03*
X501133D03*
X514086Y998663D03*
X510385D03*
X506685D03*
X502984D03*
X512236Y1001852D03*
X508535D03*
X504834D03*
X501133D03*
X514086Y1005041D03*
X510385D03*
X506685D03*
X502984D03*
X512236Y1008230D03*
X508535D03*
X504834D03*
X501133D03*
X514086Y1011419D03*
X510385D03*
X506685D03*
X502984D03*
X511567Y1027009D03*
X507866D03*
X504165D03*
X500464D03*
X513417Y1030198D03*
X509716D03*
X506015D03*
X502315D03*
X511567Y1033387D03*
X507866D03*
X504165D03*
X500464D03*
X513417Y1036576D03*
X509716D03*
X506015D03*
X502315D03*
X511567Y1039765D03*
X507866D03*
X504165D03*
X500464D03*
X513417Y1042954D03*
X509716D03*
X506015D03*
X502315D03*
X511567Y1046143D03*
X507866D03*
X504165D03*
X500464D03*
X513417Y1049332D03*
X509716D03*
X506015D03*
X502315D03*
X511567Y1052521D03*
X507866D03*
X504165D03*
X500464D03*
X513417Y1055710D03*
X509716D03*
X506015D03*
X502315D03*
X511567Y1058899D03*
X507866D03*
X504165D03*
X500464D03*
X513417Y1062088D03*
X509716D03*
X506015D03*
X502315D03*
X511567Y1065277D03*
X507866D03*
X504165D03*
X500464D03*
X513417Y1068466D03*
X509716D03*
X506015D03*
X502315D03*
X511567Y1071655D03*
X507866D03*
X504165D03*
X500464D03*
X513417Y1074844D03*
X509716D03*
X506015D03*
X502315D03*
X511567Y1078033D03*
X507866D03*
X504165D03*
X500464D03*
X513417Y1081222D03*
X509716D03*
X506015D03*
X502315D03*
X511567Y1084411D03*
X507866D03*
X504165D03*
X500464D03*
X513417Y1087600D03*
X509716D03*
X506015D03*
X502315D03*
X511567Y1090789D03*
X507866D03*
X504165D03*
X500464D03*
X513417Y1093978D03*
X509716D03*
X506015D03*
X502315D03*
X511567Y1097167D03*
X507866D03*
X504165D03*
X500464D03*
X513417Y1100356D03*
X509716D03*
X506015D03*
X502315D03*
X511567Y1103545D03*
X507866D03*
X504165D03*
X500464D03*
X513417Y1106734D03*
X509716D03*
X506015D03*
X502315D03*
X511567Y1109923D03*
X507866D03*
X504165D03*
X500464D03*
X513417Y1113112D03*
X509716D03*
X506015D03*
X502315D03*
X511567Y1116301D03*
X507866D03*
X504165D03*
X500464D03*
X513417Y1119490D03*
X509716D03*
X506015D03*
X502315D03*
X511567Y1122679D03*
X507866D03*
X504165D03*
X500464D03*
X513417Y1125868D03*
X509716D03*
X506015D03*
X502315D03*
X511567Y1129057D03*
X507866D03*
X504165D03*
X500464D03*
X513417Y1132246D03*
X509716D03*
X506015D03*
X502315D03*
X511567Y1135434D03*
X507866D03*
X504165D03*
X500464D03*
X513417Y1138623D03*
X509716D03*
X506015D03*
X502315D03*
X511567Y1141812D03*
X507866D03*
X504165D03*
X500464D03*
X513417Y1145001D03*
X509716D03*
X506015D03*
X502315D03*
X511567Y1148190D03*
X507866D03*
X504165D03*
X500464D03*
X513417Y1151379D03*
X509716D03*
X506015D03*
X502315D03*
X511567Y1154568D03*
X507866D03*
X504165D03*
X500464D03*
X513417Y1157757D03*
X509716D03*
X506015D03*
X502315D03*
X511567Y1160946D03*
X507866D03*
X504165D03*
X500464D03*
X509716Y1164135D03*
X506015D03*
X502315D03*
X527039Y874293D03*
X523338D03*
X519637D03*
X515937D03*
X528889Y877482D03*
X525189D03*
X521488D03*
X517787D03*
X527039Y880671D03*
X523338D03*
X519637D03*
X515937D03*
X528889Y883860D03*
X525189D03*
X521488D03*
X517787D03*
X527039Y887049D03*
X523338D03*
X519637D03*
X515937D03*
X528889Y890238D03*
X525189D03*
X521488D03*
X517787D03*
X527039Y893427D03*
X523338D03*
X519637D03*
X515937D03*
X528889Y896616D03*
X525189D03*
X521488D03*
X517787D03*
X527039Y899805D03*
X523338D03*
X519637D03*
X515937D03*
X528889Y902994D03*
X525189D03*
X521488D03*
X517787D03*
X527039Y906182D03*
X523338D03*
X519637D03*
X515937D03*
X528889Y909371D03*
X525189D03*
X521488D03*
X517787D03*
X527039Y912560D03*
X523338D03*
X519637D03*
X515937D03*
X528889Y915749D03*
X525189D03*
X521488D03*
X517787D03*
X527039Y918938D03*
X523338D03*
X519637D03*
X515937D03*
X528889Y922127D03*
X525189D03*
X521488D03*
X517787D03*
X527039Y925316D03*
X523338D03*
X519637D03*
X515937D03*
X528889Y928505D03*
X525189D03*
X521488D03*
X517787D03*
X527039Y931694D03*
X523338D03*
X519637D03*
X515937D03*
X528889Y934883D03*
X525189D03*
X521488D03*
X517787D03*
X527039Y938072D03*
X523338D03*
X519637D03*
X515937D03*
X528889Y941261D03*
X525189D03*
X521488D03*
X517787D03*
X527039Y944450D03*
X523338D03*
X519637D03*
X515937D03*
X528889Y947639D03*
X525189D03*
X521488D03*
X517787D03*
X527039Y950828D03*
X523338D03*
X519637D03*
X515937D03*
X528889Y954017D03*
X525189D03*
X521488D03*
X517787D03*
X527039Y957206D03*
X523338D03*
X519637D03*
X515937D03*
X528889Y960395D03*
X525189D03*
X521488D03*
X517787D03*
X527039Y963584D03*
X523338D03*
X519637D03*
X515937D03*
X528889Y966773D03*
X525189D03*
X521488D03*
X517787D03*
X527039Y969962D03*
X523338D03*
X519637D03*
X515937D03*
X528889Y973151D03*
X525189D03*
X521488D03*
X517787D03*
X527039Y976340D03*
X523338D03*
X519637D03*
X515937D03*
X528889Y979529D03*
X525189D03*
X521488D03*
X517787D03*
X527039Y982718D03*
X523338D03*
X519637D03*
X515937D03*
X528889Y985907D03*
X525189D03*
X521488D03*
X517787D03*
X527039Y989096D03*
X523338D03*
X519637D03*
X515937D03*
X528889Y992285D03*
X525189D03*
X521488D03*
X517787D03*
X527039Y995474D03*
X523338D03*
X519637D03*
X515937D03*
X528889Y998663D03*
X525189D03*
X521488D03*
X517787D03*
X527039Y1001852D03*
X523338D03*
X519637D03*
X515937D03*
X528889Y1005041D03*
X525189D03*
X521488D03*
X517787D03*
X527039Y1008230D03*
X523338D03*
X519637D03*
X515937D03*
X528889Y1011419D03*
X525189D03*
X521488D03*
X517787D03*
X526370Y1027009D03*
X522669D03*
X518968D03*
X515267D03*
X528220Y1030198D03*
X524519D03*
X520818D03*
X517118D03*
X526370Y1033387D03*
X522669D03*
X518968D03*
X515267D03*
X528220Y1036576D03*
X524519D03*
X520818D03*
X517118D03*
X526370Y1039765D03*
X522669D03*
X518968D03*
X515267D03*
X528220Y1042954D03*
X524519D03*
X520818D03*
X517118D03*
X526370Y1046143D03*
X522669D03*
X518968D03*
X515267D03*
X528220Y1049332D03*
X524519D03*
X520818D03*
X517118D03*
X526370Y1052521D03*
X522669D03*
X518968D03*
X515267D03*
X528220Y1055710D03*
X524519D03*
X520818D03*
X517118D03*
X526370Y1058899D03*
X522669D03*
X518968D03*
X515267D03*
X528220Y1062088D03*
X524519D03*
X520818D03*
X517118D03*
X526370Y1065277D03*
X522669D03*
X518968D03*
X515267D03*
X528220Y1068466D03*
X524519D03*
X520818D03*
X517118D03*
X526370Y1071655D03*
X522669D03*
X518968D03*
X515267D03*
X528220Y1074844D03*
X524519D03*
X520818D03*
X517118D03*
X526370Y1078033D03*
X522669D03*
X518968D03*
X515267D03*
X528220Y1081222D03*
X524519D03*
X520818D03*
X517118D03*
X526370Y1084411D03*
X522669D03*
X518968D03*
X515267D03*
X528220Y1087600D03*
X524519D03*
X520818D03*
X517118D03*
X526370Y1090789D03*
X522669D03*
X518968D03*
X515267D03*
X528220Y1093978D03*
X524519D03*
X520818D03*
X517118D03*
X526370Y1097167D03*
X522669D03*
X518968D03*
X515267D03*
X528220Y1100356D03*
X524519D03*
X520818D03*
X517118D03*
X526370Y1103545D03*
X522669D03*
X518968D03*
X515267D03*
X528220Y1106734D03*
X524519D03*
X520818D03*
X517118D03*
X526370Y1109923D03*
X522669D03*
X518968D03*
X515267D03*
X528220Y1113112D03*
X524519D03*
X520818D03*
X517118D03*
X526370Y1116301D03*
X522669D03*
X518968D03*
X515267D03*
X528220Y1119490D03*
X524519D03*
X520818D03*
X517118D03*
X526370Y1122679D03*
X522669D03*
X518968D03*
X515267D03*
X528220Y1125868D03*
X524519D03*
X520818D03*
X517118D03*
X526370Y1129057D03*
X522669D03*
X518968D03*
X515267D03*
X528220Y1132246D03*
X524519D03*
X520818D03*
X517118D03*
X526370Y1135434D03*
X522669D03*
X518968D03*
X515267D03*
X528220Y1138623D03*
X524519D03*
X520818D03*
X517118D03*
X526370Y1141812D03*
X522669D03*
X518968D03*
X515267D03*
X528220Y1145001D03*
X524519D03*
X520818D03*
X517118D03*
X526370Y1148190D03*
X522669D03*
X518968D03*
X515267D03*
X528220Y1151379D03*
X524519D03*
X520818D03*
X517118D03*
X526370Y1154568D03*
X522669D03*
X518968D03*
X515267D03*
X528220Y1157757D03*
X524519D03*
X520818D03*
X517118D03*
X526370Y1160946D03*
X522669D03*
X518968D03*
X515267D03*
X528220Y1164135D03*
X524519D03*
X520818D03*
X517118D03*
X541842Y874293D03*
X538141D03*
X530740D03*
X543693Y877482D03*
X539992D03*
X536291D03*
X532590D03*
X541842Y880671D03*
X538141D03*
X534441D03*
X530740D03*
X543693Y883860D03*
X539992D03*
X536291D03*
X532590D03*
X541842Y887049D03*
X538141D03*
X534441D03*
X530740D03*
X543693Y890238D03*
X539992D03*
X536291D03*
X532590D03*
X541842Y893427D03*
X538141D03*
X534441D03*
X530740D03*
X543693Y896616D03*
X539992D03*
X536291D03*
X532590D03*
X541842Y899805D03*
X538141D03*
X534441D03*
X530740D03*
X543693Y902994D03*
X539992D03*
X536291D03*
X532590D03*
X541842Y906182D03*
X538141D03*
X534441D03*
X530740D03*
X543693Y909371D03*
X539992D03*
X536291D03*
X532590D03*
X541842Y912560D03*
X538141D03*
X534441D03*
X530740D03*
X543693Y915749D03*
X539992D03*
X536291D03*
X532590D03*
X541842Y918938D03*
X538141D03*
X534441D03*
X530740D03*
X543693Y922127D03*
X539992D03*
X536291D03*
X532590D03*
X541842Y925316D03*
X538141D03*
X534441D03*
X530740D03*
X543693Y928505D03*
X539992D03*
X536291D03*
X532590D03*
X541842Y931694D03*
X538141D03*
X534441D03*
X530740D03*
X543693Y934883D03*
X539992D03*
X536291D03*
X532590D03*
X541842Y938072D03*
X538141D03*
X534441D03*
X530740D03*
X543693Y941261D03*
X539992D03*
X536291D03*
X532590D03*
X541842Y944450D03*
X538141D03*
X534441D03*
X530740D03*
X543693Y947639D03*
X539992D03*
X536291D03*
X532590D03*
X541842Y950828D03*
X538141D03*
X534441D03*
X530740D03*
X543693Y954017D03*
X539992D03*
X536291D03*
X532590D03*
X541842Y957206D03*
X538141D03*
X534441D03*
X530740D03*
X543693Y960395D03*
X539992D03*
X536291D03*
X532590D03*
X541842Y963584D03*
X538141D03*
X534441D03*
X530740D03*
X543693Y966773D03*
X539992D03*
X536291D03*
X532590D03*
X541842Y969962D03*
X538141D03*
X534441D03*
X530740D03*
X543693Y973151D03*
X539992D03*
X536291D03*
X532590D03*
X541842Y976340D03*
X538141D03*
X534441D03*
X530740D03*
X543693Y979529D03*
X539992D03*
X536291D03*
X532590D03*
X541842Y982718D03*
X538141D03*
X534441D03*
X530740D03*
X543693Y985907D03*
X539992D03*
X536291D03*
X532590D03*
X541842Y989096D03*
X538141D03*
X534441D03*
X530740D03*
X543693Y992285D03*
X539992D03*
X536291D03*
X532590D03*
X541842Y995474D03*
X538141D03*
X534441D03*
X530740D03*
X543693Y998663D03*
X539992D03*
X536291D03*
X532590D03*
X541842Y1001852D03*
X538141D03*
X534441D03*
X530740D03*
X543693Y1005041D03*
X539992D03*
X536291D03*
X532590D03*
X541842Y1008230D03*
X538141D03*
X534441D03*
X530740D03*
X543693Y1011419D03*
X539992D03*
X536291D03*
X532590D03*
X541173Y1027009D03*
X537472D03*
X533771D03*
X530070D03*
X543023Y1030198D03*
X539322D03*
X535622D03*
X531921D03*
X541173Y1033387D03*
X537472D03*
X533771D03*
X530070D03*
X543023Y1036576D03*
X539322D03*
X535622D03*
X531921D03*
X541173Y1039765D03*
X537472D03*
X533771D03*
X530070D03*
X543023Y1042954D03*
X539322D03*
X535622D03*
X531921D03*
X541173Y1046143D03*
X537472D03*
X533771D03*
X530070D03*
X543023Y1049332D03*
X539322D03*
X535622D03*
X531921D03*
X541173Y1052521D03*
X537472D03*
X533771D03*
X530070D03*
X543023Y1055710D03*
X539322D03*
X535622D03*
X531921D03*
X541173Y1058899D03*
X537472D03*
X533771D03*
X530070D03*
X543023Y1062088D03*
X539322D03*
X535622D03*
X531921D03*
X541173Y1065277D03*
X537472D03*
X533771D03*
X530070D03*
X543023Y1068466D03*
X539322D03*
X535622D03*
X531921D03*
X541173Y1071655D03*
X537472D03*
X533771D03*
X530070D03*
X543023Y1074844D03*
X539322D03*
X535622D03*
X531921D03*
X541173Y1078033D03*
X537472D03*
X533771D03*
X530070D03*
X543023Y1081222D03*
X539322D03*
X535622D03*
X531921D03*
X541173Y1084411D03*
X537472D03*
X533771D03*
X530070D03*
X543023Y1087600D03*
X539322D03*
X535622D03*
X531921D03*
X541173Y1090789D03*
X537472D03*
X533771D03*
X530070D03*
X543023Y1093978D03*
X539322D03*
X535622D03*
X531921D03*
X541173Y1097167D03*
X537472D03*
X533771D03*
X530070D03*
X543023Y1100356D03*
X539322D03*
X535622D03*
X531921D03*
X541173Y1103545D03*
X537472D03*
X533771D03*
X530070D03*
X543023Y1106734D03*
X539322D03*
X535622D03*
X531921D03*
X541173Y1109923D03*
X537472D03*
X533771D03*
X530070D03*
X543023Y1113112D03*
X539322D03*
X535622D03*
X531921D03*
X541173Y1116301D03*
X537472D03*
X533771D03*
X530070D03*
X543023Y1119490D03*
X539322D03*
X535622D03*
X531921D03*
X541173Y1122679D03*
X537472D03*
X533771D03*
X530070D03*
X543023Y1125868D03*
X539322D03*
X535622D03*
X531921D03*
X541173Y1129057D03*
X537472D03*
X533771D03*
X530070D03*
X543023Y1132246D03*
X539322D03*
X535622D03*
X531921D03*
X541173Y1135434D03*
X537472D03*
X533771D03*
X530070D03*
X543023Y1138623D03*
X539322D03*
X535622D03*
X531921D03*
X541173Y1141812D03*
X537472D03*
X533771D03*
X530070D03*
X543023Y1145001D03*
X539322D03*
X535622D03*
X531921D03*
X541173Y1148190D03*
X537472D03*
X533771D03*
X530070D03*
X543023Y1151379D03*
X539322D03*
X535622D03*
X531921D03*
X541173Y1154568D03*
X537472D03*
X533771D03*
X530070D03*
X543023Y1157757D03*
X539322D03*
X535622D03*
X531921D03*
X541173Y1160946D03*
X537472D03*
X533771D03*
X530070D03*
X543023Y1164135D03*
X539322D03*
X531921D03*
X552944Y874293D03*
X549244D03*
X545543D03*
X558496Y877482D03*
X554795D03*
X551094D03*
X547393D03*
X556645Y880671D03*
X552944D03*
X549244D03*
X545543D03*
X558496Y883860D03*
X554795D03*
X551094D03*
X547393D03*
X556645Y887049D03*
X552944D03*
X549244D03*
X545543D03*
X558496Y890238D03*
X554795D03*
X551094D03*
X547393D03*
X556645Y893427D03*
X552944D03*
X549244D03*
X545543D03*
X558496Y896616D03*
X554795D03*
X551094D03*
X547393D03*
X556645Y899805D03*
X552944D03*
X549244D03*
X545543D03*
X558496Y902994D03*
X554795D03*
X551094D03*
X547393D03*
X556645Y906182D03*
X552944D03*
X549244D03*
X545543D03*
X558496Y909371D03*
X554795D03*
X551094D03*
X547393D03*
X556645Y912560D03*
X552944D03*
X549244D03*
X545543D03*
X558496Y915749D03*
X554795D03*
X551094D03*
X547393D03*
X556645Y918938D03*
X552944D03*
X549244D03*
X545543D03*
X558496Y922127D03*
X554795D03*
X551094D03*
X547393D03*
X556645Y925316D03*
X552944D03*
X549244D03*
X545543D03*
X558496Y928505D03*
X554795D03*
X551094D03*
X547393D03*
X556645Y931694D03*
X552944D03*
X549244D03*
X545543D03*
X558496Y934883D03*
X554795D03*
X551094D03*
X547393D03*
X556645Y938072D03*
X552944D03*
X549244D03*
X545543D03*
X558496Y941261D03*
X554795D03*
X551094D03*
X547393D03*
X556645Y944450D03*
X552944D03*
X549244D03*
X545543D03*
X558496Y947639D03*
X554795D03*
X551094D03*
X547393D03*
X556645Y950828D03*
X552944D03*
X549244D03*
X545543D03*
X558496Y954017D03*
X554795D03*
X551094D03*
X547393D03*
X556645Y957206D03*
X552944D03*
X549244D03*
X545543D03*
X558496Y960395D03*
X554795D03*
X551094D03*
X547393D03*
X556645Y963584D03*
X552944D03*
X549244D03*
X545543D03*
X558496Y966773D03*
X554795D03*
X551094D03*
X547393D03*
X556645Y969962D03*
X552944D03*
X549244D03*
X545543D03*
X558496Y973151D03*
X554795D03*
X551094D03*
X547393D03*
X556645Y976340D03*
X552944D03*
X549244D03*
X545543D03*
X558496Y979529D03*
X554795D03*
X551094D03*
X547393D03*
X556645Y982718D03*
X552944D03*
X549244D03*
X545543D03*
X558496Y985907D03*
X554795D03*
X551094D03*
X547393D03*
X556645Y989096D03*
X552944D03*
X549244D03*
X545543D03*
X558496Y992285D03*
X554795D03*
X551094D03*
X547393D03*
X556645Y995474D03*
X552944D03*
X549244D03*
X545543D03*
X558496Y998663D03*
X554795D03*
X551094D03*
X547393D03*
X556645Y1001852D03*
X552944D03*
X549244D03*
X545543D03*
X558496Y1005041D03*
X554795D03*
X551094D03*
X547393D03*
X556645Y1008230D03*
X552944D03*
X549244D03*
X545543D03*
X558496Y1011419D03*
X554795D03*
X551094D03*
X547393D03*
X555976Y1027009D03*
X552275D03*
X548574D03*
X544874D03*
X557826Y1030198D03*
X554126D03*
X550425D03*
X546724D03*
X555976Y1033387D03*
X552275D03*
X548574D03*
X544874D03*
X557826Y1036576D03*
X554126D03*
X550425D03*
X546724D03*
X555976Y1039765D03*
X552275D03*
X548574D03*
X544874D03*
X557826Y1042954D03*
X554126D03*
X550425D03*
X546724D03*
X555976Y1046143D03*
X552275D03*
X548574D03*
X544874D03*
X557826Y1049332D03*
X554126D03*
X550425D03*
X546724D03*
X555976Y1052521D03*
X552275D03*
X548574D03*
X544874D03*
X557826Y1055710D03*
X554126D03*
X550425D03*
X546724D03*
X555976Y1058899D03*
X552275D03*
X548574D03*
X544874D03*
X557826Y1062088D03*
X554126D03*
X550425D03*
X546724D03*
X555976Y1065277D03*
X552275D03*
X548574D03*
X544874D03*
X557826Y1068466D03*
X554126D03*
X550425D03*
X546724D03*
X555976Y1071655D03*
X552275D03*
X548574D03*
X544874D03*
X557826Y1074844D03*
X554126D03*
X550425D03*
X546724D03*
X555976Y1078033D03*
X552275D03*
X548574D03*
X544874D03*
X557826Y1081222D03*
X554126D03*
X550425D03*
X546724D03*
X555976Y1084411D03*
X552275D03*
X548574D03*
X544874D03*
X557826Y1087600D03*
X554126D03*
X550425D03*
X546724D03*
X555976Y1090789D03*
X552275D03*
X548574D03*
X544874D03*
X557826Y1093978D03*
X554126D03*
X550425D03*
X546724D03*
X555976Y1097167D03*
X552275D03*
X548574D03*
X544874D03*
X557826Y1100356D03*
X554126D03*
X550425D03*
X546724D03*
X555976Y1103545D03*
X552275D03*
X548574D03*
X544874D03*
X557826Y1106734D03*
X554126D03*
X550425D03*
X546724D03*
X555976Y1109923D03*
X552275D03*
X548574D03*
X544874D03*
X557826Y1113112D03*
X554126D03*
X550425D03*
X546724D03*
X555976Y1116301D03*
X552275D03*
X548574D03*
X544874D03*
X557826Y1119490D03*
X554126D03*
X550425D03*
X546724D03*
X555976Y1122679D03*
X552275D03*
X548574D03*
X544874D03*
X557826Y1125868D03*
X554126D03*
X550425D03*
X546724D03*
X555976Y1129057D03*
X552275D03*
X548574D03*
X544874D03*
X557826Y1132246D03*
X554126D03*
X550425D03*
X546724D03*
X555976Y1135434D03*
X552275D03*
X548574D03*
X544874D03*
X557826Y1138623D03*
X554126D03*
X550425D03*
X546724D03*
X555976Y1141812D03*
X552275D03*
X548574D03*
X544874D03*
X557826Y1145001D03*
X554126D03*
X550425D03*
X546724D03*
X555976Y1148190D03*
X552275D03*
X548574D03*
X544874D03*
X557826Y1151379D03*
X554126D03*
X550425D03*
X546724D03*
X555976Y1154568D03*
X552275D03*
X548574D03*
X544874D03*
X557826Y1157757D03*
X554126D03*
X550425D03*
X546724D03*
X555976Y1160946D03*
X552275D03*
X548574D03*
X544874D03*
X554126Y1164135D03*
X550425D03*
X546724D03*
X567748Y874293D03*
X564047D03*
X560346D03*
X569598Y877482D03*
X565897D03*
X562196D03*
X571448Y880671D03*
X567748D03*
X564047D03*
X560346D03*
X573299Y883860D03*
X569598D03*
X565897D03*
X562196D03*
X571448Y887049D03*
X567748D03*
X564047D03*
X560346D03*
X573299Y890238D03*
X569598D03*
X565897D03*
X562196D03*
X571448Y893427D03*
X567748D03*
X564047D03*
X560346D03*
X573299Y896616D03*
X569598D03*
X565897D03*
X562196D03*
X571448Y899805D03*
X567748D03*
X564047D03*
X560346D03*
X573299Y902994D03*
X569598D03*
X565897D03*
X562196D03*
X571448Y906182D03*
X567748D03*
X564047D03*
X560346D03*
X573299Y909371D03*
X569598D03*
X565897D03*
X562196D03*
X571448Y912560D03*
X567748D03*
X564047D03*
X560346D03*
X573299Y915749D03*
X569598D03*
X565897D03*
X562196D03*
X571448Y918938D03*
X567748D03*
X564047D03*
X560346D03*
X573299Y922127D03*
X569598D03*
X565897D03*
X562196D03*
X571448Y925316D03*
X567748D03*
X564047D03*
X560346D03*
X573299Y928505D03*
X569598D03*
X565897D03*
X562196D03*
X571448Y931694D03*
X567748D03*
X564047D03*
X560346D03*
X573299Y934883D03*
X569598D03*
X565897D03*
X562196D03*
X571448Y938072D03*
X567748D03*
X564047D03*
X560346D03*
X573299Y941261D03*
X569598D03*
X565897D03*
X562196D03*
X571448Y944450D03*
X567748D03*
X564047D03*
X560346D03*
X573299Y947639D03*
X569598D03*
X565897D03*
X562196D03*
X571448Y950828D03*
X567748D03*
X564047D03*
X560346D03*
X573299Y954017D03*
X569598D03*
X565897D03*
X562196D03*
X571448Y957206D03*
X567748D03*
X564047D03*
X560346D03*
X573299Y960395D03*
X569598D03*
X565897D03*
X562196D03*
X571448Y963584D03*
X567748D03*
X564047D03*
X560346D03*
X573299Y966773D03*
X569598D03*
X565897D03*
X562196D03*
X571448Y969962D03*
X567748D03*
X564047D03*
X560346D03*
X573299Y973151D03*
X569598D03*
X565897D03*
X562196D03*
X571448Y976340D03*
X567748D03*
X564047D03*
X560346D03*
X573299Y979529D03*
X569598D03*
X565897D03*
X562196D03*
X571448Y982718D03*
X567748D03*
X564047D03*
X560346D03*
X573299Y985907D03*
X569598D03*
X565897D03*
X562196D03*
X571448Y989096D03*
X567748D03*
X564047D03*
X560346D03*
X573299Y992285D03*
X569598D03*
X565897D03*
X562196D03*
X571448Y995474D03*
X567748D03*
X564047D03*
X560346D03*
X573299Y998663D03*
X569598D03*
X565897D03*
X562196D03*
X571448Y1001852D03*
X567748D03*
X564047D03*
X560346D03*
X573299Y1005041D03*
X569598D03*
X565897D03*
X562196D03*
X571448Y1008230D03*
X567748D03*
X564047D03*
X560346D03*
X573299Y1011419D03*
X569598D03*
X565897D03*
X562196D03*
X570779Y1027009D03*
X567078D03*
X563378D03*
X559677D03*
X572629Y1030198D03*
X568929D03*
X565228D03*
X561527D03*
X570779Y1033387D03*
X567078D03*
X563378D03*
X559677D03*
X572629Y1036576D03*
X568929D03*
X565228D03*
X561527D03*
X570779Y1039765D03*
X567078D03*
X563378D03*
X559677D03*
X572629Y1042954D03*
X568929D03*
X565228D03*
X561527D03*
X570779Y1046143D03*
X567078D03*
X563378D03*
X559677D03*
X572629Y1049332D03*
X568929D03*
X565228D03*
X561527D03*
X570779Y1052521D03*
X567078D03*
X563378D03*
X559677D03*
X572629Y1055710D03*
X568929D03*
X565228D03*
X561527D03*
X570779Y1058899D03*
X567078D03*
X563378D03*
X559677D03*
X572629Y1062088D03*
X568929D03*
X565228D03*
X561527D03*
X570779Y1065277D03*
X567078D03*
X563378D03*
X559677D03*
X572629Y1068466D03*
X568929D03*
X565228D03*
X561527D03*
X570779Y1071655D03*
X567078D03*
X563378D03*
X559677D03*
X572629Y1074844D03*
X568929D03*
X565228D03*
X561527D03*
X570779Y1078033D03*
X567078D03*
X563378D03*
X559677D03*
X572629Y1081222D03*
X568929D03*
X565228D03*
X561527D03*
X570779Y1084411D03*
X567078D03*
X563378D03*
X559677D03*
X572629Y1087600D03*
X568929D03*
X565228D03*
X561527D03*
X570779Y1090789D03*
X567078D03*
X563378D03*
X559677D03*
X572629Y1093978D03*
X568929D03*
X565228D03*
X561527D03*
X570779Y1097167D03*
X567078D03*
X563378D03*
X559677D03*
X572629Y1100356D03*
X568929D03*
X565228D03*
X561527D03*
X570779Y1103545D03*
X567078D03*
X563378D03*
X559677D03*
X572629Y1106734D03*
X568929D03*
X565228D03*
X561527D03*
X570779Y1109923D03*
X567078D03*
X563378D03*
X559677D03*
X572629Y1113112D03*
X568929D03*
X565228D03*
X561527D03*
X570779Y1116301D03*
X567078D03*
X563378D03*
X559677D03*
X572629Y1119490D03*
X568929D03*
X565228D03*
X561527D03*
X570779Y1122679D03*
X567078D03*
X563378D03*
X559677D03*
X572629Y1125868D03*
X568929D03*
X565228D03*
X561527D03*
X570779Y1129057D03*
X567078D03*
X563378D03*
X559677D03*
X572629Y1132246D03*
X568929D03*
X565228D03*
X561527D03*
X570779Y1135434D03*
X567078D03*
X563378D03*
X559677D03*
X572629Y1138623D03*
X568929D03*
X565228D03*
X561527D03*
X570779Y1141812D03*
X567078D03*
X563378D03*
X559677D03*
X572629Y1145001D03*
X568929D03*
X565228D03*
X561527D03*
X570779Y1148190D03*
X567078D03*
X563378D03*
X559677D03*
X572629Y1151379D03*
X568929D03*
X565228D03*
X561527D03*
X570779Y1154568D03*
X567078D03*
X563378D03*
X559677D03*
X572629Y1157757D03*
X568929D03*
X565228D03*
X561527D03*
X570779Y1160946D03*
X567078D03*
X563378D03*
X559677D03*
X568929Y1164135D03*
X565228D03*
X561527D03*
X575149Y880671D03*
Y887049D03*
Y893427D03*
Y899805D03*
Y906182D03*
Y912560D03*
Y918938D03*
Y925316D03*
Y931694D03*
Y938072D03*
Y944450D03*
Y950828D03*
Y957206D03*
Y963584D03*
Y969962D03*
Y976340D03*
Y982718D03*
Y989096D03*
Y995474D03*
Y1001852D03*
Y1008230D03*
X574480Y1027009D03*
X576330Y1030198D03*
X574480Y1033387D03*
X576330Y1036576D03*
X574480Y1039765D03*
X576330Y1042954D03*
X574480Y1046143D03*
X576330Y1049332D03*
X574480Y1052521D03*
X576330Y1055710D03*
X574480Y1058899D03*
X576330Y1062088D03*
X574480Y1065277D03*
X576330Y1068466D03*
X574480Y1071655D03*
X576330Y1074844D03*
X574480Y1078033D03*
X576330Y1081222D03*
X574480Y1084411D03*
X576330Y1087600D03*
X574480Y1090789D03*
X576330Y1093978D03*
X574480Y1097167D03*
X576330Y1100356D03*
X574480Y1103545D03*
X576330Y1106734D03*
X574480Y1109923D03*
X576330Y1113112D03*
X574480Y1116301D03*
X576330Y1119490D03*
X574480Y1122679D03*
X576330Y1125868D03*
X574480Y1129057D03*
X576330Y1132246D03*
X574480Y1135434D03*
X576330Y1138623D03*
X574480Y1141812D03*
X576330Y1145001D03*
X574480Y1148190D03*
X576330Y1151379D03*
X574480Y1154568D03*
X576330Y1157757D03*
X1288535Y874292D03*
X1286685Y877481D03*
X1288535Y880670D03*
X1284835D03*
X1281134D03*
X1286685Y883859D03*
X1282984D03*
X1288535Y887048D03*
X1284835D03*
X1281134D03*
X1286685Y890237D03*
X1282984D03*
X1288535Y893426D03*
X1284835D03*
X1281134D03*
X1286685Y896615D03*
X1282984D03*
X1288535Y899804D03*
X1284835D03*
X1281134D03*
X1286685Y902993D03*
X1282984D03*
X1288535Y906181D03*
X1284835D03*
X1281134D03*
X1286685Y909370D03*
X1282984D03*
X1288535Y912559D03*
X1284835D03*
X1281134D03*
X1286685Y915748D03*
X1282984D03*
X1288535Y918937D03*
X1284835D03*
X1281134D03*
X1286685Y922126D03*
X1282984D03*
X1288535Y925315D03*
X1284835D03*
X1281134D03*
X1286685Y928504D03*
X1282984D03*
X1288535Y931693D03*
X1284835D03*
X1281134D03*
X1286685Y934882D03*
X1282984D03*
X1288535Y938071D03*
X1284835D03*
X1281134D03*
X1286685Y941260D03*
X1282984D03*
X1288535Y944449D03*
X1284835D03*
X1281134D03*
X1286685Y947638D03*
X1282984D03*
X1288535Y950827D03*
X1284835D03*
X1281134D03*
X1286685Y954016D03*
X1282984D03*
X1288535Y957205D03*
X1284835D03*
X1281134D03*
X1286685Y960394D03*
X1282984D03*
X1288535Y963583D03*
X1284835D03*
X1281134D03*
X1286685Y966772D03*
X1282984D03*
X1288535Y969961D03*
X1284835D03*
X1281134D03*
X1286685Y973150D03*
X1282984D03*
X1288535Y976339D03*
X1284835D03*
X1281134D03*
X1286685Y979528D03*
X1282984D03*
X1288535Y982717D03*
X1284835D03*
X1281134D03*
X1286685Y985906D03*
X1282984D03*
X1288535Y989095D03*
X1284835D03*
X1281134D03*
X1286685Y992284D03*
X1282984D03*
X1288535Y995473D03*
X1284835D03*
X1281134D03*
X1286685Y998662D03*
X1282984D03*
X1288535Y1001851D03*
X1284835D03*
X1281134D03*
X1286685Y1005040D03*
X1282984D03*
X1288535Y1008229D03*
X1284835D03*
X1281134D03*
X1286685Y1011418D03*
X1282984D03*
X1287866Y1027008D03*
X1284165D03*
X1289716Y1030197D03*
X1286016D03*
X1282315D03*
X1287866Y1033386D03*
X1284165D03*
X1289716Y1036575D03*
X1286016D03*
X1282315D03*
X1287866Y1039764D03*
X1284165D03*
X1289716Y1042953D03*
X1286016D03*
X1282315D03*
X1287866Y1046142D03*
X1284165D03*
X1289716Y1049331D03*
X1286016D03*
X1282315D03*
X1287866Y1052520D03*
X1284165D03*
X1289716Y1055709D03*
X1286016D03*
X1282315D03*
X1287866Y1058898D03*
X1284165D03*
X1289716Y1062087D03*
X1286016D03*
X1282315D03*
X1287866Y1065276D03*
X1284165D03*
X1289716Y1068465D03*
X1286016D03*
X1282315D03*
X1287866Y1071654D03*
X1284165D03*
X1289716Y1074843D03*
X1286016D03*
X1282315D03*
X1287866Y1078032D03*
X1284165D03*
X1289716Y1081221D03*
X1286016D03*
X1282315D03*
X1287866Y1084410D03*
X1284165D03*
X1289716Y1087599D03*
X1286016D03*
X1282315D03*
X1287866Y1090788D03*
X1284165D03*
X1289716Y1093977D03*
X1286016D03*
X1282315D03*
X1287866Y1097166D03*
X1284165D03*
X1289716Y1100355D03*
X1286016D03*
X1282315D03*
X1287866Y1103544D03*
X1284165D03*
X1289716Y1106733D03*
X1286016D03*
X1282315D03*
X1287866Y1109922D03*
X1284165D03*
X1289716Y1113111D03*
X1286016D03*
X1282315D03*
X1287866Y1116300D03*
X1284165D03*
X1289716Y1119489D03*
X1286016D03*
X1282315D03*
X1287866Y1122678D03*
X1284165D03*
X1289716Y1125867D03*
X1286016D03*
X1282315D03*
X1287866Y1129056D03*
X1284165D03*
X1289716Y1132245D03*
X1286016D03*
X1282315D03*
X1287866Y1135433D03*
X1284165D03*
X1289716Y1138622D03*
X1286016D03*
X1282315D03*
X1287866Y1141811D03*
X1284165D03*
X1289716Y1145000D03*
X1286016D03*
X1282315D03*
X1287866Y1148189D03*
X1284165D03*
X1289716Y1151378D03*
X1286016D03*
X1282315D03*
X1287866Y1154567D03*
X1284165D03*
X1289716Y1157756D03*
X1286016D03*
X1282315D03*
X1287866Y1160945D03*
X1289716Y1164134D03*
X1303338Y874292D03*
X1295937D03*
X1292236D03*
X1301488Y877481D03*
X1297787D03*
X1294086D03*
X1290386D03*
X1303338Y880670D03*
X1299638D03*
X1295937D03*
X1292236D03*
X1301488Y883859D03*
X1297787D03*
X1294086D03*
X1290386D03*
X1303338Y887048D03*
X1299638D03*
X1295937D03*
X1292236D03*
X1301488Y890237D03*
X1297787D03*
X1294086D03*
X1290386D03*
X1303338Y893426D03*
X1299638D03*
X1295937D03*
X1292236D03*
X1301488Y896615D03*
X1297787D03*
X1294086D03*
X1290386D03*
X1303338Y899804D03*
X1299638D03*
X1295937D03*
X1292236D03*
X1301488Y902993D03*
X1297787D03*
X1294086D03*
X1290386D03*
X1303338Y906181D03*
X1299638D03*
X1295937D03*
X1292236D03*
X1301488Y909370D03*
X1297787D03*
X1294086D03*
X1290386D03*
X1303338Y912559D03*
X1299638D03*
X1295937D03*
X1292236D03*
X1301488Y915748D03*
X1297787D03*
X1294086D03*
X1290386D03*
X1303338Y918937D03*
X1299638D03*
X1295937D03*
X1292236D03*
X1301488Y922126D03*
X1297787D03*
X1294086D03*
X1290386D03*
X1303338Y925315D03*
X1299638D03*
X1295937D03*
X1292236D03*
X1301488Y928504D03*
X1297787D03*
X1294086D03*
X1290386D03*
X1303338Y931693D03*
X1299638D03*
X1295937D03*
X1292236D03*
X1301488Y934882D03*
X1297787D03*
X1294086D03*
X1290386D03*
X1303338Y938071D03*
X1299638D03*
X1295937D03*
X1292236D03*
X1301488Y941260D03*
X1297787D03*
X1294086D03*
X1290386D03*
X1303338Y944449D03*
X1299638D03*
X1295937D03*
X1292236D03*
X1301488Y947638D03*
X1297787D03*
X1294086D03*
X1290386D03*
X1303338Y950827D03*
X1299638D03*
X1295937D03*
X1292236D03*
X1301488Y954016D03*
X1297787D03*
X1294086D03*
X1290386D03*
X1303338Y957205D03*
X1299638D03*
X1295937D03*
X1292236D03*
X1301488Y960394D03*
X1297787D03*
X1294086D03*
X1290386D03*
X1303338Y963583D03*
X1299638D03*
X1295937D03*
X1292236D03*
X1301488Y966772D03*
X1297787D03*
X1294086D03*
X1290386D03*
X1303338Y969961D03*
X1299638D03*
X1295937D03*
X1292236D03*
X1301488Y973150D03*
X1297787D03*
X1294086D03*
X1290386D03*
X1303338Y976339D03*
X1299638D03*
X1295937D03*
X1292236D03*
X1301488Y979528D03*
X1297787D03*
X1294086D03*
X1290386D03*
X1303338Y982717D03*
X1299638D03*
X1295937D03*
X1292236D03*
X1301488Y985906D03*
X1297787D03*
X1294086D03*
X1290386D03*
X1303338Y989095D03*
X1299638D03*
X1295937D03*
X1292236D03*
X1301488Y992284D03*
X1297787D03*
X1294086D03*
X1290386D03*
X1303338Y995473D03*
X1299638D03*
X1295937D03*
X1292236D03*
X1301488Y998662D03*
X1297787D03*
X1294086D03*
X1290386D03*
X1303338Y1001851D03*
X1299638D03*
X1295937D03*
X1292236D03*
X1301488Y1005040D03*
X1297787D03*
X1294086D03*
X1290386D03*
X1303338Y1008229D03*
X1299638D03*
X1295937D03*
X1292236D03*
X1301488Y1011418D03*
X1297787D03*
X1294086D03*
X1290386D03*
X1302669Y1027008D03*
X1298968D03*
X1295268D03*
X1291567D03*
X1304520Y1030197D03*
X1300819D03*
X1297118D03*
X1293417D03*
X1302669Y1033386D03*
X1298968D03*
X1295268D03*
X1291567D03*
X1304520Y1036575D03*
X1300819D03*
X1297118D03*
X1293417D03*
X1302669Y1039764D03*
X1298968D03*
X1295268D03*
X1291567D03*
X1304520Y1042953D03*
X1300819D03*
X1297118D03*
X1293417D03*
X1302669Y1046142D03*
X1298968D03*
X1295268D03*
X1291567D03*
X1304520Y1049331D03*
X1300819D03*
X1297118D03*
X1293417D03*
X1302669Y1052520D03*
X1298968D03*
X1295268D03*
X1291567D03*
X1304520Y1055709D03*
X1300819D03*
X1297118D03*
X1293417D03*
X1302669Y1058898D03*
X1298968D03*
X1295268D03*
X1291567D03*
X1304520Y1062087D03*
X1300819D03*
X1297118D03*
X1293417D03*
X1302669Y1065276D03*
X1298968D03*
X1295268D03*
X1291567D03*
X1304520Y1068465D03*
X1300819D03*
X1297118D03*
X1293417D03*
X1302669Y1071654D03*
X1298968D03*
X1295268D03*
X1291567D03*
X1304520Y1074843D03*
X1300819D03*
X1297118D03*
X1293417D03*
X1302669Y1078032D03*
X1298968D03*
X1295268D03*
X1291567D03*
X1304520Y1081221D03*
X1300819D03*
X1297118D03*
X1293417D03*
X1302669Y1084410D03*
X1298968D03*
X1295268D03*
X1291567D03*
X1304520Y1087599D03*
X1300819D03*
X1297118D03*
X1293417D03*
X1302669Y1090788D03*
X1298968D03*
X1295268D03*
X1291567D03*
X1304520Y1093977D03*
X1300819D03*
X1297118D03*
X1293417D03*
X1302669Y1097166D03*
X1298968D03*
X1295268D03*
X1291567D03*
X1304520Y1100355D03*
X1300819D03*
X1297118D03*
X1293417D03*
X1302669Y1103544D03*
X1298968D03*
X1295268D03*
X1291567D03*
X1304520Y1106733D03*
X1300819D03*
X1297118D03*
X1293417D03*
X1302669Y1109922D03*
X1298968D03*
X1295268D03*
X1291567D03*
X1304520Y1113111D03*
X1300819D03*
X1297118D03*
X1293417D03*
X1302669Y1116300D03*
X1298968D03*
X1295268D03*
X1291567D03*
X1304520Y1119489D03*
X1300819D03*
X1297118D03*
X1293417D03*
X1302669Y1122678D03*
X1298968D03*
X1295268D03*
X1291567D03*
X1304520Y1125867D03*
X1300819D03*
X1297118D03*
X1293417D03*
X1302669Y1129056D03*
X1298968D03*
X1295268D03*
X1291567D03*
X1304520Y1132245D03*
X1300819D03*
X1297118D03*
X1293417D03*
X1302669Y1135433D03*
X1298968D03*
X1295268D03*
X1291567D03*
X1304520Y1138622D03*
X1300819D03*
X1297118D03*
X1293417D03*
X1302669Y1141811D03*
X1298968D03*
X1295268D03*
X1291567D03*
X1304520Y1145000D03*
X1300819D03*
X1297118D03*
X1293417D03*
X1302669Y1148189D03*
X1298968D03*
X1295268D03*
X1291567D03*
X1304520Y1151378D03*
X1300819D03*
X1297118D03*
X1293417D03*
X1302669Y1154567D03*
X1298968D03*
X1295268D03*
X1291567D03*
X1304520Y1157756D03*
X1300819D03*
X1297118D03*
X1293417D03*
X1302669Y1160945D03*
X1298968D03*
X1295268D03*
X1291567D03*
X1304520Y1164134D03*
X1297118D03*
X1293417D03*
X1318142Y874292D03*
X1314441D03*
X1310740D03*
X1307039D03*
X1316291Y877481D03*
X1312590D03*
X1308890D03*
X1305189D03*
X1318142Y880670D03*
X1314441D03*
X1310740D03*
X1307039D03*
X1316291Y883859D03*
X1312590D03*
X1308890D03*
X1305189D03*
X1318142Y887048D03*
X1314441D03*
X1310740D03*
X1307039D03*
X1316291Y890237D03*
X1312590D03*
X1308890D03*
X1305189D03*
X1318142Y893426D03*
X1314441D03*
X1310740D03*
X1307039D03*
X1316291Y896615D03*
X1312590D03*
X1308890D03*
X1305189D03*
X1318142Y899804D03*
X1314441D03*
X1310740D03*
X1307039D03*
X1316291Y902993D03*
X1312590D03*
X1308890D03*
X1305189D03*
X1318142Y906181D03*
X1314441D03*
X1310740D03*
X1307039D03*
X1316291Y909370D03*
X1312590D03*
X1308890D03*
X1305189D03*
X1318142Y912559D03*
X1314441D03*
X1310740D03*
X1307039D03*
X1316291Y915748D03*
X1312590D03*
X1308890D03*
X1305189D03*
X1318142Y918937D03*
X1314441D03*
X1310740D03*
X1307039D03*
X1316291Y922126D03*
X1312590D03*
X1308890D03*
X1305189D03*
X1318142Y925315D03*
X1314441D03*
X1310740D03*
X1307039D03*
X1316291Y928504D03*
X1312590D03*
X1308890D03*
X1305189D03*
X1318142Y931693D03*
X1314441D03*
X1310740D03*
X1307039D03*
X1316291Y934882D03*
X1312590D03*
X1308890D03*
X1305189D03*
X1318142Y938071D03*
X1314441D03*
X1310740D03*
X1307039D03*
X1316291Y941260D03*
X1312590D03*
X1308890D03*
X1305189D03*
X1318142Y944449D03*
X1314441D03*
X1310740D03*
X1307039D03*
X1316291Y947638D03*
X1312590D03*
X1308890D03*
X1305189D03*
X1318142Y950827D03*
X1314441D03*
X1310740D03*
X1307039D03*
X1316291Y954016D03*
X1312590D03*
X1308890D03*
X1305189D03*
X1318142Y957205D03*
X1314441D03*
X1310740D03*
X1307039D03*
X1316291Y960394D03*
X1312590D03*
X1308890D03*
X1305189D03*
X1318142Y963583D03*
X1314441D03*
X1310740D03*
X1307039D03*
X1316291Y966772D03*
X1312590D03*
X1308890D03*
X1305189D03*
X1318142Y969961D03*
X1314441D03*
X1310740D03*
X1307039D03*
X1316291Y973150D03*
X1312590D03*
X1308890D03*
X1305189D03*
X1318142Y976339D03*
X1314441D03*
X1310740D03*
X1307039D03*
X1316291Y979528D03*
X1312590D03*
X1308890D03*
X1305189D03*
X1318142Y982717D03*
X1314441D03*
X1310740D03*
X1307039D03*
X1316291Y985906D03*
X1312590D03*
X1308890D03*
X1305189D03*
X1318142Y989095D03*
X1314441D03*
X1310740D03*
X1307039D03*
X1316291Y992284D03*
X1312590D03*
X1308890D03*
X1305189D03*
X1318142Y995473D03*
X1314441D03*
X1310740D03*
X1307039D03*
X1316291Y998662D03*
X1312590D03*
X1308890D03*
X1305189D03*
X1318142Y1001851D03*
X1314441D03*
X1310740D03*
X1307039D03*
X1316291Y1005040D03*
X1312590D03*
X1308890D03*
X1305189D03*
X1318142Y1008229D03*
X1314441D03*
X1310740D03*
X1307039D03*
X1316291Y1011418D03*
X1312590D03*
X1308890D03*
X1305189D03*
X1317472Y1027008D03*
X1313771D03*
X1310071D03*
X1306370D03*
X1319323Y1030197D03*
X1315622D03*
X1311921D03*
X1308220D03*
X1317472Y1033386D03*
X1313771D03*
X1310071D03*
X1306370D03*
X1319323Y1036575D03*
X1315622D03*
X1311921D03*
X1308220D03*
X1317472Y1039764D03*
X1313771D03*
X1310071D03*
X1306370D03*
X1319323Y1042953D03*
X1315622D03*
X1311921D03*
X1308220D03*
X1317472Y1046142D03*
X1313771D03*
X1310071D03*
X1306370D03*
X1319323Y1049331D03*
X1315622D03*
X1311921D03*
X1308220D03*
X1317472Y1052520D03*
X1313771D03*
X1310071D03*
X1306370D03*
X1319323Y1055709D03*
X1315622D03*
X1311921D03*
X1308220D03*
X1317472Y1058898D03*
X1313771D03*
X1310071D03*
X1306370D03*
X1319323Y1062087D03*
X1315622D03*
X1311921D03*
X1308220D03*
X1317472Y1065276D03*
X1313771D03*
X1310071D03*
X1306370D03*
X1319323Y1068465D03*
X1315622D03*
X1311921D03*
X1308220D03*
X1317472Y1071654D03*
X1313771D03*
X1310071D03*
X1306370D03*
X1319323Y1074843D03*
X1315622D03*
X1311921D03*
X1308220D03*
X1317472Y1078032D03*
X1313771D03*
X1310071D03*
X1306370D03*
X1319323Y1081221D03*
X1315622D03*
X1311921D03*
X1308220D03*
X1317472Y1084410D03*
X1313771D03*
X1310071D03*
X1306370D03*
X1319323Y1087599D03*
X1315622D03*
X1311921D03*
X1308220D03*
X1317472Y1090788D03*
X1313771D03*
X1310071D03*
X1306370D03*
X1319323Y1093977D03*
X1315622D03*
X1311921D03*
X1308220D03*
X1317472Y1097166D03*
X1313771D03*
X1310071D03*
X1306370D03*
X1319323Y1100355D03*
X1315622D03*
X1311921D03*
X1308220D03*
X1317472Y1103544D03*
X1313771D03*
X1310071D03*
X1306370D03*
X1319323Y1106733D03*
X1315622D03*
X1311921D03*
X1308220D03*
X1317472Y1109922D03*
X1313771D03*
X1310071D03*
X1306370D03*
X1319323Y1113111D03*
X1315622D03*
X1311921D03*
X1308220D03*
X1317472Y1116300D03*
X1313771D03*
X1310071D03*
X1306370D03*
X1319323Y1119489D03*
X1315622D03*
X1311921D03*
X1308220D03*
X1317472Y1122678D03*
X1313771D03*
X1310071D03*
X1306370D03*
X1319323Y1125867D03*
X1315622D03*
X1311921D03*
X1308220D03*
X1317472Y1129056D03*
X1313771D03*
X1310071D03*
X1306370D03*
X1319323Y1132245D03*
X1315622D03*
X1311921D03*
X1308220D03*
X1317472Y1135433D03*
X1313771D03*
X1310071D03*
X1306370D03*
X1319323Y1138622D03*
X1315622D03*
X1311921D03*
X1308220D03*
X1317472Y1141811D03*
X1313771D03*
X1310071D03*
X1306370D03*
X1319323Y1145000D03*
X1315622D03*
X1311921D03*
X1308220D03*
X1317472Y1148189D03*
X1313771D03*
X1310071D03*
X1306370D03*
X1319323Y1151378D03*
X1315622D03*
X1311921D03*
X1308220D03*
X1317472Y1154567D03*
X1313771D03*
X1310071D03*
X1306370D03*
X1319323Y1157756D03*
X1315622D03*
X1311921D03*
X1308220D03*
X1317472Y1160945D03*
X1313771D03*
X1310071D03*
X1306370D03*
X1319323Y1164134D03*
X1315622D03*
X1311921D03*
X1308220D03*
X1332945Y874292D03*
X1329244D03*
X1325543D03*
X1331094Y877481D03*
X1327394D03*
X1323693D03*
X1319992D03*
X1332945Y880670D03*
X1329244D03*
X1325543D03*
X1321842D03*
X1331094Y883859D03*
X1327394D03*
X1323693D03*
X1319992D03*
X1332945Y887048D03*
X1329244D03*
X1325543D03*
X1321842D03*
X1331094Y890237D03*
X1327394D03*
X1323693D03*
X1319992D03*
X1332945Y893426D03*
X1329244D03*
X1325543D03*
X1321842D03*
X1331094Y896615D03*
X1327394D03*
X1323693D03*
X1319992D03*
X1332945Y899804D03*
X1329244D03*
X1325543D03*
X1321842D03*
X1331094Y902993D03*
X1327394D03*
X1323693D03*
X1319992D03*
X1332945Y906181D03*
X1329244D03*
X1325543D03*
X1321842D03*
X1331094Y909370D03*
X1327394D03*
X1323693D03*
X1319992D03*
X1332945Y912559D03*
X1329244D03*
X1325543D03*
X1321842D03*
X1331094Y915748D03*
X1327394D03*
X1323693D03*
X1319992D03*
X1332945Y918937D03*
X1329244D03*
X1325543D03*
X1321842D03*
X1331094Y922126D03*
X1327394D03*
X1323693D03*
X1319992D03*
X1332945Y925315D03*
X1329244D03*
X1325543D03*
X1321842D03*
X1331094Y928504D03*
X1327394D03*
X1323693D03*
X1319992D03*
X1332945Y931693D03*
X1329244D03*
X1325543D03*
X1321842D03*
X1331094Y934882D03*
X1327394D03*
X1323693D03*
X1319992D03*
X1332945Y938071D03*
X1329244D03*
X1325543D03*
X1321842D03*
X1331094Y941260D03*
X1327394D03*
X1323693D03*
X1319992D03*
X1332945Y944449D03*
X1329244D03*
X1325543D03*
X1321842D03*
X1331094Y947638D03*
X1327394D03*
X1323693D03*
X1319992D03*
X1332945Y950827D03*
X1329244D03*
X1325543D03*
X1321842D03*
X1331094Y954016D03*
X1327394D03*
X1323693D03*
X1319992D03*
X1332945Y957205D03*
X1329244D03*
X1325543D03*
X1321842D03*
X1331094Y960394D03*
X1327394D03*
X1323693D03*
X1319992D03*
X1332945Y963583D03*
X1329244D03*
X1325543D03*
X1321842D03*
X1331094Y966772D03*
X1327394D03*
X1323693D03*
X1319992D03*
X1332945Y969961D03*
X1329244D03*
X1325543D03*
X1321842D03*
X1331094Y973150D03*
X1327394D03*
X1323693D03*
X1319992D03*
X1332945Y976339D03*
X1329244D03*
X1325543D03*
X1321842D03*
X1331094Y979528D03*
X1327394D03*
X1323693D03*
X1319992D03*
X1332945Y982717D03*
X1329244D03*
X1325543D03*
X1321842D03*
X1331094Y985906D03*
X1327394D03*
X1323693D03*
X1319992D03*
X1332945Y989095D03*
X1329244D03*
X1325543D03*
X1321842D03*
X1331094Y992284D03*
X1327394D03*
X1323693D03*
X1319992D03*
X1332945Y995473D03*
X1329244D03*
X1325543D03*
X1321842D03*
X1331094Y998662D03*
X1327394D03*
X1323693D03*
X1319992D03*
X1332945Y1001851D03*
X1329244D03*
X1325543D03*
X1321842D03*
X1331094Y1005040D03*
X1327394D03*
X1323693D03*
X1319992D03*
X1332945Y1008229D03*
X1329244D03*
X1325543D03*
X1321842D03*
X1331094Y1011418D03*
X1327394D03*
X1323693D03*
X1319992D03*
X1332275Y1027008D03*
X1328575D03*
X1324874D03*
X1321173D03*
X1334126Y1030197D03*
X1330425D03*
X1326724D03*
X1323023D03*
X1332275Y1033386D03*
X1328575D03*
X1324874D03*
X1321173D03*
X1334126Y1036575D03*
X1330425D03*
X1326724D03*
X1323023D03*
X1332275Y1039764D03*
X1328575D03*
X1324874D03*
X1321173D03*
X1334126Y1042953D03*
X1330425D03*
X1326724D03*
X1323023D03*
X1332275Y1046142D03*
X1328575D03*
X1324874D03*
X1321173D03*
X1334126Y1049331D03*
X1330425D03*
X1326724D03*
X1323023D03*
X1332275Y1052520D03*
X1328575D03*
X1324874D03*
X1321173D03*
X1334126Y1055709D03*
X1330425D03*
X1326724D03*
X1323023D03*
X1332275Y1058898D03*
X1328575D03*
X1324874D03*
X1321173D03*
X1334126Y1062087D03*
X1330425D03*
X1326724D03*
X1323023D03*
X1332275Y1065276D03*
X1328575D03*
X1324874D03*
X1321173D03*
X1334126Y1068465D03*
X1330425D03*
X1326724D03*
X1323023D03*
X1332275Y1071654D03*
X1328575D03*
X1324874D03*
X1321173D03*
X1334126Y1074843D03*
X1330425D03*
X1326724D03*
X1323023D03*
X1332275Y1078032D03*
X1328575D03*
X1324874D03*
X1321173D03*
X1334126Y1081221D03*
X1330425D03*
X1326724D03*
X1323023D03*
X1332275Y1084410D03*
X1328575D03*
X1324874D03*
X1321173D03*
X1334126Y1087599D03*
X1330425D03*
X1326724D03*
X1323023D03*
X1332275Y1090788D03*
X1328575D03*
X1324874D03*
X1321173D03*
X1334126Y1093977D03*
X1330425D03*
X1326724D03*
X1323023D03*
X1332275Y1097166D03*
X1328575D03*
X1324874D03*
X1321173D03*
X1334126Y1100355D03*
X1330425D03*
X1326724D03*
X1323023D03*
X1332275Y1103544D03*
X1328575D03*
X1324874D03*
X1321173D03*
X1334126Y1106733D03*
X1330425D03*
X1326724D03*
X1323023D03*
X1332275Y1109922D03*
X1328575D03*
X1324874D03*
X1321173D03*
X1334126Y1113111D03*
X1330425D03*
X1326724D03*
X1323023D03*
X1332275Y1116300D03*
X1328575D03*
X1324874D03*
X1321173D03*
X1334126Y1119489D03*
X1330425D03*
X1326724D03*
X1323023D03*
X1332275Y1122678D03*
X1328575D03*
X1324874D03*
X1321173D03*
X1334126Y1125867D03*
X1330425D03*
X1326724D03*
X1323023D03*
X1332275Y1129056D03*
X1328575D03*
X1324874D03*
X1321173D03*
X1334126Y1132245D03*
X1330425D03*
X1326724D03*
X1323023D03*
X1332275Y1135433D03*
X1328575D03*
X1324874D03*
X1321173D03*
X1334126Y1138622D03*
X1330425D03*
X1326724D03*
X1323023D03*
X1332275Y1141811D03*
X1328575D03*
X1324874D03*
X1321173D03*
X1334126Y1145000D03*
X1330425D03*
X1326724D03*
X1323023D03*
X1332275Y1148189D03*
X1328575D03*
X1324874D03*
X1321173D03*
X1334126Y1151378D03*
X1330425D03*
X1326724D03*
X1323023D03*
X1332275Y1154567D03*
X1328575D03*
X1324874D03*
X1321173D03*
X1334126Y1157756D03*
X1330425D03*
X1326724D03*
X1323023D03*
X1332275Y1160945D03*
X1328575D03*
X1324874D03*
X1321173D03*
X1334126Y1164134D03*
X1330425D03*
X1326724D03*
X1347748Y874292D03*
X1340346D03*
X1336646D03*
X1349598Y877481D03*
X1345897D03*
X1342197D03*
X1338496D03*
X1334795D03*
X1347748Y880670D03*
X1344047D03*
X1340346D03*
X1336646D03*
X1349598Y883859D03*
X1345897D03*
X1342197D03*
X1338496D03*
X1334795D03*
X1347748Y887048D03*
X1344047D03*
X1340346D03*
X1336646D03*
X1349598Y890237D03*
X1345897D03*
X1342197D03*
X1338496D03*
X1334795D03*
X1347748Y893426D03*
X1344047D03*
X1340346D03*
X1336646D03*
X1349598Y896615D03*
X1345897D03*
X1342197D03*
X1338496D03*
X1334795D03*
X1347748Y899804D03*
X1344047D03*
X1340346D03*
X1336646D03*
X1349598Y902993D03*
X1345897D03*
X1342197D03*
X1338496D03*
X1334795D03*
X1347748Y906181D03*
X1344047D03*
X1340346D03*
X1336646D03*
X1349598Y909370D03*
X1345897D03*
X1342197D03*
X1338496D03*
X1334795D03*
X1347748Y912559D03*
X1344047D03*
X1340346D03*
X1336646D03*
X1349598Y915748D03*
X1345897D03*
X1342197D03*
X1338496D03*
X1334795D03*
X1347748Y918937D03*
X1344047D03*
X1340346D03*
X1336646D03*
X1349598Y922126D03*
X1345897D03*
X1342197D03*
X1338496D03*
X1334795D03*
X1347748Y925315D03*
X1344047D03*
X1340346D03*
X1336646D03*
X1349598Y928504D03*
X1345897D03*
X1342197D03*
X1338496D03*
X1334795D03*
X1347748Y931693D03*
X1344047D03*
X1340346D03*
X1336646D03*
X1349598Y934882D03*
X1345897D03*
X1342197D03*
X1338496D03*
X1334795D03*
X1347748Y938071D03*
X1344047D03*
X1340346D03*
X1336646D03*
X1349598Y941260D03*
X1345897D03*
X1342197D03*
X1338496D03*
X1334795D03*
X1347748Y944449D03*
X1344047D03*
X1340346D03*
X1336646D03*
X1349598Y947638D03*
X1345897D03*
X1342197D03*
X1338496D03*
X1334795D03*
X1347748Y950827D03*
X1344047D03*
X1340346D03*
X1336646D03*
X1349598Y954016D03*
X1345897D03*
X1342197D03*
X1338496D03*
X1334795D03*
X1347748Y957205D03*
X1344047D03*
X1340346D03*
X1336646D03*
X1349598Y960394D03*
X1345897D03*
X1342197D03*
X1338496D03*
X1334795D03*
X1347748Y963583D03*
X1344047D03*
X1340346D03*
X1336646D03*
X1349598Y966772D03*
X1345897D03*
X1342197D03*
X1338496D03*
X1334795D03*
X1347748Y969961D03*
X1344047D03*
X1340346D03*
X1336646D03*
X1349598Y973150D03*
X1345897D03*
X1342197D03*
X1338496D03*
X1334795D03*
X1347748Y976339D03*
X1344047D03*
X1340346D03*
X1336646D03*
X1349598Y979528D03*
X1345897D03*
X1342197D03*
X1338496D03*
X1334795D03*
X1347748Y982717D03*
X1344047D03*
X1340346D03*
X1336646D03*
X1349598Y985906D03*
X1345897D03*
X1342197D03*
X1338496D03*
X1334795D03*
X1347748Y989095D03*
X1344047D03*
X1340346D03*
X1336646D03*
X1349598Y992284D03*
X1345897D03*
X1342197D03*
X1338496D03*
X1334795D03*
X1347748Y995473D03*
X1344047D03*
X1340346D03*
X1336646D03*
X1349598Y998662D03*
X1345897D03*
X1342197D03*
X1338496D03*
X1334795D03*
X1347748Y1001851D03*
X1344047D03*
X1340346D03*
X1336646D03*
X1349598Y1005040D03*
X1345897D03*
X1342197D03*
X1338496D03*
X1334795D03*
X1347748Y1008229D03*
X1344047D03*
X1340346D03*
X1336646D03*
X1349598Y1011418D03*
X1345897D03*
X1342197D03*
X1338496D03*
X1334795D03*
X1347079Y1027008D03*
X1343378D03*
X1339677D03*
X1335976D03*
X1348929Y1030197D03*
X1345228D03*
X1341527D03*
X1337827D03*
X1347079Y1033386D03*
X1343378D03*
X1339677D03*
X1335976D03*
X1348929Y1036575D03*
X1345228D03*
X1341527D03*
X1337827D03*
X1347079Y1039764D03*
X1343378D03*
X1339677D03*
X1335976D03*
X1348929Y1042953D03*
X1345228D03*
X1341527D03*
X1337827D03*
X1347079Y1046142D03*
X1343378D03*
X1339677D03*
X1335976D03*
X1348929Y1049331D03*
X1345228D03*
X1341527D03*
X1337827D03*
X1347079Y1052520D03*
X1343378D03*
X1339677D03*
X1335976D03*
X1348929Y1055709D03*
X1345228D03*
X1341527D03*
X1337827D03*
X1347079Y1058898D03*
X1343378D03*
X1339677D03*
X1335976D03*
X1348929Y1062087D03*
X1345228D03*
X1341527D03*
X1337827D03*
X1347079Y1065276D03*
X1343378D03*
X1339677D03*
X1335976D03*
X1348929Y1068465D03*
X1345228D03*
X1341527D03*
X1337827D03*
X1347079Y1071654D03*
X1343378D03*
X1339677D03*
X1335976D03*
X1348929Y1074843D03*
X1345228D03*
X1341527D03*
X1337827D03*
X1347079Y1078032D03*
X1343378D03*
X1339677D03*
X1335976D03*
X1348929Y1081221D03*
X1345228D03*
X1341527D03*
X1337827D03*
X1347079Y1084410D03*
X1343378D03*
X1339677D03*
X1335976D03*
X1348929Y1087599D03*
X1345228D03*
X1341527D03*
X1337827D03*
X1347079Y1090788D03*
X1343378D03*
X1339677D03*
X1335976D03*
X1348929Y1093977D03*
X1345228D03*
X1341527D03*
X1337827D03*
X1347079Y1097166D03*
X1343378D03*
X1339677D03*
X1335976D03*
X1348929Y1100355D03*
X1345228D03*
X1341527D03*
X1337827D03*
X1347079Y1103544D03*
X1343378D03*
X1339677D03*
X1335976D03*
X1348929Y1106733D03*
X1345228D03*
X1341527D03*
X1337827D03*
X1347079Y1109922D03*
X1343378D03*
X1339677D03*
X1335976D03*
X1348929Y1113111D03*
X1345228D03*
X1341527D03*
X1337827D03*
X1347079Y1116300D03*
X1343378D03*
X1339677D03*
X1335976D03*
X1348929Y1119489D03*
X1345228D03*
X1341527D03*
X1337827D03*
X1347079Y1122678D03*
X1343378D03*
X1339677D03*
X1335976D03*
X1348929Y1125867D03*
X1345228D03*
X1341527D03*
X1337827D03*
X1347079Y1129056D03*
X1343378D03*
X1339677D03*
X1335976D03*
X1348929Y1132245D03*
X1345228D03*
X1341527D03*
X1337827D03*
X1347079Y1135433D03*
X1343378D03*
X1339677D03*
X1335976D03*
X1348929Y1138622D03*
X1345228D03*
X1341527D03*
X1337827D03*
X1347079Y1141811D03*
X1343378D03*
X1339677D03*
X1335976D03*
X1348929Y1145000D03*
X1345228D03*
X1341527D03*
X1337827D03*
X1347079Y1148189D03*
X1343378D03*
X1339677D03*
X1335976D03*
X1348929Y1151378D03*
X1345228D03*
X1341527D03*
X1337827D03*
X1347079Y1154567D03*
X1343378D03*
X1339677D03*
X1335976D03*
X1348929Y1157756D03*
X1345228D03*
X1341527D03*
X1337827D03*
X1347079Y1160945D03*
X1343378D03*
X1339677D03*
X1335976D03*
X1348929Y1164134D03*
X1341527D03*
X1337827D03*
X1362551Y874292D03*
X1358850D03*
X1355149D03*
X1351449D03*
X1364401Y877481D03*
X1360701D03*
X1357000D03*
X1353299D03*
X1362551Y880670D03*
X1358850D03*
X1355149D03*
X1351449D03*
X1364401Y883859D03*
X1360701D03*
X1357000D03*
X1353299D03*
X1362551Y887048D03*
X1358850D03*
X1355149D03*
X1351449D03*
X1364401Y890237D03*
X1360701D03*
X1357000D03*
X1353299D03*
X1362551Y893426D03*
X1358850D03*
X1355149D03*
X1351449D03*
X1364401Y896615D03*
X1360701D03*
X1357000D03*
X1353299D03*
X1362551Y899804D03*
X1358850D03*
X1355149D03*
X1351449D03*
X1364401Y902993D03*
X1360701D03*
X1357000D03*
X1353299D03*
X1362551Y906181D03*
X1358850D03*
X1355149D03*
X1351449D03*
X1364401Y909370D03*
X1360701D03*
X1357000D03*
X1353299D03*
X1362551Y912559D03*
X1358850D03*
X1355149D03*
X1351449D03*
X1364401Y915748D03*
X1360701D03*
X1357000D03*
X1353299D03*
X1362551Y918937D03*
X1358850D03*
X1355149D03*
X1351449D03*
X1364401Y922126D03*
X1360701D03*
X1357000D03*
X1353299D03*
X1362551Y925315D03*
X1358850D03*
X1355149D03*
X1351449D03*
X1364401Y928504D03*
X1360701D03*
X1357000D03*
X1353299D03*
X1362551Y931693D03*
X1358850D03*
X1355149D03*
X1351449D03*
X1364401Y934882D03*
X1360701D03*
X1357000D03*
X1353299D03*
X1362551Y938071D03*
X1358850D03*
X1355149D03*
X1351449D03*
X1364401Y941260D03*
X1360701D03*
X1357000D03*
X1353299D03*
X1362551Y944449D03*
X1358850D03*
X1355149D03*
X1351449D03*
X1364401Y947638D03*
X1360701D03*
X1357000D03*
X1353299D03*
X1362551Y950827D03*
X1358850D03*
X1355149D03*
X1351449D03*
X1364401Y954016D03*
X1360701D03*
X1357000D03*
X1353299D03*
X1362551Y957205D03*
X1358850D03*
X1355149D03*
X1351449D03*
X1364401Y960394D03*
X1360701D03*
X1357000D03*
X1353299D03*
X1362551Y963583D03*
X1358850D03*
X1355149D03*
X1351449D03*
X1364401Y966772D03*
X1360701D03*
X1357000D03*
X1353299D03*
X1362551Y969961D03*
X1358850D03*
X1355149D03*
X1351449D03*
X1364401Y973150D03*
X1360701D03*
X1357000D03*
X1353299D03*
X1362551Y976339D03*
X1358850D03*
X1355149D03*
X1351449D03*
X1364401Y979528D03*
X1360701D03*
X1357000D03*
X1353299D03*
X1362551Y982717D03*
X1358850D03*
X1355149D03*
X1351449D03*
X1364401Y985906D03*
X1360701D03*
X1357000D03*
X1353299D03*
X1362551Y989095D03*
X1358850D03*
X1355149D03*
X1351449D03*
X1364401Y992284D03*
X1360701D03*
X1357000D03*
X1353299D03*
X1362551Y995473D03*
X1358850D03*
X1355149D03*
X1351449D03*
X1364401Y998662D03*
X1360701D03*
X1357000D03*
X1353299D03*
X1362551Y1001851D03*
X1358850D03*
X1355149D03*
X1351449D03*
X1364401Y1005040D03*
X1360701D03*
X1357000D03*
X1353299D03*
X1362551Y1008229D03*
X1358850D03*
X1355149D03*
X1351449D03*
X1364401Y1011418D03*
X1360701D03*
X1357000D03*
X1353299D03*
X1361882Y1027008D03*
X1358181D03*
X1354480D03*
X1350779D03*
X1363732Y1030197D03*
X1360031D03*
X1356331D03*
X1352630D03*
X1361882Y1033386D03*
X1358181D03*
X1354480D03*
X1350779D03*
X1363732Y1036575D03*
X1360031D03*
X1356331D03*
X1352630D03*
X1361882Y1039764D03*
X1358181D03*
X1354480D03*
X1350779D03*
X1363732Y1042953D03*
X1360031D03*
X1356331D03*
X1352630D03*
X1361882Y1046142D03*
X1358181D03*
X1354480D03*
X1350779D03*
X1363732Y1049331D03*
X1360031D03*
X1356331D03*
X1352630D03*
X1361882Y1052520D03*
X1358181D03*
X1354480D03*
X1350779D03*
X1363732Y1055709D03*
X1360031D03*
X1356331D03*
X1352630D03*
X1361882Y1058898D03*
X1358181D03*
X1354480D03*
X1350779D03*
X1363732Y1062087D03*
X1360031D03*
X1356331D03*
X1352630D03*
X1361882Y1065276D03*
X1358181D03*
X1354480D03*
X1350779D03*
X1363732Y1068465D03*
X1360031D03*
X1356331D03*
X1352630D03*
X1361882Y1071654D03*
X1358181D03*
X1354480D03*
X1350779D03*
X1363732Y1074843D03*
X1360031D03*
X1356331D03*
X1352630D03*
X1361882Y1078032D03*
X1358181D03*
X1354480D03*
X1350779D03*
X1363732Y1081221D03*
X1360031D03*
X1356331D03*
X1352630D03*
X1361882Y1084410D03*
X1358181D03*
X1354480D03*
X1350779D03*
X1363732Y1087599D03*
X1360031D03*
X1356331D03*
X1352630D03*
X1361882Y1090788D03*
X1358181D03*
X1354480D03*
X1350779D03*
X1363732Y1093977D03*
X1360031D03*
X1356331D03*
X1352630D03*
X1361882Y1097166D03*
X1358181D03*
X1354480D03*
X1350779D03*
X1363732Y1100355D03*
X1360031D03*
X1356331D03*
X1352630D03*
X1361882Y1103544D03*
X1358181D03*
X1354480D03*
X1350779D03*
X1363732Y1106733D03*
X1360031D03*
X1356331D03*
X1352630D03*
X1361882Y1109922D03*
X1358181D03*
X1354480D03*
X1350779D03*
X1363732Y1113111D03*
X1360031D03*
X1356331D03*
X1352630D03*
X1361882Y1116300D03*
X1358181D03*
X1354480D03*
X1350779D03*
X1363732Y1119489D03*
X1360031D03*
X1356331D03*
X1352630D03*
X1361882Y1122678D03*
X1358181D03*
X1354480D03*
X1350779D03*
X1363732Y1125867D03*
X1360031D03*
X1356331D03*
X1352630D03*
X1361882Y1129056D03*
X1358181D03*
X1354480D03*
X1350779D03*
X1363732Y1132245D03*
X1360031D03*
X1356331D03*
X1352630D03*
X1361882Y1135433D03*
X1358181D03*
X1354480D03*
X1350779D03*
X1363732Y1138622D03*
X1360031D03*
X1356331D03*
X1352630D03*
X1361882Y1141811D03*
X1358181D03*
X1354480D03*
X1350779D03*
X1363732Y1145000D03*
X1360031D03*
X1356331D03*
X1352630D03*
X1361882Y1148189D03*
X1358181D03*
X1354480D03*
X1350779D03*
X1363732Y1151378D03*
X1360031D03*
X1356331D03*
X1352630D03*
X1361882Y1154567D03*
X1358181D03*
X1354480D03*
X1350779D03*
X1363732Y1157756D03*
X1360031D03*
X1356331D03*
X1352630D03*
X1361882Y1160945D03*
X1358181D03*
X1354480D03*
X1350779D03*
X1363732Y1164134D03*
X1360031D03*
X1356331D03*
X1352630D03*
X1377354Y874292D03*
X1373653D03*
X1369953D03*
X1379205Y877481D03*
X1375504D03*
X1371803D03*
X1368102D03*
X1377354Y880670D03*
X1373653D03*
X1369953D03*
X1366252D03*
X1379205Y883859D03*
X1375504D03*
X1371803D03*
X1368102D03*
X1377354Y887048D03*
X1373653D03*
X1369953D03*
X1366252D03*
X1379205Y890237D03*
X1375504D03*
X1371803D03*
X1368102D03*
X1377354Y893426D03*
X1373653D03*
X1369953D03*
X1366252D03*
X1379205Y896615D03*
X1375504D03*
X1371803D03*
X1368102D03*
X1377354Y899804D03*
X1373653D03*
X1369953D03*
X1366252D03*
X1379205Y902993D03*
X1375504D03*
X1371803D03*
X1368102D03*
X1377354Y906181D03*
X1373653D03*
X1369953D03*
X1366252D03*
X1379205Y909370D03*
X1375504D03*
X1371803D03*
X1368102D03*
X1377354Y912559D03*
X1373653D03*
X1369953D03*
X1366252D03*
X1379205Y915748D03*
X1375504D03*
X1371803D03*
X1368102D03*
X1377354Y918937D03*
X1373653D03*
X1369953D03*
X1366252D03*
X1379205Y922126D03*
X1375504D03*
X1371803D03*
X1368102D03*
X1377354Y925315D03*
X1373653D03*
X1369953D03*
X1366252D03*
X1379205Y928504D03*
X1375504D03*
X1371803D03*
X1368102D03*
X1377354Y931693D03*
X1373653D03*
X1369953D03*
X1366252D03*
X1379205Y934882D03*
X1375504D03*
X1371803D03*
X1368102D03*
X1377354Y938071D03*
X1373653D03*
X1369953D03*
X1366252D03*
X1379205Y941260D03*
X1375504D03*
X1371803D03*
X1368102D03*
X1377354Y944449D03*
X1373653D03*
X1369953D03*
X1366252D03*
X1379205Y947638D03*
X1375504D03*
X1371803D03*
X1368102D03*
X1377354Y950827D03*
X1373653D03*
X1369953D03*
X1366252D03*
X1379205Y954016D03*
X1375504D03*
X1371803D03*
X1368102D03*
X1377354Y957205D03*
X1373653D03*
X1369953D03*
X1366252D03*
X1379205Y960394D03*
X1375504D03*
X1371803D03*
X1368102D03*
X1377354Y963583D03*
X1373653D03*
X1369953D03*
X1366252D03*
X1379205Y966772D03*
X1375504D03*
X1371803D03*
X1368102D03*
X1377354Y969961D03*
X1373653D03*
X1369953D03*
X1366252D03*
X1379205Y973150D03*
X1375504D03*
X1371803D03*
X1368102D03*
X1377354Y976339D03*
X1373653D03*
X1369953D03*
X1366252D03*
X1379205Y979528D03*
X1375504D03*
X1371803D03*
X1368102D03*
X1377354Y982717D03*
X1373653D03*
X1369953D03*
X1366252D03*
X1379205Y985906D03*
X1375504D03*
X1371803D03*
X1368102D03*
X1377354Y989095D03*
X1373653D03*
X1369953D03*
X1366252D03*
X1379205Y992284D03*
X1375504D03*
X1371803D03*
X1368102D03*
X1377354Y995473D03*
X1373653D03*
X1369953D03*
X1366252D03*
X1379205Y998662D03*
X1375504D03*
X1371803D03*
X1368102D03*
X1377354Y1001851D03*
X1373653D03*
X1369953D03*
X1366252D03*
X1379205Y1005040D03*
X1375504D03*
X1371803D03*
X1368102D03*
X1377354Y1008229D03*
X1373653D03*
X1369953D03*
X1366252D03*
X1379205Y1011418D03*
X1375504D03*
X1371803D03*
X1368102D03*
X1376685Y1027008D03*
X1372984D03*
X1369283D03*
X1365583D03*
X1378535Y1030197D03*
X1374835D03*
X1371134D03*
X1367433D03*
X1376685Y1033386D03*
X1372984D03*
X1369283D03*
X1365583D03*
X1378535Y1036575D03*
X1374835D03*
X1371134D03*
X1367433D03*
X1376685Y1039764D03*
X1372984D03*
X1369283D03*
X1365583D03*
X1378535Y1042953D03*
X1374835D03*
X1371134D03*
X1367433D03*
X1376685Y1046142D03*
X1372984D03*
X1369283D03*
X1365583D03*
X1378535Y1049331D03*
X1374835D03*
X1371134D03*
X1367433D03*
X1376685Y1052520D03*
X1372984D03*
X1369283D03*
X1365583D03*
X1378535Y1055709D03*
X1374835D03*
X1371134D03*
X1367433D03*
X1376685Y1058898D03*
X1372984D03*
X1369283D03*
X1365583D03*
X1378535Y1062087D03*
X1374835D03*
X1371134D03*
X1367433D03*
X1376685Y1065276D03*
X1372984D03*
X1369283D03*
X1365583D03*
X1378535Y1068465D03*
X1374835D03*
X1371134D03*
X1367433D03*
X1376685Y1071654D03*
X1372984D03*
X1369283D03*
X1365583D03*
X1378535Y1074843D03*
X1374835D03*
X1371134D03*
X1367433D03*
X1376685Y1078032D03*
X1372984D03*
X1369283D03*
X1365583D03*
X1378535Y1081221D03*
X1374835D03*
X1371134D03*
X1367433D03*
X1376685Y1084410D03*
X1372984D03*
X1369283D03*
X1365583D03*
X1378535Y1087599D03*
X1374835D03*
X1371134D03*
X1367433D03*
X1376685Y1090788D03*
X1372984D03*
X1369283D03*
X1365583D03*
X1378535Y1093977D03*
X1374835D03*
X1371134D03*
X1367433D03*
X1376685Y1097166D03*
X1372984D03*
X1369283D03*
X1365583D03*
X1378535Y1100355D03*
X1374835D03*
X1371134D03*
X1367433D03*
X1376685Y1103544D03*
X1372984D03*
X1369283D03*
X1365583D03*
X1378535Y1106733D03*
X1374835D03*
X1371134D03*
X1367433D03*
X1376685Y1109922D03*
X1372984D03*
X1369283D03*
X1365583D03*
X1378535Y1113111D03*
X1374835D03*
X1371134D03*
X1367433D03*
X1376685Y1116300D03*
X1372984D03*
X1369283D03*
X1365583D03*
X1378535Y1119489D03*
X1374835D03*
X1371134D03*
X1367433D03*
X1376685Y1122678D03*
X1372984D03*
X1369283D03*
X1365583D03*
X1378535Y1125867D03*
X1374835D03*
X1371134D03*
X1367433D03*
X1376685Y1129056D03*
X1372984D03*
X1369283D03*
X1365583D03*
X1378535Y1132245D03*
X1374835D03*
X1371134D03*
X1367433D03*
X1376685Y1135433D03*
X1372984D03*
X1369283D03*
X1365583D03*
X1378535Y1138622D03*
X1374835D03*
X1371134D03*
X1367433D03*
X1376685Y1141811D03*
X1372984D03*
X1369283D03*
X1365583D03*
X1378535Y1145000D03*
X1374835D03*
X1371134D03*
X1367433D03*
X1376685Y1148189D03*
X1372984D03*
X1369283D03*
X1365583D03*
X1378535Y1151378D03*
X1374835D03*
X1371134D03*
X1367433D03*
X1376685Y1154567D03*
X1372984D03*
X1369283D03*
X1365583D03*
X1378535Y1157756D03*
X1374835D03*
X1371134D03*
X1367433D03*
X1376685Y1160945D03*
X1372984D03*
X1369283D03*
X1365583D03*
X1378535Y1164134D03*
X1374835D03*
X1371134D03*
X1392157Y874292D03*
X1384756D03*
X1381055D03*
X1394008Y877481D03*
X1390307D03*
X1386606D03*
X1382905D03*
X1392157Y880670D03*
X1388457D03*
X1384756D03*
X1381055D03*
X1394008Y883859D03*
X1390307D03*
X1386606D03*
X1382905D03*
X1392157Y887048D03*
X1388457D03*
X1384756D03*
X1381055D03*
X1394008Y890237D03*
X1390307D03*
X1386606D03*
X1382905D03*
X1392157Y893426D03*
X1388457D03*
X1384756D03*
X1381055D03*
X1394008Y896615D03*
X1390307D03*
X1386606D03*
X1382905D03*
X1392157Y899804D03*
X1388457D03*
X1384756D03*
X1381055D03*
X1394008Y902993D03*
X1390307D03*
X1386606D03*
X1382905D03*
X1392157Y906181D03*
X1388457D03*
X1384756D03*
X1381055D03*
X1394008Y909370D03*
X1390307D03*
X1386606D03*
X1382905D03*
X1392157Y912559D03*
X1388457D03*
X1384756D03*
X1381055D03*
X1394008Y915748D03*
X1390307D03*
X1386606D03*
X1382905D03*
X1392157Y918937D03*
X1388457D03*
X1384756D03*
X1381055D03*
X1394008Y922126D03*
X1390307D03*
X1386606D03*
X1382905D03*
X1392157Y925315D03*
X1388457D03*
X1384756D03*
X1381055D03*
X1394008Y928504D03*
X1390307D03*
X1386606D03*
X1382905D03*
X1392157Y931693D03*
X1388457D03*
X1384756D03*
X1381055D03*
X1394008Y934882D03*
X1390307D03*
X1386606D03*
X1382905D03*
X1392157Y938071D03*
X1388457D03*
X1384756D03*
X1381055D03*
X1394008Y941260D03*
X1390307D03*
X1386606D03*
X1382905D03*
X1392157Y944449D03*
X1388457D03*
X1384756D03*
X1381055D03*
X1394008Y947638D03*
X1390307D03*
X1386606D03*
X1382905D03*
X1392157Y950827D03*
X1388457D03*
X1384756D03*
X1381055D03*
X1394008Y954016D03*
X1390307D03*
X1386606D03*
X1382905D03*
X1392157Y957205D03*
X1388457D03*
X1384756D03*
X1381055D03*
X1394008Y960394D03*
X1390307D03*
X1386606D03*
X1382905D03*
X1392157Y963583D03*
X1388457D03*
X1384756D03*
X1381055D03*
X1394008Y966772D03*
X1390307D03*
X1386606D03*
X1382905D03*
X1392157Y969961D03*
X1388457D03*
X1384756D03*
X1381055D03*
X1394008Y973150D03*
X1390307D03*
X1386606D03*
X1382905D03*
X1392157Y976339D03*
X1388457D03*
X1384756D03*
X1381055D03*
X1394008Y979528D03*
X1390307D03*
X1386606D03*
X1382905D03*
X1392157Y982717D03*
X1388457D03*
X1384756D03*
X1381055D03*
X1394008Y985906D03*
X1390307D03*
X1386606D03*
X1382905D03*
X1392157Y989095D03*
X1388457D03*
X1384756D03*
X1381055D03*
X1394008Y992284D03*
X1390307D03*
X1386606D03*
X1382905D03*
X1381055Y995473D03*
Y1001851D03*
Y1008229D03*
X1380386Y1027008D03*
X1382236Y1030197D03*
X1380386Y1033386D03*
X1382236Y1036575D03*
X1380386Y1039764D03*
X1382236Y1042953D03*
X1391488Y1046142D03*
X1387787D03*
X1384086D03*
X1380386D03*
X1393338Y1049331D03*
X1389638D03*
X1385937D03*
X1382236D03*
X1391488Y1052520D03*
X1387787D03*
X1384086D03*
X1380386D03*
X1393338Y1055709D03*
X1389638D03*
X1385937D03*
X1382236D03*
X1391488Y1058898D03*
X1387787D03*
X1384086D03*
X1380386D03*
X1393338Y1062087D03*
X1389638D03*
X1385937D03*
X1382236D03*
X1391488Y1065276D03*
X1387787D03*
X1384086D03*
X1380386D03*
X1393338Y1068465D03*
X1389638D03*
X1385937D03*
X1382236D03*
X1391488Y1071654D03*
X1387787D03*
X1384086D03*
X1380386D03*
X1393338Y1074843D03*
X1389638D03*
X1385937D03*
X1382236D03*
X1391488Y1078032D03*
X1387787D03*
X1384086D03*
X1380386D03*
X1393338Y1081221D03*
X1389638D03*
X1385937D03*
X1382236D03*
X1391488Y1084410D03*
X1387787D03*
X1384086D03*
X1380386D03*
X1393338Y1087599D03*
X1389638D03*
X1385937D03*
X1382236D03*
X1391488Y1090788D03*
X1387787D03*
X1384086D03*
X1380386D03*
X1393338Y1093977D03*
X1389638D03*
X1385937D03*
X1382236D03*
X1391488Y1097166D03*
X1387787D03*
X1384086D03*
X1380386D03*
X1393338Y1100355D03*
X1389638D03*
X1385937D03*
X1382236D03*
X1391488Y1103544D03*
X1387787D03*
X1384086D03*
X1380386D03*
X1393338Y1106733D03*
X1389638D03*
X1385937D03*
X1382236D03*
X1391488Y1109922D03*
X1387787D03*
X1384086D03*
X1380386D03*
X1393338Y1113111D03*
X1389638D03*
X1385937D03*
X1382236D03*
X1391488Y1116300D03*
X1387787D03*
X1384086D03*
X1380386D03*
X1393338Y1119489D03*
X1389638D03*
X1385937D03*
X1382236D03*
X1391488Y1122678D03*
X1387787D03*
X1384086D03*
X1380386D03*
X1393338Y1125867D03*
X1389638D03*
X1385937D03*
X1382236D03*
X1391488Y1129056D03*
X1387787D03*
X1384086D03*
X1380386D03*
X1393338Y1132245D03*
X1389638D03*
X1385937D03*
X1382236D03*
X1391488Y1135433D03*
X1387787D03*
X1384086D03*
X1380386D03*
X1393338Y1138622D03*
X1389638D03*
X1385937D03*
X1382236D03*
X1391488Y1141811D03*
X1387787D03*
X1384086D03*
X1380386D03*
X1393338Y1145000D03*
X1389638D03*
X1385937D03*
X1382236D03*
X1391488Y1148189D03*
X1387787D03*
X1384086D03*
X1380386D03*
X1393338Y1151378D03*
X1389638D03*
X1385937D03*
X1382236D03*
X1391488Y1154567D03*
X1387787D03*
X1384086D03*
X1380386D03*
X1393338Y1157756D03*
X1389638D03*
X1385937D03*
X1382236D03*
X1391488Y1160945D03*
X1387787D03*
X1384086D03*
X1380386D03*
X1393338Y1164134D03*
X1385937D03*
X1382236D03*
X1406960Y874292D03*
X1403260D03*
X1399559D03*
X1395858D03*
X1408811Y877481D03*
X1405110D03*
X1401409D03*
X1397709D03*
X1406960Y880670D03*
X1403260D03*
X1399559D03*
X1395858D03*
X1408811Y883859D03*
X1405110D03*
X1401409D03*
X1397709D03*
X1406960Y887048D03*
X1403260D03*
X1399559D03*
X1395858D03*
X1408811Y890237D03*
X1405110D03*
X1401409D03*
X1397709D03*
X1406960Y893426D03*
X1403260D03*
X1399559D03*
X1395858D03*
X1408811Y896615D03*
X1405110D03*
X1401409D03*
X1397709D03*
X1406960Y899804D03*
X1403260D03*
X1399559D03*
X1395858D03*
X1408811Y902993D03*
X1405110D03*
X1401409D03*
X1397709D03*
X1406960Y906181D03*
X1403260D03*
X1399559D03*
X1395858D03*
X1408811Y909370D03*
X1405110D03*
X1401409D03*
X1397709D03*
X1406960Y912559D03*
X1403260D03*
X1399559D03*
X1395858D03*
X1408811Y915748D03*
X1405110D03*
X1401409D03*
X1397709D03*
X1406960Y918937D03*
X1403260D03*
X1399559D03*
X1395858D03*
X1408811Y922126D03*
X1405110D03*
X1401409D03*
X1397709D03*
X1406960Y925315D03*
X1403260D03*
X1399559D03*
X1395858D03*
X1408811Y928504D03*
X1405110D03*
X1401409D03*
X1397709D03*
X1406960Y931693D03*
X1403260D03*
X1399559D03*
X1395858D03*
X1408811Y934882D03*
X1405110D03*
X1401409D03*
X1397709D03*
X1406960Y938071D03*
X1403260D03*
X1399559D03*
X1395858D03*
X1408811Y941260D03*
X1405110D03*
X1401409D03*
X1397709D03*
X1406960Y944449D03*
X1403260D03*
X1399559D03*
X1395858D03*
X1408811Y947638D03*
X1405110D03*
X1401409D03*
X1397709D03*
X1406960Y950827D03*
X1403260D03*
X1399559D03*
X1395858D03*
X1408811Y954016D03*
X1405110D03*
X1401409D03*
X1397709D03*
X1406960Y957205D03*
X1403260D03*
X1399559D03*
X1395858D03*
X1408811Y960394D03*
X1405110D03*
X1401409D03*
X1397709D03*
X1406960Y963583D03*
X1403260D03*
X1399559D03*
X1395858D03*
X1408811Y966772D03*
X1405110D03*
X1401409D03*
X1397709D03*
X1406960Y969961D03*
X1403260D03*
X1399559D03*
X1395858D03*
X1408811Y973150D03*
X1405110D03*
X1401409D03*
X1397709D03*
X1406960Y976339D03*
X1403260D03*
X1399559D03*
X1395858D03*
X1408811Y979528D03*
X1405110D03*
X1401409D03*
X1397709D03*
X1406960Y982717D03*
X1403260D03*
X1399559D03*
X1395858D03*
X1408811Y985906D03*
X1405110D03*
X1401409D03*
X1397709D03*
X1406960Y989095D03*
X1403260D03*
X1399559D03*
X1395858D03*
X1408811Y992284D03*
X1405110D03*
X1401409D03*
X1397709D03*
X1406291Y1046142D03*
X1402590D03*
X1398890D03*
X1395189D03*
X1408142Y1049331D03*
X1404441D03*
X1400740D03*
X1397039D03*
X1406291Y1052520D03*
X1402590D03*
X1398890D03*
X1395189D03*
X1408142Y1055709D03*
X1404441D03*
X1400740D03*
X1397039D03*
X1406291Y1058898D03*
X1402590D03*
X1398890D03*
X1395189D03*
X1408142Y1062087D03*
X1404441D03*
X1400740D03*
X1397039D03*
X1406291Y1065276D03*
X1402590D03*
X1398890D03*
X1395189D03*
X1408142Y1068465D03*
X1404441D03*
X1400740D03*
X1397039D03*
X1406291Y1071654D03*
X1402590D03*
X1398890D03*
X1395189D03*
X1408142Y1074843D03*
X1404441D03*
X1400740D03*
X1397039D03*
X1406291Y1078032D03*
X1402590D03*
X1398890D03*
X1395189D03*
X1408142Y1081221D03*
X1404441D03*
X1400740D03*
X1397039D03*
X1406291Y1084410D03*
X1402590D03*
X1398890D03*
X1395189D03*
X1408142Y1087599D03*
X1404441D03*
X1400740D03*
X1397039D03*
X1406291Y1090788D03*
X1402590D03*
X1398890D03*
X1395189D03*
X1408142Y1093977D03*
X1404441D03*
X1400740D03*
X1397039D03*
X1406291Y1097166D03*
X1402590D03*
X1398890D03*
X1395189D03*
X1408142Y1100355D03*
X1404441D03*
X1400740D03*
X1397039D03*
X1406291Y1103544D03*
X1402590D03*
X1398890D03*
X1395189D03*
X1408142Y1106733D03*
X1404441D03*
X1400740D03*
X1397039D03*
X1406291Y1109922D03*
X1402590D03*
X1398890D03*
X1395189D03*
X1408142Y1113111D03*
X1404441D03*
X1400740D03*
X1397039D03*
X1406291Y1116300D03*
X1402590D03*
X1398890D03*
X1395189D03*
X1408142Y1119489D03*
X1404441D03*
X1400740D03*
X1397039D03*
X1406291Y1122678D03*
X1402590D03*
X1398890D03*
X1395189D03*
X1408142Y1125867D03*
X1404441D03*
X1400740D03*
X1397039D03*
X1406291Y1129056D03*
X1402590D03*
X1398890D03*
X1395189D03*
X1408142Y1132245D03*
X1404441D03*
X1400740D03*
X1397039D03*
X1406291Y1135433D03*
X1402590D03*
X1398890D03*
X1395189D03*
X1408142Y1138622D03*
X1404441D03*
X1400740D03*
X1397039D03*
X1406291Y1141811D03*
X1402590D03*
X1398890D03*
X1395189D03*
X1408142Y1145000D03*
X1404441D03*
X1400740D03*
X1397039D03*
X1406291Y1148189D03*
X1402590D03*
X1398890D03*
X1395189D03*
X1408142Y1151378D03*
X1404441D03*
X1400740D03*
X1397039D03*
X1406291Y1154567D03*
X1402590D03*
X1398890D03*
X1395189D03*
X1408142Y1157756D03*
X1404441D03*
X1400740D03*
X1397039D03*
X1406291Y1160945D03*
X1402590D03*
X1398890D03*
X1395189D03*
X1408142Y1164134D03*
X1404441D03*
X1400740D03*
X1397039D03*
X1423614Y877481D03*
X1419913D03*
X1412512D03*
X1421764Y880670D03*
X1410661D03*
X1423614Y883859D03*
X1419913D03*
X1412512D03*
X1421764Y887048D03*
X1410661D03*
X1423614Y890237D03*
X1419913D03*
X1412512D03*
X1421764Y893426D03*
X1410661D03*
X1423614Y896615D03*
X1419913D03*
X1412512D03*
X1421764Y899804D03*
X1410661D03*
X1423614Y902993D03*
X1419913D03*
X1412512D03*
X1421764Y906181D03*
X1410661D03*
X1423614Y909370D03*
X1419913D03*
X1412512D03*
X1421764Y912559D03*
X1410661D03*
X1423614Y915748D03*
X1419913D03*
X1412512D03*
X1421764Y918937D03*
X1410661D03*
X1423614Y922126D03*
X1419913D03*
X1412512D03*
X1421764Y925315D03*
X1410661D03*
X1423614Y928504D03*
X1419913D03*
X1412512D03*
X1421764Y931693D03*
X1410661D03*
X1423614Y934882D03*
X1419913D03*
X1412512D03*
X1421764Y938071D03*
X1410661D03*
X1423614Y941260D03*
X1419913D03*
X1412512D03*
X1421764Y944449D03*
X1410661D03*
X1423614Y947638D03*
X1419913D03*
X1412512D03*
X1421764Y950827D03*
X1410661D03*
X1423614Y954016D03*
X1419913D03*
X1412512D03*
X1421764Y957205D03*
X1410661D03*
X1423614Y960394D03*
X1419913D03*
X1412512D03*
X1421764Y963583D03*
X1410661D03*
X1423614Y966772D03*
X1419913D03*
X1412512D03*
X1421764Y969961D03*
X1410661D03*
X1423614Y973150D03*
X1419913D03*
X1412512D03*
X1421764Y976339D03*
X1410661D03*
X1423614Y979528D03*
X1419913D03*
X1412512D03*
X1421764Y982717D03*
X1410661D03*
X1423614Y985906D03*
X1419913D03*
X1412512D03*
X1421764Y989095D03*
X1410661D03*
X1423614Y992284D03*
X1419913D03*
X1412512D03*
X1421094Y1046142D03*
X1413693D03*
X1409992D03*
X1422945Y1049331D03*
X1411842D03*
X1421094Y1052520D03*
X1413693D03*
X1409992D03*
X1422945Y1055709D03*
X1411842D03*
X1421094Y1058898D03*
X1413693D03*
X1409992D03*
X1422945Y1062087D03*
X1411842D03*
X1421094Y1065276D03*
X1413693D03*
X1409992D03*
X1422945Y1068465D03*
X1411842D03*
X1421094Y1071654D03*
X1413693D03*
X1409992D03*
X1422945Y1074843D03*
X1411842D03*
X1421094Y1078032D03*
X1413693D03*
X1409992D03*
X1422945Y1081221D03*
X1411842D03*
X1421094Y1084410D03*
X1413693D03*
X1409992D03*
X1422945Y1087599D03*
X1411842D03*
X1421094Y1090788D03*
X1413693D03*
X1409992D03*
X1422945Y1093977D03*
X1411842D03*
X1421094Y1097166D03*
X1413693D03*
X1409992D03*
X1422945Y1100355D03*
X1411842D03*
X1421094Y1103544D03*
X1413693D03*
X1409992D03*
X1422945Y1106733D03*
X1411842D03*
X1421094Y1109922D03*
X1413693D03*
X1409992D03*
X1422945Y1113111D03*
X1411842D03*
X1421094Y1116300D03*
X1413693D03*
X1409992D03*
X1422945Y1119489D03*
X1411842D03*
X1421094Y1122678D03*
X1413693D03*
X1409992D03*
X1422945Y1125867D03*
X1411842D03*
X1421094Y1129056D03*
X1413693D03*
X1409992D03*
X1422945Y1132245D03*
X1411842D03*
X1421094Y1135433D03*
X1413693D03*
X1409992D03*
X1422945Y1138622D03*
X1411842D03*
X1421094Y1141811D03*
X1413693D03*
X1409992D03*
X1422945Y1145000D03*
X1411842D03*
X1421094Y1148189D03*
X1413693D03*
X1409992D03*
X1422945Y1151378D03*
X1411842D03*
X1421094Y1154567D03*
X1413693D03*
X1409992D03*
X1422945Y1157756D03*
X1411842D03*
X1421094Y1160945D03*
X1413693D03*
X1409992D03*
X1436567Y874292D03*
X1432866D03*
X1429165D03*
X1425464D03*
X1438417Y877481D03*
X1434716D03*
X1431016D03*
X1427315D03*
X1436567Y880670D03*
X1432866D03*
X1429165D03*
X1425464D03*
X1438417Y883859D03*
X1434716D03*
X1431016D03*
X1427315D03*
X1436567Y887048D03*
X1432866D03*
X1429165D03*
X1425464D03*
X1438417Y890237D03*
X1434716D03*
X1431016D03*
X1427315D03*
X1436567Y893426D03*
X1432866D03*
X1429165D03*
X1425464D03*
X1438417Y896615D03*
X1434716D03*
X1431016D03*
X1427315D03*
X1436567Y899804D03*
X1432866D03*
X1429165D03*
X1425464D03*
X1438417Y902993D03*
X1434716D03*
X1431016D03*
X1427315D03*
X1436567Y906181D03*
X1432866D03*
X1429165D03*
X1425464D03*
X1438417Y909370D03*
X1434716D03*
X1431016D03*
X1427315D03*
X1436567Y912559D03*
X1432866D03*
X1429165D03*
X1425464D03*
X1438417Y915748D03*
X1434716D03*
X1431016D03*
X1427315D03*
X1436567Y918937D03*
X1432866D03*
X1429165D03*
X1425464D03*
X1438417Y922126D03*
X1434716D03*
X1431016D03*
X1427315D03*
X1436567Y925315D03*
X1432866D03*
X1429165D03*
X1425464D03*
X1438417Y928504D03*
X1434716D03*
X1431016D03*
X1427315D03*
X1436567Y931693D03*
X1432866D03*
X1429165D03*
X1425464D03*
X1438417Y934882D03*
X1434716D03*
X1431016D03*
X1427315D03*
X1436567Y938071D03*
X1432866D03*
X1429165D03*
X1425464D03*
X1438417Y941260D03*
X1434716D03*
X1431016D03*
X1427315D03*
X1436567Y944449D03*
X1432866D03*
X1429165D03*
X1425464D03*
X1438417Y947638D03*
X1434716D03*
X1431016D03*
X1427315D03*
X1436567Y950827D03*
X1432866D03*
X1429165D03*
X1425464D03*
X1438417Y954016D03*
X1434716D03*
X1431016D03*
X1427315D03*
X1436567Y957205D03*
X1432866D03*
X1429165D03*
X1425464D03*
X1438417Y960394D03*
X1434716D03*
X1431016D03*
X1427315D03*
X1436567Y963583D03*
X1432866D03*
X1429165D03*
X1425464D03*
X1438417Y966772D03*
X1434716D03*
X1431016D03*
X1427315D03*
X1436567Y969961D03*
X1432866D03*
X1429165D03*
X1425464D03*
X1438417Y973150D03*
X1434716D03*
X1431016D03*
X1427315D03*
X1436567Y976339D03*
X1432866D03*
X1429165D03*
X1425464D03*
X1438417Y979528D03*
X1434716D03*
X1431016D03*
X1427315D03*
X1436567Y982717D03*
X1432866D03*
X1429165D03*
X1425464D03*
X1438417Y985906D03*
X1434716D03*
X1431016D03*
X1427315D03*
X1436567Y989095D03*
X1432866D03*
X1429165D03*
X1425464D03*
X1438417Y992284D03*
X1434716D03*
X1431016D03*
X1427315D03*
X1435897Y1046142D03*
X1432197D03*
X1428496D03*
X1424795D03*
X1437748Y1049331D03*
X1434047D03*
X1430346D03*
X1426646D03*
X1435897Y1052520D03*
X1432197D03*
X1428496D03*
X1424795D03*
X1437748Y1055709D03*
X1434047D03*
X1430346D03*
X1426646D03*
X1435897Y1058898D03*
X1432197D03*
X1428496D03*
X1424795D03*
X1437748Y1062087D03*
X1434047D03*
X1430346D03*
X1426646D03*
X1435897Y1065276D03*
X1432197D03*
X1428496D03*
X1424795D03*
X1437748Y1068465D03*
X1434047D03*
X1430346D03*
X1426646D03*
X1435897Y1071654D03*
X1432197D03*
X1428496D03*
X1424795D03*
X1437748Y1074843D03*
X1434047D03*
X1430346D03*
X1426646D03*
X1435897Y1078032D03*
X1432197D03*
X1428496D03*
X1424795D03*
X1437748Y1081221D03*
X1434047D03*
X1430346D03*
X1426646D03*
X1435897Y1084410D03*
X1432197D03*
X1428496D03*
X1424795D03*
X1437748Y1087599D03*
X1434047D03*
X1430346D03*
X1426646D03*
X1435897Y1090788D03*
X1432197D03*
X1428496D03*
X1424795D03*
X1437748Y1093977D03*
X1434047D03*
X1430346D03*
X1426646D03*
X1435897Y1097166D03*
X1432197D03*
X1428496D03*
X1424795D03*
X1437748Y1100355D03*
X1434047D03*
X1430346D03*
X1426646D03*
X1435897Y1103544D03*
X1432197D03*
X1428496D03*
X1424795D03*
X1437748Y1106733D03*
X1434047D03*
X1430346D03*
X1426646D03*
X1435897Y1109922D03*
X1432197D03*
X1428496D03*
X1424795D03*
X1437748Y1113111D03*
X1434047D03*
X1430346D03*
X1426646D03*
X1435897Y1116300D03*
X1432197D03*
X1428496D03*
X1424795D03*
X1437748Y1119489D03*
X1434047D03*
X1430346D03*
X1426646D03*
X1435897Y1122678D03*
X1432197D03*
X1428496D03*
X1424795D03*
X1437748Y1125867D03*
X1434047D03*
X1430346D03*
X1426646D03*
X1435897Y1129056D03*
X1432197D03*
X1428496D03*
X1424795D03*
X1437748Y1132245D03*
X1434047D03*
X1430346D03*
X1426646D03*
X1435897Y1135433D03*
X1432197D03*
X1428496D03*
X1424795D03*
X1437748Y1138622D03*
X1434047D03*
X1430346D03*
X1426646D03*
X1435897Y1141811D03*
X1432197D03*
X1428496D03*
X1424795D03*
X1437748Y1145000D03*
X1434047D03*
X1430346D03*
X1426646D03*
X1435897Y1148189D03*
X1432197D03*
X1428496D03*
X1424795D03*
X1437748Y1151378D03*
X1434047D03*
X1430346D03*
X1426646D03*
X1435897Y1154567D03*
X1432197D03*
X1428496D03*
X1424795D03*
X1437748Y1157756D03*
X1434047D03*
X1430346D03*
X1426646D03*
X1435897Y1160945D03*
X1432197D03*
X1428496D03*
X1424795D03*
X1437748Y1164134D03*
X1434047D03*
X1430346D03*
X1426646D03*
X1451370Y874292D03*
X1447669D03*
X1440268D03*
X1453220Y877481D03*
X1449520D03*
X1445819D03*
X1442118D03*
X1451370Y880670D03*
X1447669D03*
X1443968D03*
X1440268D03*
X1453220Y883859D03*
X1449520D03*
X1445819D03*
X1442118D03*
X1451370Y887048D03*
X1447669D03*
X1443968D03*
X1440268D03*
X1453220Y890237D03*
X1449520D03*
X1445819D03*
X1442118D03*
X1451370Y893426D03*
X1447669D03*
X1443968D03*
X1440268D03*
X1453220Y896615D03*
X1449520D03*
X1445819D03*
X1442118D03*
X1451370Y899804D03*
X1447669D03*
X1443968D03*
X1440268D03*
X1453220Y902993D03*
X1449520D03*
X1445819D03*
X1442118D03*
X1451370Y906181D03*
X1447669D03*
X1443968D03*
X1440268D03*
X1453220Y909370D03*
X1449520D03*
X1445819D03*
X1442118D03*
X1451370Y912559D03*
X1447669D03*
X1443968D03*
X1440268D03*
X1453220Y915748D03*
X1449520D03*
X1445819D03*
X1442118D03*
X1451370Y918937D03*
X1447669D03*
X1443968D03*
X1440268D03*
X1453220Y922126D03*
X1449520D03*
X1445819D03*
X1442118D03*
X1451370Y925315D03*
X1447669D03*
X1443968D03*
X1440268D03*
X1453220Y928504D03*
X1449520D03*
X1445819D03*
X1442118D03*
X1451370Y931693D03*
X1447669D03*
X1443968D03*
X1440268D03*
X1453220Y934882D03*
X1449520D03*
X1445819D03*
X1442118D03*
X1451370Y938071D03*
X1447669D03*
X1443968D03*
X1440268D03*
X1453220Y941260D03*
X1449520D03*
X1445819D03*
X1442118D03*
X1451370Y944449D03*
X1447669D03*
X1443968D03*
X1440268D03*
X1453220Y947638D03*
X1449520D03*
X1445819D03*
X1442118D03*
X1451370Y950827D03*
X1447669D03*
X1443968D03*
X1440268D03*
X1453220Y954016D03*
X1449520D03*
X1445819D03*
X1442118D03*
X1451370Y957205D03*
X1447669D03*
X1443968D03*
X1440268D03*
X1453220Y960394D03*
X1449520D03*
X1445819D03*
X1442118D03*
X1451370Y963583D03*
X1447669D03*
X1443968D03*
X1440268D03*
X1453220Y966772D03*
X1449520D03*
X1445819D03*
X1442118D03*
X1451370Y969961D03*
X1447669D03*
X1443968D03*
X1440268D03*
X1453220Y973150D03*
X1449520D03*
X1445819D03*
X1442118D03*
X1451370Y976339D03*
X1447669D03*
X1443968D03*
X1440268D03*
X1453220Y979528D03*
X1449520D03*
X1445819D03*
X1442118D03*
X1451370Y982717D03*
X1447669D03*
X1443968D03*
X1440268D03*
X1453220Y985906D03*
X1449520D03*
X1445819D03*
X1442118D03*
X1451370Y989095D03*
X1447669D03*
X1443968D03*
X1440268D03*
X1453220Y992284D03*
X1449520D03*
X1445819D03*
X1442118D03*
X1451370Y995473D03*
X1453220Y998662D03*
X1451370Y1001851D03*
X1453220Y1005040D03*
X1451370Y1008229D03*
X1453220Y1011418D03*
X1452551Y1030197D03*
Y1036575D03*
Y1042953D03*
X1450701Y1046142D03*
X1447000D03*
X1443299D03*
X1439598D03*
X1452551Y1049331D03*
X1448850D03*
X1445149D03*
X1441449D03*
X1450701Y1052520D03*
X1447000D03*
X1443299D03*
X1439598D03*
X1452551Y1055709D03*
X1448850D03*
X1445149D03*
X1441449D03*
X1450701Y1058898D03*
X1447000D03*
X1443299D03*
X1439598D03*
X1452551Y1062087D03*
X1448850D03*
X1445149D03*
X1441449D03*
X1450701Y1065276D03*
X1447000D03*
X1443299D03*
X1439598D03*
X1452551Y1068465D03*
X1448850D03*
X1445149D03*
X1441449D03*
X1450701Y1071654D03*
X1447000D03*
X1443299D03*
X1439598D03*
X1452551Y1074843D03*
X1448850D03*
X1445149D03*
X1441449D03*
X1450701Y1078032D03*
X1447000D03*
X1443299D03*
X1439598D03*
X1452551Y1081221D03*
X1448850D03*
X1445149D03*
X1441449D03*
X1450701Y1084410D03*
X1447000D03*
X1443299D03*
X1439598D03*
X1452551Y1087599D03*
X1448850D03*
X1445149D03*
X1441449D03*
X1450701Y1090788D03*
X1447000D03*
X1443299D03*
X1439598D03*
X1452551Y1093977D03*
X1448850D03*
X1445149D03*
X1441449D03*
X1450701Y1097166D03*
X1447000D03*
X1443299D03*
X1439598D03*
X1452551Y1100355D03*
X1448850D03*
X1445149D03*
X1441449D03*
X1450701Y1103544D03*
X1447000D03*
X1443299D03*
X1439598D03*
X1452551Y1106733D03*
X1448850D03*
X1445149D03*
X1441449D03*
X1450701Y1109922D03*
X1447000D03*
X1443299D03*
X1439598D03*
X1452551Y1113111D03*
X1448850D03*
X1445149D03*
X1441449D03*
X1450701Y1116300D03*
X1447000D03*
X1443299D03*
X1439598D03*
X1452551Y1119489D03*
X1448850D03*
X1445149D03*
X1441449D03*
X1450701Y1122678D03*
X1447000D03*
X1443299D03*
X1439598D03*
X1452551Y1125867D03*
X1448850D03*
X1445149D03*
X1441449D03*
X1450701Y1129056D03*
X1447000D03*
X1443299D03*
X1439598D03*
X1452551Y1132245D03*
X1448850D03*
X1445149D03*
X1441449D03*
X1450701Y1135433D03*
X1447000D03*
X1443299D03*
X1439598D03*
X1452551Y1138622D03*
X1448850D03*
X1445149D03*
X1441449D03*
X1450701Y1141811D03*
X1447000D03*
X1443299D03*
X1439598D03*
X1452551Y1145000D03*
X1448850D03*
X1445149D03*
X1441449D03*
X1450701Y1148189D03*
X1447000D03*
X1443299D03*
X1439598D03*
X1452551Y1151378D03*
X1448850D03*
X1445149D03*
X1441449D03*
X1450701Y1154567D03*
X1447000D03*
X1443299D03*
X1439598D03*
X1452551Y1157756D03*
X1448850D03*
X1445149D03*
X1441449D03*
X1450701Y1160945D03*
X1447000D03*
X1443299D03*
X1439598D03*
X1452551Y1164134D03*
X1448850D03*
X1441449D03*
X1462472Y874292D03*
X1458771D03*
X1455071D03*
X1468023Y877481D03*
X1464323D03*
X1460622D03*
X1456921D03*
X1466173Y880670D03*
X1462472D03*
X1458771D03*
X1455071D03*
X1468023Y883859D03*
X1464323D03*
X1460622D03*
X1456921D03*
X1466173Y887048D03*
X1462472D03*
X1458771D03*
X1455071D03*
X1468023Y890237D03*
X1464323D03*
X1460622D03*
X1456921D03*
X1466173Y893426D03*
X1462472D03*
X1458771D03*
X1455071D03*
X1468023Y896615D03*
X1464323D03*
X1460622D03*
X1456921D03*
X1466173Y899804D03*
X1462472D03*
X1458771D03*
X1455071D03*
X1468023Y902993D03*
X1464323D03*
X1460622D03*
X1456921D03*
X1466173Y906181D03*
X1462472D03*
X1458771D03*
X1455071D03*
X1468023Y909370D03*
X1464323D03*
X1460622D03*
X1456921D03*
X1466173Y912559D03*
X1462472D03*
X1458771D03*
X1455071D03*
X1468023Y915748D03*
X1464323D03*
X1460622D03*
X1456921D03*
X1466173Y918937D03*
X1462472D03*
X1458771D03*
X1455071D03*
X1468023Y922126D03*
X1464323D03*
X1460622D03*
X1456921D03*
X1466173Y925315D03*
X1462472D03*
X1458771D03*
X1455071D03*
X1468023Y928504D03*
X1464323D03*
X1460622D03*
X1456921D03*
X1466173Y931693D03*
X1462472D03*
X1458771D03*
X1455071D03*
X1468023Y934882D03*
X1464323D03*
X1460622D03*
X1456921D03*
X1466173Y938071D03*
X1462472D03*
X1458771D03*
X1455071D03*
X1468023Y941260D03*
X1464323D03*
X1460622D03*
X1456921D03*
X1466173Y944449D03*
X1462472D03*
X1458771D03*
X1455071D03*
X1468023Y947638D03*
X1464323D03*
X1460622D03*
X1456921D03*
X1466173Y950827D03*
X1462472D03*
X1458771D03*
X1455071D03*
X1468023Y954016D03*
X1464323D03*
X1460622D03*
X1456921D03*
X1466173Y957205D03*
X1462472D03*
X1458771D03*
X1455071D03*
X1468023Y960394D03*
X1464323D03*
X1460622D03*
X1456921D03*
X1466173Y963583D03*
X1462472D03*
X1458771D03*
X1455071D03*
X1468023Y966772D03*
X1464323D03*
X1460622D03*
X1456921D03*
X1466173Y969961D03*
X1462472D03*
X1458771D03*
X1455071D03*
X1468023Y973150D03*
X1464323D03*
X1460622D03*
X1456921D03*
X1466173Y976339D03*
X1462472D03*
X1458771D03*
X1455071D03*
X1468023Y979528D03*
X1464323D03*
X1460622D03*
X1456921D03*
X1466173Y982717D03*
X1462472D03*
X1458771D03*
X1455071D03*
X1468023Y985906D03*
X1464323D03*
X1460622D03*
X1456921D03*
X1466173Y989095D03*
X1462472D03*
X1458771D03*
X1455071D03*
X1468023Y992284D03*
X1464323D03*
X1460622D03*
X1456921D03*
X1466173Y995473D03*
X1462472D03*
X1458771D03*
X1455071D03*
X1468023Y998662D03*
X1464323D03*
X1460622D03*
X1456921D03*
X1466173Y1001851D03*
X1462472D03*
X1458771D03*
X1455071D03*
X1468023Y1005040D03*
X1464323D03*
X1460622D03*
X1456921D03*
X1466173Y1008229D03*
X1462472D03*
X1458771D03*
X1455071D03*
X1468023Y1011418D03*
X1464323D03*
X1460622D03*
X1456921D03*
X1465504Y1027008D03*
X1461803D03*
X1458102D03*
X1454401D03*
X1467354Y1030197D03*
X1463653D03*
X1459953D03*
X1456252D03*
X1465504Y1033386D03*
X1461803D03*
X1458102D03*
X1454401D03*
X1467354Y1036575D03*
X1463653D03*
X1459953D03*
X1456252D03*
X1465504Y1039764D03*
X1461803D03*
X1458102D03*
X1454401D03*
X1467354Y1042953D03*
X1463653D03*
X1459953D03*
X1456252D03*
X1465504Y1046142D03*
X1461803D03*
X1458102D03*
X1454401D03*
X1467354Y1049331D03*
X1463653D03*
X1459953D03*
X1456252D03*
X1465504Y1052520D03*
X1461803D03*
X1458102D03*
X1454401D03*
X1467354Y1055709D03*
X1463653D03*
X1459953D03*
X1456252D03*
X1465504Y1058898D03*
X1461803D03*
X1458102D03*
X1454401D03*
X1467354Y1062087D03*
X1463653D03*
X1459953D03*
X1456252D03*
X1465504Y1065276D03*
X1461803D03*
X1458102D03*
X1454401D03*
X1467354Y1068465D03*
X1463653D03*
X1459953D03*
X1456252D03*
X1465504Y1071654D03*
X1461803D03*
X1458102D03*
X1454401D03*
X1467354Y1074843D03*
X1463653D03*
X1459953D03*
X1456252D03*
X1465504Y1078032D03*
X1461803D03*
X1458102D03*
X1454401D03*
X1467354Y1081221D03*
X1463653D03*
X1459953D03*
X1456252D03*
X1465504Y1084410D03*
X1461803D03*
X1458102D03*
X1454401D03*
X1467354Y1087599D03*
X1463653D03*
X1459953D03*
X1456252D03*
X1465504Y1090788D03*
X1461803D03*
X1458102D03*
X1454401D03*
X1467354Y1093977D03*
X1463653D03*
X1459953D03*
X1456252D03*
X1465504Y1097166D03*
X1461803D03*
X1458102D03*
X1454401D03*
X1467354Y1100355D03*
X1463653D03*
X1459953D03*
X1456252D03*
X1465504Y1103544D03*
X1461803D03*
X1458102D03*
X1454401D03*
X1467354Y1106733D03*
X1463653D03*
X1459953D03*
X1456252D03*
X1465504Y1109922D03*
X1461803D03*
X1458102D03*
X1454401D03*
X1467354Y1113111D03*
X1463653D03*
X1459953D03*
X1456252D03*
X1465504Y1116300D03*
X1461803D03*
X1458102D03*
X1454401D03*
X1467354Y1119489D03*
X1463653D03*
X1459953D03*
X1456252D03*
X1465504Y1122678D03*
X1461803D03*
X1458102D03*
X1454401D03*
X1467354Y1125867D03*
X1463653D03*
X1459953D03*
X1456252D03*
X1465504Y1129056D03*
X1461803D03*
X1458102D03*
X1454401D03*
X1467354Y1132245D03*
X1463653D03*
X1459953D03*
X1456252D03*
X1465504Y1135433D03*
X1461803D03*
X1458102D03*
X1454401D03*
X1467354Y1138622D03*
X1463653D03*
X1459953D03*
X1456252D03*
X1465504Y1141811D03*
X1461803D03*
X1458102D03*
X1454401D03*
X1467354Y1145000D03*
X1463653D03*
X1459953D03*
X1456252D03*
X1465504Y1148189D03*
X1461803D03*
X1458102D03*
X1454401D03*
X1467354Y1151378D03*
X1463653D03*
X1459953D03*
X1456252D03*
X1465504Y1154567D03*
X1461803D03*
X1458102D03*
X1454401D03*
X1467354Y1157756D03*
X1463653D03*
X1459953D03*
X1456252D03*
X1465504Y1160945D03*
X1461803D03*
X1458102D03*
X1454401D03*
X1463653Y1164134D03*
X1459953D03*
X1456252D03*
X1480976Y874292D03*
X1477275D03*
X1473575D03*
X1469874D03*
X1482827Y877481D03*
X1479126D03*
X1475425D03*
X1471724D03*
X1480976Y880670D03*
X1477275D03*
X1473575D03*
X1469874D03*
X1482827Y883859D03*
X1479126D03*
X1475425D03*
X1471724D03*
X1480976Y887048D03*
X1477275D03*
X1473575D03*
X1469874D03*
X1482827Y890237D03*
X1479126D03*
X1475425D03*
X1471724D03*
X1480976Y893426D03*
X1477275D03*
X1473575D03*
X1469874D03*
X1482827Y896615D03*
X1479126D03*
X1475425D03*
X1471724D03*
X1480976Y899804D03*
X1477275D03*
X1473575D03*
X1469874D03*
X1482827Y902993D03*
X1479126D03*
X1475425D03*
X1471724D03*
X1480976Y906181D03*
X1477275D03*
X1473575D03*
X1469874D03*
X1482827Y909370D03*
X1479126D03*
X1475425D03*
X1471724D03*
X1480976Y912559D03*
X1477275D03*
X1473575D03*
X1469874D03*
X1482827Y915748D03*
X1479126D03*
X1475425D03*
X1471724D03*
X1480976Y918937D03*
X1477275D03*
X1473575D03*
X1469874D03*
X1482827Y922126D03*
X1479126D03*
X1475425D03*
X1471724D03*
X1480976Y925315D03*
X1477275D03*
X1473575D03*
X1469874D03*
X1482827Y928504D03*
X1479126D03*
X1475425D03*
X1471724D03*
X1480976Y931693D03*
X1477275D03*
X1473575D03*
X1469874D03*
X1482827Y934882D03*
X1479126D03*
X1475425D03*
X1471724D03*
X1480976Y938071D03*
X1477275D03*
X1473575D03*
X1469874D03*
X1482827Y941260D03*
X1479126D03*
X1475425D03*
X1471724D03*
X1480976Y944449D03*
X1477275D03*
X1473575D03*
X1469874D03*
X1482827Y947638D03*
X1479126D03*
X1475425D03*
X1471724D03*
X1480976Y950827D03*
X1477275D03*
X1473575D03*
X1469874D03*
X1482827Y954016D03*
X1479126D03*
X1475425D03*
X1471724D03*
X1480976Y957205D03*
X1477275D03*
X1473575D03*
X1469874D03*
X1482827Y960394D03*
X1479126D03*
X1475425D03*
X1471724D03*
X1480976Y963583D03*
X1477275D03*
X1473575D03*
X1469874D03*
X1482827Y966772D03*
X1479126D03*
X1475425D03*
X1471724D03*
X1480976Y969961D03*
X1477275D03*
X1473575D03*
X1469874D03*
X1482827Y973150D03*
X1479126D03*
X1475425D03*
X1471724D03*
X1480976Y976339D03*
X1477275D03*
X1473575D03*
X1469874D03*
X1482827Y979528D03*
X1479126D03*
X1475425D03*
X1471724D03*
X1480976Y982717D03*
X1477275D03*
X1473575D03*
X1469874D03*
X1482827Y985906D03*
X1479126D03*
X1475425D03*
X1471724D03*
X1480976Y989095D03*
X1477275D03*
X1473575D03*
X1469874D03*
X1482827Y992284D03*
X1479126D03*
X1475425D03*
X1471724D03*
X1480976Y995473D03*
X1477275D03*
X1473575D03*
X1469874D03*
X1482827Y998662D03*
X1479126D03*
X1475425D03*
X1471724D03*
X1480976Y1001851D03*
X1477275D03*
X1473575D03*
X1469874D03*
X1482827Y1005040D03*
X1479126D03*
X1475425D03*
X1471724D03*
X1480976Y1008229D03*
X1477275D03*
X1473575D03*
X1469874D03*
X1482827Y1011418D03*
X1479126D03*
X1475425D03*
X1471724D03*
X1480307Y1027008D03*
X1476606D03*
X1472905D03*
X1469205D03*
X1482157Y1030197D03*
X1478457D03*
X1474756D03*
X1471055D03*
X1480307Y1033386D03*
X1476606D03*
X1472905D03*
X1469205D03*
X1482157Y1036575D03*
X1478457D03*
X1474756D03*
X1471055D03*
X1480307Y1039764D03*
X1476606D03*
X1472905D03*
X1469205D03*
X1482157Y1042953D03*
X1478457D03*
X1474756D03*
X1471055D03*
X1480307Y1046142D03*
X1476606D03*
X1472905D03*
X1469205D03*
X1482157Y1049331D03*
X1478457D03*
X1474756D03*
X1471055D03*
X1480307Y1052520D03*
X1476606D03*
X1472905D03*
X1469205D03*
X1482157Y1055709D03*
X1478457D03*
X1474756D03*
X1471055D03*
X1480307Y1058898D03*
X1476606D03*
X1472905D03*
X1469205D03*
X1482157Y1062087D03*
X1478457D03*
X1474756D03*
X1471055D03*
X1480307Y1065276D03*
X1476606D03*
X1472905D03*
X1469205D03*
X1482157Y1068465D03*
X1478457D03*
X1474756D03*
X1471055D03*
X1480307Y1071654D03*
X1476606D03*
X1472905D03*
X1469205D03*
X1482157Y1074843D03*
X1478457D03*
X1474756D03*
X1471055D03*
X1480307Y1078032D03*
X1476606D03*
X1472905D03*
X1469205D03*
X1482157Y1081221D03*
X1478457D03*
X1474756D03*
X1471055D03*
X1480307Y1084410D03*
X1476606D03*
X1472905D03*
X1469205D03*
X1482157Y1087599D03*
X1478457D03*
X1474756D03*
X1471055D03*
X1480307Y1090788D03*
X1476606D03*
X1472905D03*
X1469205D03*
X1482157Y1093977D03*
X1478457D03*
X1474756D03*
X1471055D03*
X1480307Y1097166D03*
X1476606D03*
X1472905D03*
X1469205D03*
X1482157Y1100355D03*
X1478457D03*
X1474756D03*
X1471055D03*
X1480307Y1103544D03*
X1476606D03*
X1472905D03*
X1469205D03*
X1482157Y1106733D03*
X1478457D03*
X1474756D03*
X1471055D03*
X1480307Y1109922D03*
X1476606D03*
X1472905D03*
X1469205D03*
X1482157Y1113111D03*
X1478457D03*
X1474756D03*
X1471055D03*
X1480307Y1116300D03*
X1476606D03*
X1472905D03*
X1469205D03*
X1482157Y1119489D03*
X1478457D03*
X1474756D03*
X1471055D03*
X1480307Y1122678D03*
X1476606D03*
X1472905D03*
X1469205D03*
X1482157Y1125867D03*
X1478457D03*
X1474756D03*
X1471055D03*
X1480307Y1129056D03*
X1476606D03*
X1472905D03*
X1469205D03*
X1482157Y1132245D03*
X1478457D03*
X1474756D03*
X1471055D03*
X1480307Y1135433D03*
X1476606D03*
X1472905D03*
X1469205D03*
X1482157Y1138622D03*
X1478457D03*
X1474756D03*
X1471055D03*
X1480307Y1141811D03*
X1476606D03*
X1472905D03*
X1469205D03*
X1482157Y1145000D03*
X1478457D03*
X1474756D03*
X1471055D03*
X1480307Y1148189D03*
X1476606D03*
X1472905D03*
X1469205D03*
X1482157Y1151378D03*
X1478457D03*
X1474756D03*
X1471055D03*
X1480307Y1154567D03*
X1476606D03*
X1472905D03*
X1469205D03*
X1482157Y1157756D03*
X1478457D03*
X1474756D03*
X1471055D03*
X1480307Y1160945D03*
X1476606D03*
X1472905D03*
X1469205D03*
X1482157Y1164134D03*
X1478457D03*
X1474756D03*
X1471055D03*
X1495779Y874292D03*
X1492079D03*
X1484677D03*
X1497630Y877481D03*
X1493929D03*
X1490228D03*
X1486527D03*
X1495779Y880670D03*
X1492079D03*
X1488378D03*
X1484677D03*
X1497630Y883859D03*
X1493929D03*
X1490228D03*
X1486527D03*
X1495779Y887048D03*
X1492079D03*
X1488378D03*
X1484677D03*
X1497630Y890237D03*
X1493929D03*
X1490228D03*
X1486527D03*
X1495779Y893426D03*
X1492079D03*
X1488378D03*
X1484677D03*
X1497630Y896615D03*
X1493929D03*
X1490228D03*
X1486527D03*
X1495779Y899804D03*
X1492079D03*
X1488378D03*
X1484677D03*
X1497630Y902993D03*
X1493929D03*
X1490228D03*
X1486527D03*
X1495779Y906181D03*
X1492079D03*
X1488378D03*
X1484677D03*
X1497630Y909370D03*
X1493929D03*
X1490228D03*
X1486527D03*
X1495779Y912559D03*
X1492079D03*
X1488378D03*
X1484677D03*
X1497630Y915748D03*
X1493929D03*
X1490228D03*
X1486527D03*
X1495779Y918937D03*
X1492079D03*
X1488378D03*
X1484677D03*
X1497630Y922126D03*
X1493929D03*
X1490228D03*
X1486527D03*
X1495779Y925315D03*
X1492079D03*
X1488378D03*
X1484677D03*
X1497630Y928504D03*
X1493929D03*
X1490228D03*
X1486527D03*
X1495779Y931693D03*
X1492079D03*
X1488378D03*
X1484677D03*
X1497630Y934882D03*
X1493929D03*
X1490228D03*
X1486527D03*
X1495779Y938071D03*
X1492079D03*
X1488378D03*
X1484677D03*
X1497630Y941260D03*
X1493929D03*
X1490228D03*
X1486527D03*
X1495779Y944449D03*
X1492079D03*
X1488378D03*
X1484677D03*
X1497630Y947638D03*
X1493929D03*
X1490228D03*
X1486527D03*
X1495779Y950827D03*
X1492079D03*
X1488378D03*
X1484677D03*
X1497630Y954016D03*
X1493929D03*
X1490228D03*
X1486527D03*
X1495779Y957205D03*
X1492079D03*
X1488378D03*
X1484677D03*
X1497630Y960394D03*
X1493929D03*
X1490228D03*
X1486527D03*
X1495779Y963583D03*
X1492079D03*
X1488378D03*
X1484677D03*
X1497630Y966772D03*
X1493929D03*
X1490228D03*
X1486527D03*
X1495779Y969961D03*
X1492079D03*
X1488378D03*
X1484677D03*
X1497630Y973150D03*
X1493929D03*
X1490228D03*
X1486527D03*
X1495779Y976339D03*
X1492079D03*
X1488378D03*
X1484677D03*
X1497630Y979528D03*
X1493929D03*
X1490228D03*
X1486527D03*
X1495779Y982717D03*
X1492079D03*
X1488378D03*
X1484677D03*
X1497630Y985906D03*
X1493929D03*
X1490228D03*
X1486527D03*
X1495779Y989095D03*
X1492079D03*
X1488378D03*
X1484677D03*
X1497630Y992284D03*
X1493929D03*
X1490228D03*
X1486527D03*
X1495779Y995473D03*
X1492079D03*
X1488378D03*
X1484677D03*
X1497630Y998662D03*
X1493929D03*
X1490228D03*
X1486527D03*
X1495779Y1001851D03*
X1492079D03*
X1488378D03*
X1484677D03*
X1497630Y1005040D03*
X1493929D03*
X1490228D03*
X1486527D03*
X1495779Y1008229D03*
X1492079D03*
X1488378D03*
X1484677D03*
X1497630Y1011418D03*
X1493929D03*
X1490228D03*
X1486527D03*
X1495110Y1027008D03*
X1491409D03*
X1487709D03*
X1484008D03*
X1496960Y1030197D03*
X1493260D03*
X1489559D03*
X1485858D03*
X1495110Y1033386D03*
X1491409D03*
X1487709D03*
X1484008D03*
X1496960Y1036575D03*
X1493260D03*
X1489559D03*
X1485858D03*
X1495110Y1039764D03*
X1491409D03*
X1487709D03*
X1484008D03*
X1496960Y1042953D03*
X1493260D03*
X1489559D03*
X1485858D03*
X1495110Y1046142D03*
X1491409D03*
X1487709D03*
X1484008D03*
X1496960Y1049331D03*
X1493260D03*
X1489559D03*
X1485858D03*
X1495110Y1052520D03*
X1491409D03*
X1487709D03*
X1484008D03*
X1496960Y1055709D03*
X1493260D03*
X1489559D03*
X1485858D03*
X1495110Y1058898D03*
X1491409D03*
X1487709D03*
X1484008D03*
X1496960Y1062087D03*
X1493260D03*
X1489559D03*
X1485858D03*
X1495110Y1065276D03*
X1491409D03*
X1487709D03*
X1484008D03*
X1496960Y1068465D03*
X1493260D03*
X1489559D03*
X1485858D03*
X1495110Y1071654D03*
X1491409D03*
X1487709D03*
X1484008D03*
X1496960Y1074843D03*
X1493260D03*
X1489559D03*
X1485858D03*
X1495110Y1078032D03*
X1491409D03*
X1487709D03*
X1484008D03*
X1496960Y1081221D03*
X1493260D03*
X1489559D03*
X1485858D03*
X1495110Y1084410D03*
X1491409D03*
X1487709D03*
X1484008D03*
X1496960Y1087599D03*
X1493260D03*
X1489559D03*
X1485858D03*
X1495110Y1090788D03*
X1491409D03*
X1487709D03*
X1484008D03*
X1496960Y1093977D03*
X1493260D03*
X1489559D03*
X1485858D03*
X1495110Y1097166D03*
X1491409D03*
X1487709D03*
X1484008D03*
X1496960Y1100355D03*
X1493260D03*
X1489559D03*
X1485858D03*
X1495110Y1103544D03*
X1491409D03*
X1487709D03*
X1484008D03*
X1496960Y1106733D03*
X1493260D03*
X1489559D03*
X1485858D03*
X1495110Y1109922D03*
X1491409D03*
X1487709D03*
X1484008D03*
X1496960Y1113111D03*
X1493260D03*
X1489559D03*
X1485858D03*
X1495110Y1116300D03*
X1491409D03*
X1487709D03*
X1484008D03*
X1496960Y1119489D03*
X1493260D03*
X1489559D03*
X1485858D03*
X1495110Y1122678D03*
X1491409D03*
X1487709D03*
X1484008D03*
X1496960Y1125867D03*
X1493260D03*
X1489559D03*
X1485858D03*
X1495110Y1129056D03*
X1491409D03*
X1487709D03*
X1484008D03*
X1496960Y1132245D03*
X1493260D03*
X1489559D03*
X1485858D03*
X1495110Y1135433D03*
X1491409D03*
X1487709D03*
X1484008D03*
X1496960Y1138622D03*
X1493260D03*
X1489559D03*
X1485858D03*
X1495110Y1141811D03*
X1491409D03*
X1487709D03*
X1484008D03*
X1496960Y1145000D03*
X1493260D03*
X1489559D03*
X1485858D03*
X1495110Y1148189D03*
X1491409D03*
X1487709D03*
X1484008D03*
X1496960Y1151378D03*
X1493260D03*
X1489559D03*
X1485858D03*
X1495110Y1154567D03*
X1491409D03*
X1487709D03*
X1484008D03*
X1496960Y1157756D03*
X1493260D03*
X1489559D03*
X1485858D03*
X1495110Y1160945D03*
X1491409D03*
X1487709D03*
X1484008D03*
X1496960Y1164134D03*
X1493260D03*
X1485858D03*
X1506882Y874292D03*
X1503181D03*
X1499480D03*
X1512433Y877481D03*
X1508732D03*
X1505031D03*
X1501331D03*
X1510583Y880670D03*
X1506882D03*
X1503181D03*
X1499480D03*
X1512433Y883859D03*
X1508732D03*
X1505031D03*
X1501331D03*
X1510583Y887048D03*
X1506882D03*
X1503181D03*
X1499480D03*
X1512433Y890237D03*
X1508732D03*
X1505031D03*
X1501331D03*
X1510583Y893426D03*
X1506882D03*
X1503181D03*
X1499480D03*
X1512433Y896615D03*
X1508732D03*
X1505031D03*
X1501331D03*
X1510583Y899804D03*
X1506882D03*
X1503181D03*
X1499480D03*
X1512433Y902993D03*
X1508732D03*
X1505031D03*
X1501331D03*
X1510583Y906181D03*
X1506882D03*
X1503181D03*
X1499480D03*
X1512433Y909370D03*
X1508732D03*
X1505031D03*
X1501331D03*
X1510583Y912559D03*
X1506882D03*
X1503181D03*
X1499480D03*
X1512433Y915748D03*
X1508732D03*
X1505031D03*
X1501331D03*
X1510583Y918937D03*
X1506882D03*
X1503181D03*
X1499480D03*
X1512433Y922126D03*
X1508732D03*
X1505031D03*
X1501331D03*
X1510583Y925315D03*
X1506882D03*
X1503181D03*
X1499480D03*
X1512433Y928504D03*
X1508732D03*
X1505031D03*
X1501331D03*
X1510583Y931693D03*
X1506882D03*
X1503181D03*
X1499480D03*
X1512433Y934882D03*
X1508732D03*
X1505031D03*
X1501331D03*
X1510583Y938071D03*
X1506882D03*
X1503181D03*
X1499480D03*
X1512433Y941260D03*
X1508732D03*
X1505031D03*
X1501331D03*
X1510583Y944449D03*
X1506882D03*
X1503181D03*
X1499480D03*
X1512433Y947638D03*
X1508732D03*
X1505031D03*
X1501331D03*
X1510583Y950827D03*
X1506882D03*
X1503181D03*
X1499480D03*
X1512433Y954016D03*
X1508732D03*
X1505031D03*
X1501331D03*
X1510583Y957205D03*
X1506882D03*
X1503181D03*
X1499480D03*
X1512433Y960394D03*
X1508732D03*
X1505031D03*
X1501331D03*
X1510583Y963583D03*
X1506882D03*
X1503181D03*
X1499480D03*
X1512433Y966772D03*
X1508732D03*
X1505031D03*
X1501331D03*
X1510583Y969961D03*
X1506882D03*
X1503181D03*
X1499480D03*
X1512433Y973150D03*
X1508732D03*
X1505031D03*
X1501331D03*
X1510583Y976339D03*
X1506882D03*
X1503181D03*
X1499480D03*
X1512433Y979528D03*
X1508732D03*
X1505031D03*
X1501331D03*
X1510583Y982717D03*
X1506882D03*
X1503181D03*
X1499480D03*
X1512433Y985906D03*
X1508732D03*
X1505031D03*
X1501331D03*
X1510583Y989095D03*
X1506882D03*
X1503181D03*
X1499480D03*
X1512433Y992284D03*
X1508732D03*
X1505031D03*
X1501331D03*
X1510583Y995473D03*
X1506882D03*
X1503181D03*
X1499480D03*
X1512433Y998662D03*
X1508732D03*
X1505031D03*
X1501331D03*
X1510583Y1001851D03*
X1506882D03*
X1503181D03*
X1499480D03*
X1512433Y1005040D03*
X1508732D03*
X1505031D03*
X1501331D03*
X1510583Y1008229D03*
X1506882D03*
X1503181D03*
X1499480D03*
X1512433Y1011418D03*
X1508732D03*
X1505031D03*
X1501331D03*
X1513614Y1027008D03*
X1509913D03*
X1506212D03*
X1502512D03*
X1498811D03*
X1511764Y1030197D03*
X1508063D03*
X1504362D03*
X1500661D03*
X1513614Y1033386D03*
X1509913D03*
X1506212D03*
X1502512D03*
X1498811D03*
X1511764Y1036575D03*
X1508063D03*
X1504362D03*
X1500661D03*
X1513614Y1039764D03*
X1509913D03*
X1506212D03*
X1502512D03*
X1498811D03*
X1511764Y1042953D03*
X1508063D03*
X1504362D03*
X1500661D03*
X1513614Y1046142D03*
X1509913D03*
X1506212D03*
X1502512D03*
X1498811D03*
X1511764Y1049331D03*
X1508063D03*
X1504362D03*
X1500661D03*
X1513614Y1052520D03*
X1509913D03*
X1506212D03*
X1502512D03*
X1498811D03*
X1511764Y1055709D03*
X1508063D03*
X1504362D03*
X1500661D03*
X1513614Y1058898D03*
X1509913D03*
X1506212D03*
X1502512D03*
X1498811D03*
X1511764Y1062087D03*
X1508063D03*
X1504362D03*
X1500661D03*
X1513614Y1065276D03*
X1509913D03*
X1506212D03*
X1502512D03*
X1498811D03*
X1511764Y1068465D03*
X1508063D03*
X1504362D03*
X1500661D03*
X1513614Y1071654D03*
X1509913D03*
X1506212D03*
X1502512D03*
X1498811D03*
X1511764Y1074843D03*
X1508063D03*
X1504362D03*
X1500661D03*
X1513614Y1078032D03*
X1509913D03*
X1506212D03*
X1502512D03*
X1498811D03*
X1511764Y1081221D03*
X1508063D03*
X1504362D03*
X1500661D03*
X1513614Y1084410D03*
X1509913D03*
X1506212D03*
X1502512D03*
X1498811D03*
X1511764Y1087599D03*
X1508063D03*
X1504362D03*
X1500661D03*
X1513614Y1090788D03*
X1509913D03*
X1506212D03*
X1502512D03*
X1498811D03*
X1511764Y1093977D03*
X1508063D03*
X1504362D03*
X1500661D03*
X1513614Y1097166D03*
X1509913D03*
X1506212D03*
X1502512D03*
X1498811D03*
X1511764Y1100355D03*
X1508063D03*
X1504362D03*
X1500661D03*
X1513614Y1103544D03*
X1509913D03*
X1506212D03*
X1502512D03*
X1498811D03*
X1511764Y1106733D03*
X1508063D03*
X1504362D03*
X1500661D03*
X1513614Y1109922D03*
X1509913D03*
X1506212D03*
X1502512D03*
X1498811D03*
X1511764Y1113111D03*
X1508063D03*
X1504362D03*
X1500661D03*
X1513614Y1116300D03*
X1509913D03*
X1506212D03*
X1502512D03*
X1498811D03*
X1511764Y1119489D03*
X1508063D03*
X1504362D03*
X1500661D03*
X1513614Y1122678D03*
X1509913D03*
X1506212D03*
X1502512D03*
X1498811D03*
X1511764Y1125867D03*
X1508063D03*
X1504362D03*
X1500661D03*
X1513614Y1129056D03*
X1509913D03*
X1506212D03*
X1502512D03*
X1498811D03*
X1511764Y1132245D03*
X1508063D03*
X1504362D03*
X1500661D03*
X1513614Y1135433D03*
X1509913D03*
X1506212D03*
X1502512D03*
X1498811D03*
X1511764Y1138622D03*
X1508063D03*
X1504362D03*
X1500661D03*
X1513614Y1141811D03*
X1509913D03*
X1506212D03*
X1502512D03*
X1498811D03*
X1511764Y1145000D03*
X1508063D03*
X1504362D03*
X1500661D03*
X1513614Y1148189D03*
X1509913D03*
X1506212D03*
X1502512D03*
X1498811D03*
X1511764Y1151378D03*
X1508063D03*
X1504362D03*
X1500661D03*
X1513614Y1154567D03*
X1509913D03*
X1506212D03*
X1502512D03*
X1498811D03*
X1511764Y1157756D03*
X1508063D03*
X1504362D03*
X1500661D03*
X1513614Y1160945D03*
X1509913D03*
X1506212D03*
X1502512D03*
X1498811D03*
X1508063Y1164134D03*
X1504362D03*
X1500661D03*
X1525386Y874292D03*
X1521685D03*
X1517984D03*
X1514283D03*
X1527236Y877481D03*
X1523535D03*
X1519835D03*
X1516134D03*
X1525386Y880670D03*
X1521685D03*
X1517984D03*
X1514283D03*
X1527236Y883859D03*
X1523535D03*
X1519835D03*
X1516134D03*
X1525386Y887048D03*
X1521685D03*
X1517984D03*
X1514283D03*
X1527236Y890237D03*
X1523535D03*
X1519835D03*
X1516134D03*
X1525386Y893426D03*
X1521685D03*
X1517984D03*
X1514283D03*
X1527236Y896615D03*
X1523535D03*
X1519835D03*
X1516134D03*
X1525386Y899804D03*
X1521685D03*
X1517984D03*
X1514283D03*
X1527236Y902993D03*
X1523535D03*
X1519835D03*
X1516134D03*
X1525386Y906181D03*
X1521685D03*
X1517984D03*
X1514283D03*
X1527236Y909370D03*
X1523535D03*
X1519835D03*
X1516134D03*
X1525386Y912559D03*
X1521685D03*
X1517984D03*
X1514283D03*
X1527236Y915748D03*
X1523535D03*
X1519835D03*
X1516134D03*
X1525386Y918937D03*
X1521685D03*
X1517984D03*
X1514283D03*
X1527236Y922126D03*
X1523535D03*
X1519835D03*
X1516134D03*
X1525386Y925315D03*
X1521685D03*
X1517984D03*
X1514283D03*
X1527236Y928504D03*
X1523535D03*
X1519835D03*
X1516134D03*
X1525386Y931693D03*
X1521685D03*
X1517984D03*
X1514283D03*
X1527236Y934882D03*
X1523535D03*
X1519835D03*
X1516134D03*
X1525386Y938071D03*
X1521685D03*
X1517984D03*
X1514283D03*
X1527236Y941260D03*
X1523535D03*
X1519835D03*
X1516134D03*
X1525386Y944449D03*
X1521685D03*
X1517984D03*
X1514283D03*
X1527236Y947638D03*
X1523535D03*
X1519835D03*
X1516134D03*
X1525386Y950827D03*
X1521685D03*
X1517984D03*
X1514283D03*
X1527236Y954016D03*
X1523535D03*
X1519835D03*
X1516134D03*
X1525386Y957205D03*
X1521685D03*
X1517984D03*
X1514283D03*
X1527236Y960394D03*
X1523535D03*
X1519835D03*
X1516134D03*
X1525386Y963583D03*
X1521685D03*
X1517984D03*
X1514283D03*
X1527236Y966772D03*
X1523535D03*
X1519835D03*
X1516134D03*
X1525386Y969961D03*
X1521685D03*
X1517984D03*
X1514283D03*
X1527236Y973150D03*
X1523535D03*
X1519835D03*
X1516134D03*
X1525386Y976339D03*
X1521685D03*
X1517984D03*
X1514283D03*
X1527236Y979528D03*
X1523535D03*
X1519835D03*
X1516134D03*
X1525386Y982717D03*
X1521685D03*
X1517984D03*
X1514283D03*
X1527236Y985906D03*
X1523535D03*
X1519835D03*
X1516134D03*
X1525386Y989095D03*
X1521685D03*
X1517984D03*
X1514283D03*
X1527236Y992284D03*
X1523535D03*
X1519835D03*
X1516134D03*
X1525386Y995473D03*
X1521685D03*
X1517984D03*
X1514283D03*
X1527236Y998662D03*
X1523535D03*
X1519835D03*
X1516134D03*
X1525386Y1001851D03*
X1521685D03*
X1517984D03*
X1514283D03*
X1527236Y1005040D03*
X1523535D03*
X1519835D03*
X1516134D03*
X1525386Y1008229D03*
X1521685D03*
X1517984D03*
X1514283D03*
X1527236Y1011418D03*
X1523535D03*
X1519835D03*
X1516134D03*
X1528417Y1027008D03*
X1524716D03*
X1521016D03*
X1517315D03*
X1526567Y1030197D03*
X1522866D03*
X1519165D03*
X1515464D03*
X1528417Y1033386D03*
X1524716D03*
X1521016D03*
X1517315D03*
X1526567Y1036575D03*
X1522866D03*
X1519165D03*
X1515464D03*
X1528417Y1039764D03*
X1524716D03*
X1521016D03*
X1517315D03*
X1526567Y1042953D03*
X1522866D03*
X1519165D03*
X1515464D03*
X1528417Y1046142D03*
X1524716D03*
X1521016D03*
X1517315D03*
X1526567Y1049331D03*
X1522866D03*
X1519165D03*
X1515464D03*
X1528417Y1052520D03*
X1524716D03*
X1521016D03*
X1517315D03*
X1526567Y1055709D03*
X1522866D03*
X1519165D03*
X1515464D03*
X1528417Y1058898D03*
X1524716D03*
X1521016D03*
X1517315D03*
X1526567Y1062087D03*
X1522866D03*
X1519165D03*
X1515464D03*
X1528417Y1065276D03*
X1524716D03*
X1521016D03*
X1517315D03*
X1526567Y1068465D03*
X1522866D03*
X1519165D03*
X1515464D03*
X1528417Y1071654D03*
X1524716D03*
X1521016D03*
X1517315D03*
X1526567Y1074843D03*
X1522866D03*
X1519165D03*
X1515464D03*
X1528417Y1078032D03*
X1524716D03*
X1521016D03*
X1517315D03*
X1526567Y1081221D03*
X1522866D03*
X1519165D03*
X1515464D03*
X1528417Y1084410D03*
X1524716D03*
X1521016D03*
X1517315D03*
X1526567Y1087599D03*
X1522866D03*
X1519165D03*
X1515464D03*
X1528417Y1090788D03*
X1524716D03*
X1521016D03*
X1517315D03*
X1526567Y1093977D03*
X1522866D03*
X1519165D03*
X1515464D03*
X1528417Y1097166D03*
X1524716D03*
X1521016D03*
X1517315D03*
X1526567Y1100355D03*
X1522866D03*
X1519165D03*
X1515464D03*
X1528417Y1103544D03*
X1524716D03*
X1521016D03*
X1517315D03*
X1526567Y1106733D03*
X1522866D03*
X1519165D03*
X1515464D03*
X1528417Y1109922D03*
X1524716D03*
X1521016D03*
X1517315D03*
X1526567Y1113111D03*
X1522866D03*
X1519165D03*
X1515464D03*
X1528417Y1116300D03*
X1524716D03*
X1521016D03*
X1517315D03*
X1526567Y1119489D03*
X1522866D03*
X1519165D03*
X1515464D03*
X1528417Y1122678D03*
X1524716D03*
X1521016D03*
X1517315D03*
X1526567Y1125867D03*
X1522866D03*
X1519165D03*
X1515464D03*
X1528417Y1129056D03*
X1524716D03*
X1521016D03*
X1517315D03*
X1526567Y1132245D03*
X1522866D03*
X1519165D03*
X1515464D03*
X1528417Y1135433D03*
X1524716D03*
X1521016D03*
X1517315D03*
X1526567Y1138622D03*
X1522866D03*
X1519165D03*
X1515464D03*
X1528417Y1141811D03*
X1524716D03*
X1521016D03*
X1517315D03*
X1526567Y1145000D03*
X1522866D03*
X1519165D03*
X1515464D03*
X1528417Y1148189D03*
X1524716D03*
X1521016D03*
X1517315D03*
X1526567Y1151378D03*
X1522866D03*
X1519165D03*
X1515464D03*
X1528417Y1154567D03*
X1524716D03*
X1521016D03*
X1517315D03*
X1526567Y1157756D03*
X1522866D03*
X1519165D03*
X1515464D03*
X1528417Y1160945D03*
X1524716D03*
X1521016D03*
X1517315D03*
X1526567Y1164134D03*
X1522866D03*
X1519165D03*
X1515464D03*
X1540189Y874292D03*
X1536488D03*
X1529086D03*
X1542039Y877481D03*
X1538338D03*
X1534638D03*
X1530937D03*
X1540189Y880670D03*
X1536488D03*
X1532787D03*
X1529086D03*
X1542039Y883859D03*
X1538338D03*
X1534638D03*
X1530937D03*
X1540189Y887048D03*
X1536488D03*
X1532787D03*
X1529086D03*
X1542039Y890237D03*
X1538338D03*
X1534638D03*
X1530937D03*
X1540189Y893426D03*
X1536488D03*
X1532787D03*
X1529086D03*
X1542039Y896615D03*
X1538338D03*
X1534638D03*
X1530937D03*
X1540189Y899804D03*
X1536488D03*
X1532787D03*
X1529086D03*
X1542039Y902993D03*
X1538338D03*
X1534638D03*
X1530937D03*
X1540189Y906181D03*
X1536488D03*
X1532787D03*
X1529086D03*
X1542039Y909370D03*
X1538338D03*
X1534638D03*
X1530937D03*
X1540189Y912559D03*
X1536488D03*
X1532787D03*
X1529086D03*
X1542039Y915748D03*
X1538338D03*
X1534638D03*
X1530937D03*
X1540189Y918937D03*
X1536488D03*
X1532787D03*
X1529086D03*
X1542039Y922126D03*
X1538338D03*
X1534638D03*
X1530937D03*
X1540189Y925315D03*
X1536488D03*
X1532787D03*
X1529086D03*
X1542039Y928504D03*
X1538338D03*
X1534638D03*
X1530937D03*
X1540189Y931693D03*
X1536488D03*
X1532787D03*
X1529086D03*
X1542039Y934882D03*
X1538338D03*
X1534638D03*
X1530937D03*
X1540189Y938071D03*
X1536488D03*
X1532787D03*
X1529086D03*
X1542039Y941260D03*
X1538338D03*
X1534638D03*
X1530937D03*
X1540189Y944449D03*
X1536488D03*
X1532787D03*
X1529086D03*
X1542039Y947638D03*
X1538338D03*
X1534638D03*
X1530937D03*
X1540189Y950827D03*
X1536488D03*
X1532787D03*
X1529086D03*
X1542039Y954016D03*
X1538338D03*
X1534638D03*
X1530937D03*
X1540189Y957205D03*
X1536488D03*
X1532787D03*
X1529086D03*
X1542039Y960394D03*
X1538338D03*
X1534638D03*
X1530937D03*
X1540189Y963583D03*
X1536488D03*
X1532787D03*
X1529086D03*
X1542039Y966772D03*
X1538338D03*
X1534638D03*
X1530937D03*
X1540189Y969961D03*
X1536488D03*
X1532787D03*
X1529086D03*
X1542039Y973150D03*
X1538338D03*
X1534638D03*
X1530937D03*
X1540189Y976339D03*
X1536488D03*
X1532787D03*
X1529086D03*
X1542039Y979528D03*
X1538338D03*
X1534638D03*
X1530937D03*
X1540189Y982717D03*
X1536488D03*
X1532787D03*
X1529086D03*
X1542039Y985906D03*
X1538338D03*
X1534638D03*
X1530937D03*
X1540189Y989095D03*
X1536488D03*
X1532787D03*
X1529086D03*
X1542039Y992284D03*
X1538338D03*
X1534638D03*
X1530937D03*
X1540189Y995473D03*
X1536488D03*
X1532787D03*
X1529086D03*
X1542039Y998662D03*
X1538338D03*
X1534638D03*
X1530937D03*
X1540189Y1001851D03*
X1536488D03*
X1532787D03*
X1529086D03*
X1542039Y1005040D03*
X1538338D03*
X1534638D03*
X1530937D03*
X1540189Y1008229D03*
X1536488D03*
X1532787D03*
X1529086D03*
X1542039Y1011418D03*
X1538338D03*
X1534638D03*
X1530937D03*
X1543220Y1027008D03*
X1539520D03*
X1535819D03*
X1532118D03*
X1541370Y1030197D03*
X1537669D03*
X1533968D03*
X1530268D03*
X1543220Y1033386D03*
X1539520D03*
X1535819D03*
X1532118D03*
X1541370Y1036575D03*
X1537669D03*
X1533968D03*
X1530268D03*
X1543220Y1039764D03*
X1539520D03*
X1535819D03*
X1532118D03*
X1541370Y1042953D03*
X1537669D03*
X1533968D03*
X1530268D03*
X1543220Y1046142D03*
X1539520D03*
X1535819D03*
X1532118D03*
X1541370Y1049331D03*
X1537669D03*
X1533968D03*
X1530268D03*
X1543220Y1052520D03*
X1539520D03*
X1535819D03*
X1532118D03*
X1541370Y1055709D03*
X1537669D03*
X1533968D03*
X1530268D03*
X1543220Y1058898D03*
X1539520D03*
X1535819D03*
X1532118D03*
X1541370Y1062087D03*
X1537669D03*
X1533968D03*
X1530268D03*
X1543220Y1065276D03*
X1539520D03*
X1535819D03*
X1532118D03*
X1541370Y1068465D03*
X1537669D03*
X1533968D03*
X1530268D03*
X1543220Y1071654D03*
X1539520D03*
X1535819D03*
X1532118D03*
X1541370Y1074843D03*
X1537669D03*
X1533968D03*
X1530268D03*
X1543220Y1078032D03*
X1539520D03*
X1535819D03*
X1532118D03*
X1541370Y1081221D03*
X1537669D03*
X1533968D03*
X1530268D03*
X1543220Y1084410D03*
X1539520D03*
X1535819D03*
X1532118D03*
X1541370Y1087599D03*
X1537669D03*
X1533968D03*
X1530268D03*
X1543220Y1090788D03*
X1539520D03*
X1535819D03*
X1532118D03*
X1541370Y1093977D03*
X1537669D03*
X1533968D03*
X1530268D03*
X1543220Y1097166D03*
X1539520D03*
X1535819D03*
X1532118D03*
X1541370Y1100355D03*
X1537669D03*
X1533968D03*
X1530268D03*
X1543220Y1103544D03*
X1539520D03*
X1535819D03*
X1532118D03*
X1541370Y1106733D03*
X1537669D03*
X1533968D03*
X1530268D03*
X1543220Y1109922D03*
X1539520D03*
X1535819D03*
X1532118D03*
X1541370Y1113111D03*
X1537669D03*
X1533968D03*
X1530268D03*
X1543220Y1116300D03*
X1539520D03*
X1535819D03*
X1532118D03*
X1541370Y1119489D03*
X1537669D03*
X1533968D03*
X1530268D03*
X1543220Y1122678D03*
X1539520D03*
X1535819D03*
X1532118D03*
X1541370Y1125867D03*
X1537669D03*
X1533968D03*
X1530268D03*
X1543220Y1129056D03*
X1539520D03*
X1535819D03*
X1532118D03*
X1541370Y1132245D03*
X1537669D03*
X1533968D03*
X1530268D03*
X1543220Y1135433D03*
X1539520D03*
X1535819D03*
X1532118D03*
X1541370Y1138622D03*
X1537669D03*
X1533968D03*
X1530268D03*
X1543220Y1141811D03*
X1539520D03*
X1535819D03*
X1532118D03*
X1541370Y1145000D03*
X1537669D03*
X1533968D03*
X1530268D03*
X1543220Y1148189D03*
X1539520D03*
X1535819D03*
X1532118D03*
X1541370Y1151378D03*
X1537669D03*
X1533968D03*
X1530268D03*
X1543220Y1154567D03*
X1539520D03*
X1535819D03*
X1532118D03*
X1541370Y1157756D03*
X1537669D03*
X1533968D03*
X1530268D03*
X1543220Y1160945D03*
X1539520D03*
X1535819D03*
X1532118D03*
X1541370Y1164134D03*
X1537669D03*
X1530268D03*
X1543890Y874292D03*
X1545740Y877481D03*
X1551291Y880670D03*
X1547590D03*
X1543890D03*
X1549441Y883859D03*
X1545740D03*
X1551291Y887048D03*
X1547590D03*
X1543890D03*
X1549441Y890237D03*
X1545740D03*
X1551291Y893426D03*
X1547590D03*
X1543890D03*
X1549441Y896615D03*
X1545740D03*
X1551291Y899804D03*
X1547590D03*
X1543890D03*
X1549441Y902993D03*
X1545740D03*
X1551291Y906181D03*
X1547590D03*
X1543890D03*
X1549441Y909370D03*
X1545740D03*
X1551291Y912559D03*
X1547590D03*
X1543890D03*
X1549441Y915748D03*
X1545740D03*
X1551291Y918937D03*
X1547590D03*
X1543890D03*
X1549441Y922126D03*
X1545740D03*
X1551291Y925315D03*
X1547590D03*
X1543890D03*
X1549441Y928504D03*
X1545740D03*
X1551291Y931693D03*
X1547590D03*
X1543890D03*
X1549441Y934882D03*
X1545740D03*
X1551291Y938071D03*
X1547590D03*
X1543890D03*
X1549441Y941260D03*
X1545740D03*
X1551291Y944449D03*
X1547590D03*
X1543890D03*
X1549441Y947638D03*
X1545740D03*
X1551291Y950827D03*
X1547590D03*
X1543890D03*
X1549441Y954016D03*
X1545740D03*
X1551291Y957205D03*
X1547590D03*
X1543890D03*
X1549441Y960394D03*
X1545740D03*
X1551291Y963583D03*
X1547590D03*
X1543890D03*
X1549441Y966772D03*
X1545740D03*
X1551291Y969961D03*
X1547590D03*
X1543890D03*
X1549441Y973150D03*
X1545740D03*
X1551291Y976339D03*
X1547590D03*
X1543890D03*
X1549441Y979528D03*
X1545740D03*
X1551291Y982717D03*
X1547590D03*
X1543890D03*
X1549441Y985906D03*
X1545740D03*
X1551291Y989095D03*
X1547590D03*
X1543890D03*
X1549441Y992284D03*
X1545740D03*
X1551291Y995473D03*
X1547590D03*
X1543890D03*
X1549441Y998662D03*
X1545740D03*
X1551291Y1001851D03*
X1547590D03*
X1543890D03*
X1549441Y1005040D03*
X1545740D03*
X1551291Y1008229D03*
X1547590D03*
X1543890D03*
X1549441Y1011418D03*
X1545740D03*
X1550622Y1027008D03*
X1546921D03*
X1552472Y1030197D03*
X1548771D03*
X1545071D03*
X1550622Y1033386D03*
X1546921D03*
X1552472Y1036575D03*
X1548771D03*
X1545071D03*
X1550622Y1039764D03*
X1546921D03*
X1552472Y1042953D03*
X1548771D03*
X1545071D03*
X1550622Y1046142D03*
X1546921D03*
X1552472Y1049331D03*
X1548771D03*
X1545071D03*
X1550622Y1052520D03*
X1546921D03*
X1552472Y1055709D03*
X1548771D03*
X1545071D03*
X1550622Y1058898D03*
X1546921D03*
X1552472Y1062087D03*
X1548771D03*
X1545071D03*
X1550622Y1065276D03*
X1546921D03*
X1552472Y1068465D03*
X1548771D03*
X1545071D03*
X1550622Y1071654D03*
X1546921D03*
X1552472Y1074843D03*
X1548771D03*
X1545071D03*
X1550622Y1078032D03*
X1546921D03*
X1552472Y1081221D03*
X1548771D03*
X1545071D03*
X1550622Y1084410D03*
X1546921D03*
X1552472Y1087599D03*
X1548771D03*
X1545071D03*
X1550622Y1090788D03*
X1546921D03*
X1552472Y1093977D03*
X1548771D03*
X1545071D03*
X1550622Y1097166D03*
X1546921D03*
X1552472Y1100355D03*
X1548771D03*
X1545071D03*
X1550622Y1103544D03*
X1546921D03*
X1552472Y1106733D03*
X1548771D03*
X1545071D03*
X1550622Y1109922D03*
X1546921D03*
X1552472Y1113111D03*
X1548771D03*
X1545071D03*
X1550622Y1116300D03*
X1546921D03*
X1552472Y1119489D03*
X1548771D03*
X1545071D03*
X1550622Y1122678D03*
X1546921D03*
X1552472Y1125867D03*
X1548771D03*
X1545071D03*
X1550622Y1129056D03*
X1546921D03*
X1552472Y1132245D03*
X1548771D03*
X1545071D03*
X1550622Y1135433D03*
X1546921D03*
X1552472Y1138622D03*
X1548771D03*
X1545071D03*
X1550622Y1141811D03*
X1546921D03*
X1552472Y1145000D03*
X1548771D03*
X1545071D03*
X1550622Y1148189D03*
X1546921D03*
X1552472Y1151378D03*
X1548771D03*
X1545071D03*
X1550622Y1154567D03*
X1546921D03*
X1552472Y1157756D03*
X1548771D03*
X1545071D03*
X1546921Y1160945D03*
X1545071Y1164134D03*
G54D12*
X20709Y139746D03*
X23563Y1590338D03*
X409259Y412106D03*
X864625Y1368522D03*
X925009Y1014595D03*
X1088663Y299646D03*
X1148239Y554216D03*
X1489957Y1403002D03*
X1568792Y178239D03*
X1704930Y1649379D03*
G54D141*
X326731Y663237D03*
X363731D03*
X443467Y594259D03*
X754645Y1436735D03*
X1077638Y133866D03*
X1166535Y1422322D03*
X1291146Y1385558D03*
X1320516D03*
X1425533Y601230D03*
X1487677Y649988D03*
X1524437Y650208D03*
X1701285Y208455D03*
X1700840Y1434362D03*
X1731660Y208455D03*
X1770442Y294777D03*
X1800002D03*
G54D123*
X275005Y594223D03*
X273430D03*
X271855D03*
X270281D03*
X279729D03*
X278155D03*
X276580D03*
X483967Y218408D03*
X485541D03*
Y212896D03*
X512076Y209742D03*
X510501D03*
Y216828D03*
X512076D03*
X513651D03*
X576672Y222740D03*
X575098D03*
Y228252D03*
G54D222*
X771220Y1481045D03*
Y1535967D03*
G54D133*
X312693Y59753D03*
X328441D03*
X747269Y79238D03*
X763017D03*
X1655999Y385598D03*
X1671747D03*
X1784364Y61037D03*
X1800112D03*
G54D22*
X20587Y528693D03*
Y537355D03*
X26887D03*
Y528693D03*
X414963Y83352D03*
Y92014D03*
X421655D03*
Y83352D03*
G54D151*
X404743Y483094D03*
X402184D03*
X399625D03*
Y490476D03*
X402184D03*
X404743D03*
X418543Y483017D03*
X415984D03*
X413425D03*
Y490399D03*
X415984D03*
X418543D03*
X432343Y482940D03*
X429784D03*
X427225D03*
Y490322D03*
X429784D03*
X432343D03*
G54D142*
X347673Y130005D03*
Y126265D03*
Y122525D03*
X357319D03*
Y130005D03*
X1492797Y134562D03*
Y127082D03*
X1502443D03*
Y130822D03*
Y134562D03*
G54D106*
X190861Y120502D03*
X195979D03*
Y113022D03*
X193420D03*
X190861D03*
X203061Y120502D03*
X208179D03*
Y113022D03*
X205620D03*
X203061D03*
X409000Y1662260D03*
Y1669740D03*
X406441Y1662260D03*
Y1669740D03*
X411559Y1662260D03*
Y1669740D03*
X469975Y1720053D03*
Y1727533D03*
X467416Y1720053D03*
Y1727533D03*
X472534Y1720053D03*
Y1727533D03*
X1095489Y1703764D03*
Y1711244D03*
X1092930Y1703764D03*
Y1711244D03*
X1098048Y1703764D03*
Y1711244D03*
X1413622Y1625627D03*
X1418740D03*
X1416181D03*
X1418740Y1633107D03*
X1413622D03*
G54D160*
X430520Y248768D03*
Y253768D03*
Y258768D03*
Y263768D03*
X450992Y253768D03*
Y248768D03*
Y263768D03*
Y258768D03*
X1133070Y1579453D03*
Y1584453D03*
Y1589453D03*
Y1594453D03*
X1153542Y1579453D03*
Y1594453D03*
Y1589453D03*
Y1584453D03*
X1205182Y431875D03*
Y436875D03*
Y441875D03*
Y446875D03*
X1225654Y431875D03*
Y446875D03*
Y441875D03*
Y436875D03*
X1217866Y455376D03*
Y460376D03*
Y465376D03*
Y470376D03*
X1238338Y460376D03*
Y455376D03*
Y470376D03*
Y465376D03*
G54D31*
X45876Y384395D03*
Y386364D03*
Y388333D03*
Y390301D03*
Y392269D03*
Y394238D03*
Y396207D03*
X64872Y388333D03*
Y386364D03*
Y384395D03*
Y396207D03*
Y394238D03*
Y392269D03*
Y390301D03*
G54D205*
X667552Y149803D03*
Y151771D03*
Y153740D03*
Y155708D03*
Y165551D03*
Y167519D03*
Y169488D03*
Y171456D03*
Y173425D03*
Y175393D03*
Y177362D03*
Y179330D03*
Y181299D03*
Y183268D03*
Y185236D03*
Y187204D03*
Y189173D03*
Y191142D03*
Y193110D03*
Y195079D03*
Y197047D03*
Y199016D03*
Y200984D03*
Y202953D03*
Y204921D03*
Y206890D03*
Y208858D03*
Y210827D03*
Y212795D03*
Y214764D03*
Y216732D03*
Y218701D03*
Y220669D03*
X697277Y148819D03*
Y150787D03*
Y152756D03*
Y154724D03*
Y156693D03*
Y166535D03*
Y168504D03*
Y170472D03*
Y172441D03*
Y174409D03*
Y176378D03*
Y178346D03*
Y180315D03*
Y182283D03*
Y184252D03*
Y186220D03*
Y188189D03*
Y190157D03*
Y192126D03*
Y194094D03*
Y196063D03*
Y198031D03*
Y200000D03*
Y201968D03*
Y203937D03*
Y205905D03*
Y207874D03*
Y209842D03*
Y211811D03*
Y213779D03*
Y215748D03*
Y217716D03*
Y219685D03*
Y221653D03*
G54D250*
X916642Y1147586D03*
X963667D03*
X1326435Y553526D03*
X1632560Y553181D03*
G54D124*
X276088Y605247D03*
G54D223*
X762696Y1490789D03*
Y1506538D03*
Y1502600D03*
Y1498663D03*
Y1494726D03*
Y1522286D03*
Y1518349D03*
Y1514412D03*
Y1510474D03*
Y1526223D03*
X779744Y1492758D03*
Y1488821D03*
Y1504569D03*
Y1500632D03*
Y1496695D03*
Y1520317D03*
Y1516380D03*
Y1512443D03*
Y1508506D03*
Y1528191D03*
Y1524254D03*
G54D115*
X256978Y107835D03*
Y111771D03*
X690134Y111960D03*
Y115896D03*
X993943Y194419D03*
Y196387D03*
Y198356D03*
Y200325D03*
Y202293D03*
Y204261D03*
Y206230D03*
Y208199D03*
Y210167D03*
X1004967D03*
Y208199D03*
Y206230D03*
Y204261D03*
Y202293D03*
Y200325D03*
Y198356D03*
Y196387D03*
X1732099Y108959D03*
Y112895D03*
G54D232*
X796079Y1334469D03*
G54D13*
X11782Y174960D03*
X18691Y175132D03*
X33180Y301266D03*
X36524Y395255D03*
X32847Y537524D03*
X36372Y534279D03*
X50304Y61804D03*
X39008Y366396D03*
X51114D03*
X42809D03*
X48502Y507756D03*
X48626Y549744D03*
X52040Y1502281D03*
X48662Y1526319D03*
X50631Y1540155D03*
X50696Y1547353D03*
X51996Y1554426D03*
X46133Y1636380D03*
X51133D03*
X54616Y61804D03*
X63780Y301266D03*
X67681Y366396D03*
X59322D03*
X63429D03*
X56163Y416987D03*
X52902Y507569D03*
X58402D03*
X58633Y1593380D03*
X63633D03*
X56133Y1639480D03*
X61133D03*
X64427Y1649871D03*
X55427D03*
X69523Y416987D03*
X80378Y1412139D03*
X68768Y1550280D03*
X68133Y1593380D03*
X72660D03*
X81006Y1599391D03*
X77427Y1649871D03*
X78127Y1684871D03*
X70127D03*
X74127D03*
X94158Y1311085D03*
X90601Y1385773D03*
X94713Y1385821D03*
X84405Y1526319D03*
X86374Y1540655D03*
X82606Y1607691D03*
X86127Y1684871D03*
X92500Y1701934D03*
X98124Y1359700D03*
X98101Y1377021D03*
X101995Y1385652D03*
X107000Y1410484D03*
X104511Y1549980D03*
X112353Y1652071D03*
X120016Y297681D03*
Y318115D03*
X115590Y1384842D03*
X115353Y1693450D03*
X119353D03*
X130724Y1359700D03*
X130701Y1377021D03*
X134595Y1385652D03*
X141028Y1452096D03*
X137120Y1452142D03*
X133120D03*
X132353Y1652071D03*
X136353D03*
X139353Y1693571D03*
X131353D03*
X135353D03*
X132420Y1704495D03*
X144610Y427064D03*
X148190Y1384842D03*
X148000Y1417484D03*
X151000Y1445484D03*
X145028Y1452096D03*
X149028D03*
X152353Y1652071D03*
X151353Y1693571D03*
X143353D03*
X155353D03*
X163424Y1359700D03*
X163401Y1377021D03*
X167295Y1385652D03*
X158740Y1710484D03*
X183890Y393644D03*
X180890Y1384842D03*
X185760Y1710372D03*
X181760Y1728860D03*
X195979Y101126D03*
X190861Y128561D03*
X197645Y133671D03*
X196324Y1359700D03*
X196301Y1377021D03*
X200195Y1385652D03*
X189760Y1728860D03*
X208179Y101126D03*
X203061Y128561D03*
X213790Y1384842D03*
X229516Y155043D03*
X225090Y156454D03*
X229124Y1359700D03*
X229101Y1377021D03*
X243487Y107744D03*
X246297Y127027D03*
X242297D03*
X233595Y155055D03*
X244125Y666222D03*
X232995Y1385652D03*
X247487Y107744D03*
X261297Y127027D03*
X254297D03*
X250297D03*
X260100Y156946D03*
X254756Y159786D03*
X251424Y648243D03*
X246590Y1384842D03*
X271797Y127027D03*
X268297Y130527D03*
X275500Y233984D03*
X273069Y585054D03*
X272955Y666564D03*
X262724Y1313554D03*
X266595Y1339506D03*
X262701Y1330875D03*
X273597Y1522904D03*
X289357Y118987D03*
X284154Y682484D03*
X276855Y700463D03*
X280190Y1338696D03*
X279499Y1522904D03*
X302500Y253484D03*
X297815Y585938D03*
X305685Y700805D03*
X295620Y1313526D03*
X295597Y1330847D03*
X299491Y1339478D03*
X314602Y274075D03*
X316924Y702634D03*
X309655Y720323D03*
X313086Y1338668D03*
X325617Y84227D03*
X328524Y1313469D03*
X328501Y1330790D03*
X332395Y1339421D03*
X339811Y126161D03*
X346153Y273370D03*
X349984Y702366D03*
X342710Y720296D03*
X338455Y720955D03*
X345990Y1338611D03*
X352628Y286774D03*
X357582Y558274D03*
X353582D03*
X361324Y1313669D03*
X361301Y1330990D03*
X365195Y1339621D03*
X370064Y242620D03*
X371412Y275061D03*
X371962Y537151D03*
X375704Y720447D03*
X371515Y720687D03*
X378790Y1338811D03*
X395048Y126662D03*
X382184Y471835D03*
X393376Y472181D03*
X383024Y702434D03*
X393906Y1333000D03*
X393883Y1350321D03*
X384824Y1627197D03*
X394824D03*
X389824D03*
X384824Y1664604D03*
X394824D03*
X389824D03*
X406243Y105560D03*
X399264Y126628D03*
X400632Y144209D03*
X399299Y217555D03*
X402184Y471953D03*
Y504585D03*
X408739Y702578D03*
X404771Y696122D03*
X404555Y720755D03*
X397777Y1358952D03*
X401659Y1522904D03*
X407561D03*
X402969Y1625808D03*
X399824Y1664604D03*
X405000Y1680484D03*
X411299Y209604D03*
Y217555D03*
X415984Y471876D03*
Y504508D03*
X412771Y534122D03*
X416024Y684634D03*
X423921Y1009407D03*
X411372Y1358142D03*
X417000Y1667984D03*
Y1680484D03*
X433673Y80184D03*
X429997Y163609D03*
X433997Y156609D03*
X437997D03*
X439299Y217555D03*
X429784Y471799D03*
X439500Y496484D03*
X437309Y677911D03*
X437555Y702955D03*
X435141Y1009407D03*
X438882D03*
X427661D03*
X431401D03*
X427251Y1289178D03*
X441997Y163609D03*
X451299Y217555D03*
X443500Y489484D03*
X448424Y660034D03*
X441137Y677897D03*
X450102Y1009407D03*
X442622D03*
X446362D03*
X453842D03*
X453085Y1646917D03*
X466600Y145859D03*
X457997Y163609D03*
X465997D03*
X461931Y218162D03*
X458115Y244012D03*
X469038Y303622D03*
X469881Y651521D03*
X469955Y678355D03*
X457582Y1009407D03*
X461000Y1646984D03*
X475435Y209619D03*
X484754Y226436D03*
X481024Y633534D03*
X473732Y651523D03*
X483500Y1267846D03*
X478500Y1267984D03*
X474500D03*
X498314Y118402D03*
X485997Y163609D03*
X489997D03*
X494144Y218711D03*
X487107Y288213D03*
X488544Y295008D03*
X488538Y301687D03*
X487500Y1267846D03*
X492500D03*
X496500D03*
X501500Y429484D03*
X512000Y432484D03*
X501500Y422484D03*
X514324Y599434D03*
X502998Y617397D03*
X506964Y617405D03*
X502555Y651855D03*
X515539Y85626D03*
X522088Y207344D03*
X543131Y126314D03*
X536177Y246689D03*
X535855Y617755D03*
X537770Y1522904D03*
X543672D03*
X554196Y187740D03*
X556038Y312622D03*
X566460Y160553D03*
X574107Y297213D03*
X570216Y767496D03*
X582193Y86157D03*
Y93157D03*
X588194Y178034D03*
X575538Y310687D03*
X575567Y304152D03*
X579385Y379486D03*
X585585Y377536D03*
X579385Y390286D03*
Y404217D03*
X585585Y390286D03*
X575216Y767496D03*
X595260Y160553D03*
X602293Y209245D03*
X598294Y201245D03*
X602294D03*
X608793Y209245D03*
X608794Y201245D03*
X618705Y295789D03*
X615385Y379486D03*
Y390286D03*
Y409905D03*
X625310Y178593D03*
X626705Y295789D03*
X622705D03*
X621585Y377536D03*
Y390286D03*
X619500Y441984D03*
X626703Y1353168D03*
X630000Y1404484D03*
X635060Y146127D03*
X646231Y153035D03*
X638000Y425484D03*
X642500Y421984D03*
X643563Y1389881D03*
X647445Y1389905D03*
X635000Y1404484D03*
X637794Y1721454D03*
X653821Y87246D03*
X649500Y379484D03*
X655702Y1388407D03*
X659559Y1388349D03*
X651877Y1388374D03*
X652800Y1694284D03*
X656800D03*
X675843Y107169D03*
X666885Y408239D03*
X665832Y1530484D03*
X673113Y1722083D03*
Y1732745D03*
X680623Y111869D03*
X687453Y131152D03*
X683453D03*
X689440Y366388D03*
X690800Y379846D03*
X687500Y396346D03*
X679500Y523984D03*
X687310Y510846D03*
X692500D03*
X688500Y543346D03*
X688120Y1519510D03*
X704953Y131152D03*
X694453D03*
X700963Y131212D03*
X707545Y366305D03*
X703520Y366388D03*
X708300Y379846D03*
X704300D03*
X700300D03*
X707500Y396346D03*
X699500D03*
X695500D03*
X703500D03*
X700500Y510846D03*
X696500D03*
Y527346D03*
X700500Y543346D03*
X704500Y553346D03*
X704056Y580565D03*
X698996D03*
X708056D03*
X694996D03*
X698699Y1348854D03*
X705680Y1377709D03*
X705657Y1395030D03*
X701661Y1395052D03*
X697731Y1395022D03*
X698500Y1593984D03*
X696030Y1630761D03*
X699799Y1630677D03*
X723500Y366346D03*
X715395Y366336D03*
X712300Y379846D03*
X720300D03*
X715500Y396346D03*
X711500D03*
X720500Y553346D03*
Y543346D03*
X720787Y633815D03*
X716721Y633751D03*
X711702Y652240D03*
X709551Y1403661D03*
X723146Y1402661D03*
X710217Y1438722D03*
X723050Y1602417D03*
X717110Y1602507D03*
X715152Y1630565D03*
X729380Y78002D03*
X734380D03*
X723933Y138472D03*
X731500Y366346D03*
X727564Y379846D03*
X735500Y396346D03*
X732500Y510846D03*
X728500D03*
X736500D03*
X728500Y543346D03*
X736500D03*
X732500Y543484D03*
X738462Y1377809D03*
X738439Y1395130D03*
X732723Y1630004D03*
X736723D03*
X728723D03*
X737468Y1690187D03*
X732434Y1688157D03*
X728454Y1687988D03*
X745500Y202484D03*
X747500Y379846D03*
X743500Y396346D03*
X747500D03*
X751500D03*
X739652Y396328D03*
X744500Y510846D03*
X752500D03*
X748500D03*
X740895Y527365D03*
X748500Y527346D03*
X752500D03*
X744500D03*
X752500Y543346D03*
X742333Y1403761D03*
X740723Y1630004D03*
X741326Y1686796D03*
X752187Y1688478D03*
X760193Y103712D03*
X761000Y215484D03*
X759500Y379846D03*
Y396346D03*
X755500D03*
X764500Y510846D03*
X756500D03*
X760500D03*
X756500Y527346D03*
X760500D03*
X764500D03*
X765000Y543346D03*
X755928Y1402761D03*
X757770Y1631267D03*
X761770D03*
X754030Y1659067D03*
Y1666067D03*
X762030D03*
X767368Y1665546D03*
X767381Y1673225D03*
X773766Y284306D03*
X781456Y381101D03*
X775500Y396346D03*
X771500D03*
X773000Y543346D03*
X768700Y543484D03*
X779447Y1337240D03*
X770450Y1584017D03*
X789277Y1527313D03*
X809817Y564921D03*
X807669Y1304700D03*
X812750Y1584917D03*
X819114Y120682D03*
X823114D03*
X827114D03*
X826614Y150182D03*
X824500Y511484D03*
X820500D03*
X831114Y120682D03*
X839360Y120566D03*
X840221Y187846D03*
X840220Y200846D03*
X839000Y388984D03*
X841872Y538169D03*
X844936Y93235D03*
X844221Y187846D03*
X844220Y200846D03*
X848500Y457984D03*
X852000Y488984D03*
X848762Y527472D03*
X854750Y1584917D03*
X871500Y319484D03*
X867190Y387744D03*
X871190D03*
X864065Y519020D03*
X886503Y281771D03*
X876923Y1245404D03*
X889368Y1144562D03*
X893368D03*
X895394Y1162815D03*
X896750Y1584917D03*
X916268Y275343D03*
X945263Y277640D03*
X936393Y1144562D03*
X940393D03*
X942419Y1162815D03*
X935907Y1245404D03*
X965442Y174869D03*
X981445Y182567D03*
X977195Y210907D03*
X1005699Y174327D03*
X999915Y182057D03*
X996415D03*
X1005395Y221407D03*
X1009735Y160927D03*
X1014828Y264749D03*
Y273911D03*
X1015334Y294295D03*
X1007011Y544983D03*
X1019961Y560416D03*
X1023220Y189083D03*
X1024961Y560416D03*
X1039000Y560484D03*
X1064915Y1310972D03*
X1066363Y1385534D03*
X1062405Y1385502D03*
X1063751Y1650978D03*
X1064221Y1659904D03*
X1069322Y404032D03*
X1069862Y1359681D03*
X1073733Y1385633D03*
X1069839Y1377002D03*
X1068094Y1650979D03*
X1068221Y1659904D03*
X1087328Y1384823D03*
X1094514Y1725900D03*
X1102462Y1359681D03*
X1102439Y1377002D03*
X1106333Y1385633D03*
X1108747Y1531864D03*
X1109558Y1547570D03*
X1105000Y1679484D03*
X1098514Y1718900D03*
X1119928Y1384823D03*
X1114617Y1531864D03*
X1115005Y1582535D03*
X1116000Y1668484D03*
X1120303Y1679419D03*
X1119361Y1719218D03*
X1135162Y1359681D03*
X1135139Y1377002D03*
X1139033Y1385633D03*
X1129846Y1459432D03*
X1131256Y1572011D03*
X1140117Y1668636D03*
X1152628Y1384823D03*
X1144107Y1668550D03*
X1168062Y1359681D03*
X1168039Y1377002D03*
X1178340Y472649D03*
X1180849Y464674D03*
X1171933Y1385633D03*
X1185528Y1384823D03*
X1195488Y91034D03*
X1215581Y88830D03*
X1200862Y1359681D03*
X1200839Y1377002D03*
X1204733Y1385633D03*
X1208000Y1396984D03*
X1210254Y1709920D03*
Y1730920D03*
Y1716920D03*
Y1723920D03*
X1206254Y1727770D03*
X1223455Y88830D03*
X1218328Y1384823D03*
X1238853Y1313535D03*
X1242724Y1339487D03*
X1238830Y1330856D03*
X1245000Y1429984D03*
Y1436984D03*
Y1443984D03*
X1241000D03*
X1253152Y90379D03*
Y101009D03*
X1256319Y1338677D03*
X1247000Y1406484D03*
X1256859Y1422984D03*
X1249000Y1429984D03*
Y1436984D03*
X1253000D03*
X1263472Y90348D03*
X1271749Y1313507D03*
X1271726Y1330828D03*
X1275620Y1339459D03*
X1289215Y1338649D03*
X1281470Y1555904D03*
X1287372D03*
X1296386Y548307D03*
X1299986D03*
X1296156Y558932D03*
X1304653Y1313450D03*
X1304630Y1330771D03*
X1307857Y108837D03*
X1305187Y568755D03*
X1308524Y1339402D03*
X1331930Y64429D03*
X1322119Y1338592D03*
X1343840Y64395D03*
X1337453Y1313650D03*
X1337430Y1330971D03*
X1341324Y1339602D03*
X1355750Y64395D03*
X1361976Y617577D03*
X1350261Y635565D03*
X1354597D03*
X1354919Y1338792D03*
X1367950Y64395D03*
X1370035Y1332981D03*
X1373906Y1358933D03*
X1370012Y1350302D03*
X1383507Y635898D03*
X1387297Y668465D03*
X1387501Y1358123D03*
X1394676Y650477D03*
X1407543Y1009406D03*
X1403803D03*
X1400063D03*
X1416207Y668798D03*
X1420007Y700715D03*
X1415024Y1009406D03*
X1411283D03*
X1418764D03*
X1422504D03*
X1417711Y1261850D03*
X1421211D03*
X1409532Y1555904D03*
X1415434D03*
X1415622Y1613251D03*
X1410622D03*
X1413622Y1640826D03*
X1434262Y58376D03*
X1439049Y112927D03*
X1429169Y112797D03*
X1427276Y683057D03*
X1433724Y1009406D03*
X1429984D03*
X1426244D03*
X1438532Y1278244D03*
X1448549Y120127D03*
X1443049Y112927D03*
X1448807Y701378D03*
X1452765Y720391D03*
X1449334Y1274976D03*
X1453334D03*
X1442532Y1278244D03*
X1450500Y1620484D03*
Y1629984D03*
X1445500D03*
X1440500D03*
X1442579Y1670787D03*
X1447579D03*
X1452579D03*
X1459896Y61472D03*
X1454549Y112927D03*
X1460194Y702634D03*
X1457579Y1670787D03*
X1481725Y720955D03*
X1493276Y702634D03*
X1485897Y720622D03*
X1513644Y249409D03*
X1505477Y1273872D03*
X1526076Y702634D03*
X1518697Y720622D03*
X1514807Y720955D03*
X1533454Y91205D03*
X1537454D03*
X1542697Y565071D03*
X1547827Y698514D03*
X1551827D03*
X1547607Y720955D03*
X1556178Y1265847D03*
X1558077Y1276272D03*
X1554377D03*
X1545644Y1555904D03*
X1551546D03*
X1559206Y680694D03*
X1560157Y1265847D03*
X1584597Y664913D03*
X1580597D03*
X1580737Y699015D03*
X1583177Y1265272D03*
X1587177D03*
X1575680Y1302963D03*
X1588800Y306655D03*
X1591976Y646925D03*
X1591177Y1265272D03*
X1617400Y306655D03*
X1617506Y567910D03*
X1617597Y645913D03*
X1613597D03*
X1613507Y665246D03*
X1629000Y388984D03*
Y395984D03*
X1624976Y627925D03*
X1646510Y431528D03*
X1646507Y646246D03*
X1645155Y1394304D03*
X1634327Y1409424D03*
X1662000Y220984D03*
X1651910Y232971D03*
X1652610Y400186D03*
X1661110Y431686D03*
X1653413Y1376998D03*
X1657284Y1402950D03*
X1653390Y1394319D03*
X1649197Y1394252D03*
X1653667Y1443225D03*
X1658167D03*
X1662465Y1441658D03*
X1657892Y1455344D03*
X1653614Y1455323D03*
X1650513Y1711668D03*
Y1726818D03*
Y1718668D03*
Y1733818D03*
X1673872Y431129D03*
X1670879Y1401950D03*
X1666290Y1441691D03*
X1670147Y1441633D03*
X1673706Y1563484D03*
X1675360Y1711986D03*
Y1726736D03*
X1684942Y231396D03*
X1686154Y431669D03*
X1686195Y1377098D03*
X1690066Y1403050D03*
X1686172Y1394419D03*
X1688243Y1669286D03*
X1692415Y1669224D03*
X1679816Y1669287D03*
X1685513Y1711668D03*
Y1718668D03*
X1704624Y431159D03*
X1701124D03*
X1703661Y1402050D03*
X1718608Y104068D03*
X1721418Y128151D03*
X1717418D03*
X1713312Y141206D03*
X1715044Y410029D03*
X1718931Y410021D03*
X1710408Y423429D03*
X1720845Y1676818D03*
X1710360Y1711986D03*
X1722608Y108868D03*
X1736418Y128151D03*
X1729418D03*
X1725418D03*
X1730364Y174435D03*
X1722500Y371846D03*
X1725500Y380846D03*
X1735945Y1559355D03*
X1728633Y1708174D03*
X1724633Y1715174D03*
Y1708174D03*
Y1723324D03*
Y1730324D03*
X1746918Y128151D03*
X1743418Y131651D03*
X1740688Y1534088D03*
X1737914Y1573191D03*
X1737979Y1580389D03*
X1739279Y1587462D03*
X1750380Y1713292D03*
X1749480Y1723642D03*
X1764478Y120111D03*
X1756051Y1583316D03*
X1758963Y1688949D03*
X1763463D03*
X1771688Y1559355D03*
X1773657Y1573691D03*
X1790738Y85351D03*
X1784133Y165883D03*
Y158794D03*
X1783448Y210441D03*
X1791794Y1583016D03*
X1819705Y166856D03*
G54D40*
X57646Y12480D03*
X137272D03*
X186622D03*
X266858D03*
X315598D03*
X502528Y33267D03*
X582154D03*
X631504D03*
X711740D03*
X760480D03*
X1183858Y207205D03*
Y217205D03*
X1173858D03*
X1193858Y207205D03*
Y217205D03*
X1351260Y164213D03*
Y174213D03*
X1361260Y164213D03*
Y174213D03*
X1371260Y164213D03*
X1381260D03*
X1371260Y174213D03*
X1381260D03*
X1391260Y164213D03*
X1532055Y12480D03*
X1611681D03*
X1661031D03*
X1741267D03*
X1790007D03*
G54D214*
X722356Y1573552D03*
X718813D03*
X720585D03*
Y1591170D03*
X722356D03*
X718813D03*
X736530Y1573552D03*
X734758D03*
X732986D03*
X731215D03*
X729443D03*
X727671D03*
X724128D03*
X725900D03*
Y1591170D03*
X727671D03*
X729443D03*
X731215D03*
X732986D03*
X734758D03*
X736530D03*
X724128D03*
X740073Y1573552D03*
X738301D03*
Y1591170D03*
X740073D03*
G54D241*
X876098Y1092807D03*
X897358D03*
X966577Y1092258D03*
X987837D03*
G54D116*
X258455Y669601D03*
X291185Y703842D03*
X323955Y723992D03*
X357015Y723724D03*
X390055Y723792D03*
X423055Y705992D03*
X455455Y681392D03*
X488055Y654892D03*
X521355Y620792D03*
X1369007Y638935D03*
X1401707Y671835D03*
X1434307Y704415D03*
X1467225Y723992D03*
X1500307Y724160D03*
X1533107Y723992D03*
X1566237Y702052D03*
X1599007Y668283D03*
X1632007Y649283D03*
G54D170*
X481550Y295282D03*
X568550Y304282D03*
G54D134*
X318333Y78520D03*
X316364D03*
X314395D03*
X312427D03*
X310459D03*
X308490D03*
X306521D03*
X318333Y80489D03*
X316364D03*
X314395D03*
X312427D03*
X310459D03*
X308490D03*
X306521D03*
X318333Y82457D03*
X316364D03*
X314395D03*
X312427D03*
X310459D03*
X308490D03*
X306521D03*
X318333Y84426D03*
X316364D03*
X314395D03*
X312427D03*
X310459D03*
X308490D03*
X306521D03*
X354139Y232608D03*
X356108D03*
X358077D03*
X360045D03*
X362013D03*
X363982D03*
X354139Y230639D03*
X356108D03*
X358077D03*
X360045D03*
X362013D03*
X363982D03*
X354139Y228671D03*
X356108D03*
X358077D03*
X360045D03*
X362013D03*
X363982D03*
X354139Y226702D03*
X356108D03*
X358077D03*
X360045D03*
X362013D03*
X363982D03*
X365951Y232608D03*
Y230639D03*
Y228671D03*
Y226702D03*
X750940Y98005D03*
X748971D03*
X747003D03*
X745035D03*
X743066D03*
X741097D03*
X750940Y99974D03*
X748971D03*
X747003D03*
X745035D03*
X743066D03*
X741097D03*
X750940Y101942D03*
X748971D03*
X747003D03*
X745035D03*
X743066D03*
X741097D03*
X750940Y103911D03*
X748971D03*
X747003D03*
X745035D03*
X743066D03*
X741097D03*
X752909Y98005D03*
Y99974D03*
Y101942D03*
Y103911D03*
X871345Y276064D03*
X869376D03*
X867407D03*
X871345Y278033D03*
X869376D03*
X867407D03*
X871345Y280001D03*
X869376D03*
X867407D03*
X871345Y281970D03*
X869376D03*
X867407D03*
X879219Y276064D03*
X877250D03*
X875281D03*
X873313D03*
X879219Y278033D03*
X877250D03*
X875281D03*
X873313D03*
X879219Y280001D03*
X877250D03*
X875281D03*
X873313D03*
X879219Y281970D03*
X877250D03*
X875281D03*
X873313D03*
X992452Y159667D03*
Y161636D03*
Y163605D03*
Y165573D03*
X994421Y159667D03*
Y161636D03*
Y163605D03*
Y165573D03*
X996389Y159667D03*
Y161636D03*
Y163605D03*
Y165573D03*
X998358Y159667D03*
Y161636D03*
Y163605D03*
Y165573D03*
X992452Y167541D03*
Y169510D03*
Y171479D03*
X994421Y167541D03*
Y169510D03*
Y171479D03*
X996389Y167541D03*
Y169510D03*
Y171479D03*
X998358Y167541D03*
Y169510D03*
Y171479D03*
X1697161Y408769D03*
Y410738D03*
Y412707D03*
Y414675D03*
Y416643D03*
Y418612D03*
X1699130Y408769D03*
Y410738D03*
Y412707D03*
Y414675D03*
Y416643D03*
Y418612D03*
X1701098Y408769D03*
Y410738D03*
Y412707D03*
Y414675D03*
Y416643D03*
Y418612D03*
X1703067Y408769D03*
Y410738D03*
Y412707D03*
Y414675D03*
Y416643D03*
Y418612D03*
X1697161Y420581D03*
X1699130D03*
X1701098D03*
X1703067D03*
X1779516Y79644D03*
X1777548D03*
X1775580D03*
X1773611D03*
X1771642D03*
X1779516Y81613D03*
X1777548D03*
X1775580D03*
X1773611D03*
X1771642D03*
X1779516Y83581D03*
X1777548D03*
X1775580D03*
X1773611D03*
X1771642D03*
X1779516Y85550D03*
X1777548D03*
X1775580D03*
X1773611D03*
X1771642D03*
X1783454Y79644D03*
X1781485D03*
X1783454Y81613D03*
X1781485D03*
X1783454Y83581D03*
X1781485D03*
X1783454Y85550D03*
X1781485D03*
G54D23*
X27048Y1533228D03*
X79590Y1369350D03*
X137284Y1533228D03*
X215418Y658055D03*
X276440Y1357539D03*
X420125Y656008D03*
X443764Y1339823D03*
X523173Y578174D03*
X681440Y1385138D03*
X791678D03*
X873622Y1145275D03*
X983858D03*
X1052960Y1369350D03*
X1249812Y1357539D03*
X1370284Y582303D03*
X1417134Y1339823D03*
X1533552Y682342D03*
X1629732Y1383523D03*
X1664890Y642972D03*
X1714330Y1570984D03*
X1739968Y1383527D03*
X1761575Y159134D03*
X1824566Y1570988D03*
X1838150Y201929D03*
G54D41*
X65933Y32756D03*
Y44370D03*
X68295Y32756D03*
X70657D03*
X73020D03*
X75382D03*
X77744D03*
X80106D03*
X68295Y44370D03*
X70657D03*
X73020D03*
X75382D03*
X77744D03*
X80106D03*
X82468Y32756D03*
X84831D03*
X87193D03*
X89555D03*
X91917D03*
X94279D03*
X96642D03*
X82468Y44370D03*
X84831D03*
X87193D03*
X89555D03*
X91917D03*
X94279D03*
X96642D03*
X99004Y32756D03*
X101366D03*
X103728D03*
X106090D03*
X108453D03*
X110815D03*
X99004Y44370D03*
X101366D03*
X103728D03*
X106090D03*
X108453D03*
X110815D03*
X113177Y32756D03*
X115539D03*
X117902D03*
X120264D03*
X122626D03*
X124988D03*
X113177Y44370D03*
X115539D03*
X117902D03*
X120264D03*
X122626D03*
X124988D03*
X127350Y32756D03*
X129713D03*
X127350Y44370D03*
X129713D03*
X149043Y32756D03*
X151405D03*
X153768D03*
X156130D03*
X149043Y44370D03*
X151405D03*
X153768D03*
X156130D03*
X158492Y32756D03*
X160854D03*
X163216D03*
X165579D03*
X167941D03*
X170303D03*
X158492Y44370D03*
X160854D03*
X163216D03*
X165579D03*
X167941D03*
X170303D03*
X172665Y32756D03*
X175028D03*
X177390D03*
X179752D03*
X172665Y44370D03*
X175028D03*
X177390D03*
X179752D03*
X195539Y32756D03*
X197902D03*
X200264D03*
X195539Y44370D03*
X197902D03*
X200264D03*
X202626Y32756D03*
X204988D03*
X207350D03*
X209713D03*
X212075D03*
X214437D03*
X202626Y44370D03*
X204988D03*
X207350D03*
X209713D03*
X212075D03*
X214437D03*
X216799Y32756D03*
X219161D03*
X221524D03*
X223886D03*
X226248D03*
X228610D03*
X230972D03*
X216799Y44370D03*
X219161D03*
X221524D03*
X223886D03*
X226248D03*
X228610D03*
X230972D03*
X233335Y32756D03*
X235697D03*
X238059D03*
X240421D03*
X242783D03*
X245146D03*
X233335Y44370D03*
X235697D03*
X238059D03*
X240421D03*
X242783D03*
X245146D03*
X247508Y32756D03*
X249870D03*
X252232D03*
X254594D03*
X256957D03*
X259319D03*
X247508Y44370D03*
X249870D03*
X252232D03*
X254594D03*
X256957D03*
X259319D03*
X276622Y32756D03*
X278984D03*
X281346D03*
X283709D03*
X286071D03*
X288433D03*
X290795D03*
X276622Y44370D03*
X278984D03*
X281346D03*
X283709D03*
X286071D03*
X288433D03*
X290795D03*
X293157Y32756D03*
X295520D03*
X297882D03*
X300244D03*
X302606D03*
X304968D03*
X293157Y44370D03*
X295520D03*
X297882D03*
X300244D03*
X302606D03*
X304968D03*
X307331Y32756D03*
Y44370D03*
X510815Y53543D03*
X513177D03*
X510815Y65157D03*
X513177D03*
X515539Y53543D03*
X517902D03*
X520264D03*
X522626D03*
X524988D03*
X527350D03*
X515539Y65157D03*
X517902D03*
X520264D03*
X522626D03*
X524988D03*
X527350D03*
X529713Y53543D03*
X532075D03*
X534437D03*
X536799D03*
X539161D03*
X541524D03*
X543886D03*
X529713Y65157D03*
X532075D03*
X534437D03*
X536799D03*
X539161D03*
X541524D03*
X543886D03*
X546248Y53543D03*
X548610D03*
X550972D03*
X553335D03*
X555697D03*
X558059D03*
X546248Y65157D03*
X548610D03*
X550972D03*
X553335D03*
X555697D03*
X558059D03*
X560421Y53543D03*
X562784D03*
X565146D03*
X567508D03*
X569870D03*
X572232D03*
X560421Y65157D03*
X562784D03*
X565146D03*
X567508D03*
X569870D03*
X572232D03*
X574595Y53543D03*
Y65157D03*
X593925Y53543D03*
X596287D03*
X598650D03*
X601012D03*
X603374D03*
X593925Y65157D03*
X596287D03*
X598650D03*
X601012D03*
X603374D03*
X605736Y53543D03*
X608098D03*
X610461D03*
X612823D03*
X615185D03*
X617547D03*
X605736Y65157D03*
X608098D03*
X610461D03*
X612823D03*
X615185D03*
X617547D03*
X619910Y53543D03*
X622272D03*
X624634D03*
X619910Y65157D03*
X622272D03*
X624634D03*
X640421Y53543D03*
X642784D03*
X645146D03*
X647508D03*
X640421Y65157D03*
X642784D03*
X645146D03*
X647508D03*
X649870Y53543D03*
X652232D03*
X654595D03*
X656957D03*
X659319D03*
X661681D03*
X649870Y65157D03*
X652232D03*
X654595D03*
X656957D03*
X659319D03*
X661681D03*
X664043Y53543D03*
X666406D03*
X668768D03*
X671130D03*
X673492D03*
X675854D03*
X678217D03*
X664043Y65157D03*
X666406D03*
X668768D03*
X671130D03*
X673492D03*
X675854D03*
X678217D03*
X680579Y53543D03*
X682941D03*
X685303D03*
X687665D03*
X690028D03*
X692390D03*
X680579Y65157D03*
X682941D03*
X685303D03*
X687665D03*
X690028D03*
X692390D03*
X694752Y53543D03*
X697114D03*
X699476D03*
X701839D03*
X704201D03*
X694752Y65157D03*
X697114D03*
X699476D03*
X701839D03*
X704201D03*
X721504Y53543D03*
Y65157D03*
X723866Y53543D03*
X726228D03*
X728591D03*
X730953D03*
X733315D03*
X735677D03*
X738039D03*
X723866Y65157D03*
X726228D03*
X728591D03*
X730953D03*
X733315D03*
X735677D03*
X738039D03*
X740402Y53543D03*
X742764D03*
X745126D03*
X747488D03*
X749850D03*
X752213D03*
X740402Y65157D03*
X742764D03*
X745126D03*
X747488D03*
X749850D03*
X752213D03*
X1540342Y32756D03*
X1542704D03*
X1540342Y44370D03*
X1542704D03*
X1545066Y32756D03*
X1547429D03*
X1549791D03*
X1552153D03*
X1554515D03*
X1556877D03*
X1545066Y44370D03*
X1547429D03*
X1549791D03*
X1552153D03*
X1554515D03*
X1556877D03*
X1559240Y32756D03*
X1561602D03*
X1563964D03*
X1566326D03*
X1568688D03*
X1571051D03*
X1559240Y44370D03*
X1561602D03*
X1563964D03*
X1566326D03*
X1568688D03*
X1571051D03*
X1573413Y32756D03*
X1575775D03*
X1578137D03*
X1580499D03*
X1582862D03*
X1585224D03*
X1587586D03*
X1573413Y44370D03*
X1575775D03*
X1578137D03*
X1580499D03*
X1582862D03*
X1585224D03*
X1587586D03*
X1589948Y32756D03*
X1592311D03*
X1594673D03*
X1597035D03*
X1599397D03*
X1601759D03*
X1589948Y44370D03*
X1592311D03*
X1594673D03*
X1597035D03*
X1599397D03*
X1601759D03*
X1604122Y32756D03*
Y44370D03*
X1623452Y32756D03*
X1625814D03*
X1628177D03*
X1630539D03*
X1623452Y44370D03*
X1625814D03*
X1628177D03*
X1630539D03*
X1632901Y32756D03*
X1635263D03*
X1637625D03*
X1639988D03*
X1642350D03*
X1644712D03*
X1647074D03*
X1632901Y44370D03*
X1635263D03*
X1637625D03*
X1639988D03*
X1642350D03*
X1644712D03*
X1647074D03*
X1649437Y32756D03*
X1651799D03*
X1654161D03*
X1649437Y44370D03*
X1651799D03*
X1654161D03*
X1669948Y32756D03*
X1672311D03*
X1674673D03*
X1677035D03*
X1669948Y44370D03*
X1672311D03*
X1674673D03*
X1677035D03*
X1679397Y32756D03*
X1681759D03*
X1684122D03*
X1686484D03*
X1688846D03*
X1691208D03*
X1679397Y44370D03*
X1681759D03*
X1684122D03*
X1686484D03*
X1688846D03*
X1691208D03*
X1693570Y32756D03*
X1695933D03*
X1698295D03*
X1700657D03*
X1703019D03*
X1705381D03*
X1693570Y44370D03*
X1695933D03*
X1698295D03*
X1700657D03*
X1703019D03*
X1705381D03*
X1707744Y32756D03*
X1710106D03*
X1712468D03*
X1714830D03*
X1717192D03*
X1719555D03*
X1721917D03*
X1707744Y44370D03*
X1710106D03*
X1712468D03*
X1714830D03*
X1717192D03*
X1719555D03*
X1721917D03*
X1724279Y32756D03*
X1726641D03*
X1729003D03*
X1731366D03*
X1733728D03*
X1724279Y44370D03*
X1726641D03*
X1729003D03*
X1731366D03*
X1733728D03*
X1751031Y32756D03*
Y44370D03*
X1753393Y32756D03*
X1755755D03*
X1758118D03*
X1760480D03*
X1762842D03*
X1765204D03*
X1753393Y44370D03*
X1755755D03*
X1758118D03*
X1760480D03*
X1762842D03*
X1765204D03*
X1767566Y32756D03*
X1769929D03*
X1772291D03*
X1774653D03*
X1777015D03*
X1779377D03*
X1781740D03*
X1767566Y44370D03*
X1769929D03*
X1772291D03*
X1774653D03*
X1777015D03*
X1779377D03*
X1781740D03*
G54D161*
X453472Y489760D03*
Y497240D03*
X462528Y493500D03*
G54D215*
X721963Y1577932D03*
Y1586790D03*
G54D242*
X887519Y1528191D03*
G54D152*
X410379Y1569803D03*
X405379D03*
X400379D03*
Y1590275D03*
X405379D03*
X410379D03*
X415379Y1569803D03*
X425374D03*
X415379Y1590275D03*
X425374D03*
X440374Y1569803D03*
X435374D03*
X430374D03*
Y1590275D03*
X435374D03*
X440374D03*
X649284Y1658333D03*
X644284D03*
X639284D03*
Y1678805D03*
X644284D03*
X649284D03*
X654284Y1658333D03*
X662971Y1658547D03*
X654284Y1678805D03*
X662971Y1679019D03*
X677971Y1658547D03*
X672971D03*
X667971D03*
Y1679019D03*
X672971D03*
X677971D03*
X1169187Y1662159D03*
Y1682631D03*
X1184187Y1662159D03*
X1179187D03*
X1174187D03*
Y1682631D03*
X1179187D03*
X1184187D03*
X1661101Y1675927D03*
X1656101D03*
X1651101D03*
Y1696399D03*
X1656101D03*
X1661101D03*
X1666101Y1675927D03*
Y1696399D03*
G54D32*
X44967Y416860D03*
D03*
Y413710D03*
X50339Y416945D03*
Y413795D03*
Y416945D03*
X44967Y420010D03*
X50339Y420095D03*
X60189Y417070D03*
Y413920D03*
X65533Y414040D03*
Y410890D03*
Y417190D03*
Y414040D03*
X60189Y413920D03*
Y410770D03*
X238297Y123968D03*
Y127118D03*
X556280Y119790D03*
X551280D03*
X556280Y126090D03*
Y122940D03*
X551280Y126090D03*
Y122940D03*
X556280D03*
X551280D03*
X568360Y119635D03*
X573360D03*
X568360Y122785D03*
X573360D03*
X568360Y125935D03*
Y122785D03*
X573360Y125935D03*
Y122785D03*
X714129Y664242D03*
Y667392D03*
Y661092D03*
Y664242D03*
X726201Y664244D03*
Y667394D03*
Y661094D03*
Y664244D03*
X1016770Y233573D03*
Y230423D03*
X1256785Y754715D03*
Y757865D03*
D03*
Y761015D03*
X1263706Y754715D03*
Y757865D03*
D03*
Y761015D03*
X1713000Y654925D03*
Y651775D03*
Y658075D03*
Y654925D03*
Y670425D03*
Y673575D03*
Y676725D03*
Y673575D03*
G54D143*
X362651Y283902D03*
Y285870D03*
Y287838D03*
X370525Y283902D03*
Y287838D03*
Y285870D03*
X777703Y275290D03*
Y273322D03*
Y271354D03*
X769829D03*
Y273322D03*
Y275290D03*
G54D260*
X1008631Y514587D03*
Y517146D03*
Y519705D03*
Y522264D03*
Y524824D03*
Y527383D03*
Y529942D03*
Y532501D03*
X1030679Y522264D03*
Y519705D03*
Y517146D03*
Y514587D03*
Y532501D03*
Y529942D03*
Y527383D03*
Y524824D03*
X1040045Y376007D03*
Y378566D03*
Y381125D03*
Y383684D03*
Y386244D03*
Y388803D03*
Y391362D03*
Y393921D03*
X1040425Y411704D03*
Y414263D03*
Y416822D03*
Y419381D03*
Y421941D03*
Y424500D03*
Y427059D03*
Y429618D03*
X1062093Y388803D03*
Y386244D03*
Y383684D03*
Y381125D03*
Y378566D03*
Y376007D03*
Y393921D03*
Y391362D03*
X1062473Y419381D03*
Y416822D03*
Y414263D03*
Y411704D03*
Y429618D03*
Y427059D03*
Y424500D03*
Y421941D03*
X1097111Y375469D03*
Y378028D03*
Y380587D03*
Y383146D03*
Y385706D03*
Y388265D03*
Y390824D03*
Y393383D03*
X1119159Y388265D03*
Y385706D03*
Y383146D03*
Y380587D03*
Y378028D03*
Y375469D03*
Y393383D03*
Y390824D03*
X1220178Y162158D03*
Y164717D03*
Y167276D03*
Y169835D03*
Y172395D03*
Y174954D03*
Y177513D03*
Y180072D03*
X1242226Y164717D03*
Y162158D03*
Y180072D03*
Y177513D03*
Y174954D03*
Y172395D03*
Y169835D03*
Y167276D03*
G54D125*
X268312Y605247D03*
X281698Y594223D03*
G54D224*
X782624Y1573554D03*
X780656D03*
Y1591172D03*
X782624D03*
X790498Y1573554D03*
X788530D03*
X786561D03*
X784593D03*
Y1591172D03*
X786561D03*
X788530D03*
X790498D03*
X826593Y1573554D03*
X824624D03*
X822656D03*
Y1591172D03*
X824624D03*
X826593D03*
X832498Y1573554D03*
X830530D03*
X828561D03*
Y1591172D03*
X830530D03*
X832498D03*
X870561Y1573554D03*
X868593D03*
X866624D03*
X864656D03*
Y1591172D03*
X866624D03*
X868593D03*
X870561D03*
X874498Y1573554D03*
X872530D03*
Y1591172D03*
X874498D03*
X916498Y1573554D03*
X914530D03*
X912561D03*
X910593D03*
X908624D03*
X906656D03*
Y1591172D03*
X908624D03*
X910593D03*
X912561D03*
X914530D03*
X916498D03*
G54D14*
X11782Y171993D03*
X18691Y172165D03*
X33180Y298299D03*
X36524Y392288D03*
X32847Y534557D03*
X36372Y531312D03*
X50304Y58837D03*
X39008Y363429D03*
X51114D03*
X42809D03*
X48502Y504789D03*
X48626Y546777D03*
X52040Y1499314D03*
X50631Y1537188D03*
X48662Y1523352D03*
X51996Y1551459D03*
X50696Y1544386D03*
X46133Y1633413D03*
X51133D03*
X54616Y58837D03*
X63780Y298299D03*
X67681Y363429D03*
X59322D03*
X63429D03*
X56163Y414020D03*
X52902Y504602D03*
X58402D03*
X58633Y1590413D03*
X63633D03*
X56133Y1636513D03*
X61133D03*
X64427Y1646904D03*
X55427D03*
X69523Y414020D03*
X80378Y1409172D03*
X68768Y1547313D03*
X81006Y1596424D03*
X68133Y1590413D03*
X72660D03*
X77427Y1646904D03*
X78127Y1681904D03*
X70127D03*
X74127D03*
X94158Y1308118D03*
X90601Y1382806D03*
X94713Y1382854D03*
X86374Y1537688D03*
X84405Y1523352D03*
X82606Y1604724D03*
X86127Y1681904D03*
X92500Y1698967D03*
X98124Y1356733D03*
X98101Y1374054D03*
X101995Y1382685D03*
X107000Y1407517D03*
X104511Y1547013D03*
X112353Y1649104D03*
X120016Y294714D03*
Y315148D03*
X115590Y1381875D03*
X115353Y1690483D03*
X119353D03*
X130724Y1356733D03*
X130701Y1374054D03*
X134595Y1382685D03*
X141028Y1449129D03*
X137120Y1449175D03*
X133120D03*
X132353Y1649104D03*
X136353D03*
X132420Y1701528D03*
X139353Y1690604D03*
X131353D03*
X135353D03*
X144610Y424097D03*
X148190Y1381875D03*
X148000Y1414517D03*
X151000Y1442517D03*
X145028Y1449129D03*
X149028D03*
X152353Y1649104D03*
X151353Y1690604D03*
X143353D03*
X155353D03*
X163424Y1356733D03*
X163401Y1374054D03*
X167295Y1382685D03*
X158740Y1707517D03*
X183890Y390677D03*
X180890Y1381875D03*
X185760Y1707405D03*
X181760Y1725893D03*
X195979Y98159D03*
X190861Y125594D03*
X197645Y130704D03*
X196324Y1356733D03*
X196301Y1374054D03*
X200195Y1382685D03*
X189760Y1725893D03*
X208179Y98159D03*
X203061Y125594D03*
X213790Y1381875D03*
X229516Y152076D03*
X225090Y153487D03*
X229124Y1356733D03*
X229101Y1374054D03*
X243487Y104777D03*
X246297Y124060D03*
X242297D03*
X233595Y152088D03*
X244125Y663255D03*
X232995Y1382685D03*
X247487Y104777D03*
X261297Y124060D03*
X254297D03*
X250297D03*
X260100Y153979D03*
X254756Y156819D03*
X251424Y645276D03*
X246590Y1381875D03*
X271797Y124060D03*
X268297Y127560D03*
X275500Y231017D03*
X273069Y582087D03*
X272955Y663597D03*
X262724Y1310587D03*
X262701Y1327908D03*
X266595Y1336539D03*
X273597Y1519937D03*
X289357Y116020D03*
X284154Y679517D03*
X276855Y697496D03*
X280190Y1335729D03*
X279499Y1519937D03*
X302500Y250517D03*
X297815Y582971D03*
X305685Y697838D03*
X295620Y1310559D03*
X295597Y1327880D03*
X299491Y1336511D03*
X314602Y271108D03*
X316924Y699667D03*
X309655Y717356D03*
X313086Y1335701D03*
X325617Y81260D03*
X328524Y1310502D03*
X328501Y1327823D03*
X332395Y1336454D03*
X339811Y123194D03*
X346153Y270403D03*
X349984Y699399D03*
X342710Y717329D03*
X338455Y717988D03*
X345990Y1335644D03*
X352628Y283807D03*
X357582Y555307D03*
X353582D03*
X361324Y1310702D03*
X361301Y1328023D03*
X365195Y1336654D03*
X370064Y239653D03*
X371412Y272094D03*
X371962Y534184D03*
X375704Y717480D03*
X371515Y717720D03*
X378790Y1335844D03*
X395048Y123695D03*
X382184Y468868D03*
X393376Y469214D03*
X383024Y699467D03*
X393906Y1330033D03*
X393883Y1347354D03*
X384824Y1624230D03*
X394824D03*
X389824D03*
X384824Y1661637D03*
X394824D03*
X389824D03*
X406243Y102593D03*
X399264Y123661D03*
X400632Y141242D03*
X399299Y214588D03*
X402184Y468986D03*
Y501618D03*
X408739Y699611D03*
X404771Y693155D03*
X404555Y717788D03*
X397777Y1355985D03*
X401659Y1519937D03*
X407561D03*
X402969Y1622841D03*
X399824Y1661637D03*
X405000Y1677517D03*
X411299Y206637D03*
Y214588D03*
X415984Y468909D03*
Y501541D03*
X412771Y531155D03*
X416024Y681667D03*
X423921Y1006440D03*
X411372Y1355175D03*
X417000Y1665017D03*
Y1677517D03*
X433673Y77217D03*
X429997Y160642D03*
X433997Y153642D03*
X437997D03*
X439299Y214588D03*
X429784Y468832D03*
X439500Y493517D03*
X437309Y674944D03*
X437555Y699988D03*
X435141Y1006440D03*
X438882D03*
X427661D03*
X431401D03*
X427251Y1286211D03*
X441997Y160642D03*
X451299Y214588D03*
X443500Y486517D03*
X448424Y657067D03*
X441137Y674930D03*
X450102Y1006440D03*
X442622D03*
X446362D03*
X453842D03*
X453085Y1643950D03*
X466600Y142892D03*
X457997Y160642D03*
X465997D03*
X461931Y215195D03*
X458115Y241045D03*
X469038Y300655D03*
X469881Y648554D03*
X469955Y675388D03*
X457582Y1006440D03*
X461000Y1644017D03*
X475435Y206652D03*
X484754Y223469D03*
X481024Y630567D03*
X473732Y648556D03*
X483500Y1264879D03*
X478500Y1265017D03*
X474500D03*
X498314Y115435D03*
X485997Y160642D03*
X489997D03*
X494144Y215744D03*
X487107Y285246D03*
X488538Y298720D03*
X488544Y292041D03*
X487500Y1264879D03*
X492500D03*
X496500D03*
X501500Y419517D03*
Y426517D03*
X512000Y429517D03*
X514324Y596467D03*
X502998Y614430D03*
X506964Y614438D03*
X502555Y648888D03*
X515539Y82659D03*
X522088Y204377D03*
X543131Y123347D03*
X536177Y243722D03*
X535855Y614788D03*
X537770Y1519937D03*
X543672D03*
X554196Y184773D03*
X556038Y309655D03*
X566460Y157586D03*
X574107Y294246D03*
X570216Y764529D03*
X582193Y90190D03*
Y83190D03*
X588194Y175067D03*
X575538Y307720D03*
X575567Y301185D03*
X585585Y374569D03*
X579385Y376519D03*
Y387319D03*
X585585D03*
X579385Y401250D03*
X575216Y764529D03*
X595260Y157586D03*
X602293Y206278D03*
X598294Y198278D03*
X602294D03*
X608793Y206278D03*
X608794Y198278D03*
X618705Y292822D03*
X615385Y387319D03*
Y376519D03*
Y406938D03*
X625310Y175626D03*
X626705Y292822D03*
X622705D03*
X621585Y374569D03*
Y387319D03*
X619500Y439017D03*
X626703Y1350201D03*
X630000Y1401517D03*
X635060Y143160D03*
X646231Y150068D03*
X642500Y419017D03*
X638000Y422517D03*
X643563Y1386914D03*
X647445Y1386938D03*
X635000Y1401517D03*
X637794Y1718487D03*
X653821Y84279D03*
X649500Y376517D03*
X655702Y1385440D03*
X659559Y1385382D03*
X651877Y1385407D03*
X652800Y1691317D03*
X656800D03*
X675843Y104202D03*
X666885Y405272D03*
X665832Y1527517D03*
X673113Y1729778D03*
Y1719116D03*
X680623Y108902D03*
X687453Y128185D03*
X683453D03*
X689440Y363421D03*
X690800Y376879D03*
X687500Y393379D03*
X687310Y507879D03*
X692500D03*
X679500Y521017D03*
X688500Y540379D03*
X688120Y1516543D03*
X704953Y128185D03*
X694453D03*
X700963Y128245D03*
X707545Y363338D03*
X703520Y363421D03*
X708300Y376879D03*
X704300D03*
X700300D03*
X707500Y393379D03*
X699500D03*
X695500D03*
X703500D03*
X700500Y507879D03*
X696500D03*
Y524379D03*
X700500Y540379D03*
X704500Y550379D03*
X704056Y577598D03*
X698996D03*
X708056D03*
X694996D03*
X698699Y1345887D03*
X705680Y1374742D03*
X705657Y1392063D03*
X701661Y1392085D03*
X697731Y1392055D03*
X698500Y1591017D03*
X696030Y1627794D03*
X699799Y1627710D03*
X723500Y363379D03*
X715395Y363369D03*
X712300Y376879D03*
X720300D03*
X715500Y393379D03*
X711500D03*
X720500Y550379D03*
Y540379D03*
X720787Y630848D03*
X716721Y630784D03*
X711702Y649273D03*
X709551Y1400694D03*
X723146Y1399694D03*
X710217Y1435755D03*
X723050Y1599450D03*
X717110Y1599540D03*
X715152Y1627598D03*
X729380Y75035D03*
X734380D03*
X723933Y135505D03*
X731500Y363379D03*
X727564Y376879D03*
X735500Y393379D03*
X732500Y507879D03*
X728500D03*
X736500D03*
X728500Y540379D03*
X736500D03*
X732500Y540517D03*
X738462Y1374842D03*
X738439Y1392163D03*
X732723Y1627037D03*
X736723D03*
X728723D03*
X732434Y1685190D03*
X728454Y1685021D03*
X737468Y1687220D03*
X745500Y199517D03*
X747500Y376879D03*
X743500Y393379D03*
X747500D03*
X751500D03*
X739652Y393361D03*
X744500Y507879D03*
X752500D03*
X748500D03*
X740895Y524398D03*
X748500Y524379D03*
X752500D03*
X744500D03*
X752500Y540379D03*
X742333Y1400794D03*
X740723Y1627037D03*
X752187Y1685511D03*
X741326Y1683829D03*
X760193Y100745D03*
X761000Y212517D03*
X759500Y376879D03*
Y393379D03*
X755500D03*
X764500Y507879D03*
X756500D03*
X760500D03*
X756500Y524379D03*
X760500D03*
X764500D03*
X765000Y540379D03*
X755928Y1399794D03*
X757770Y1628300D03*
X761770D03*
X754030Y1656100D03*
X767381Y1670258D03*
X754030Y1663100D03*
X762030D03*
X767368Y1662579D03*
X773766Y281339D03*
X781456Y378134D03*
X775500Y393379D03*
X771500D03*
X773000Y540379D03*
X768700Y540517D03*
X779447Y1334273D03*
X770450Y1581050D03*
X789277Y1524346D03*
X809817Y561954D03*
X807669Y1301733D03*
X812750Y1581950D03*
X819114Y117715D03*
X823114D03*
X827114D03*
X826614Y147215D03*
X824500Y508517D03*
X820500D03*
X831114Y117715D03*
X839360Y117599D03*
X840221Y184879D03*
X840220Y197879D03*
X839000Y386017D03*
X841872Y535202D03*
X844936Y90268D03*
X844221Y184879D03*
X844220Y197879D03*
X848500Y455017D03*
X852000Y486017D03*
X848762Y524505D03*
X854750Y1581950D03*
X871500Y316517D03*
X867190Y384777D03*
X871190D03*
X864065Y516053D03*
X886503Y278804D03*
X876923Y1242437D03*
X889368Y1141595D03*
X893368D03*
X895394Y1159848D03*
X896750Y1581950D03*
X916268Y272376D03*
X945263Y274673D03*
X936393Y1141595D03*
X940393D03*
X942419Y1159848D03*
X935907Y1242437D03*
X965442Y171902D03*
X981445Y179600D03*
X977195Y207940D03*
X1005699Y171360D03*
X999915Y179090D03*
X996415D03*
X1005395Y218440D03*
X1009735Y157960D03*
X1014828Y261782D03*
Y270944D03*
X1015334Y291328D03*
X1007011Y542016D03*
X1019961Y557449D03*
X1023220Y186116D03*
X1024961Y557449D03*
X1039000Y557517D03*
X1064915Y1308005D03*
X1066363Y1382567D03*
X1062405Y1382535D03*
X1064221Y1656937D03*
X1063751Y1648011D03*
X1069322Y401065D03*
X1069862Y1356714D03*
X1073733Y1382666D03*
X1069839Y1374035D03*
X1068094Y1648012D03*
X1068221Y1656937D03*
X1087328Y1381856D03*
X1094514Y1722933D03*
X1102462Y1356714D03*
X1102439Y1374035D03*
X1106333Y1382666D03*
X1108747Y1528897D03*
X1109558Y1544603D03*
X1105000Y1676517D03*
X1098514Y1715933D03*
X1119928Y1381856D03*
X1114617Y1528897D03*
X1115005Y1579568D03*
X1116000Y1665517D03*
X1120303Y1676452D03*
X1119361Y1716251D03*
X1135162Y1356714D03*
X1135139Y1374035D03*
X1139033Y1382666D03*
X1129846Y1456465D03*
X1131256Y1569044D03*
X1140117Y1665669D03*
X1152628Y1381856D03*
X1144107Y1665583D03*
X1168062Y1356714D03*
X1168039Y1374035D03*
X1180849Y461707D03*
X1178340Y469682D03*
X1171933Y1382666D03*
X1185528Y1381856D03*
X1195488Y88067D03*
X1215581Y85863D03*
X1200862Y1356714D03*
X1200839Y1374035D03*
X1204733Y1382666D03*
X1208000Y1394017D03*
X1210254Y1713953D03*
Y1706953D03*
Y1727953D03*
Y1720953D03*
X1206254Y1724803D03*
X1223455Y85863D03*
X1218328Y1381856D03*
X1238853Y1310568D03*
X1238830Y1327889D03*
X1242724Y1336520D03*
X1245000Y1427017D03*
Y1434017D03*
Y1441017D03*
X1241000D03*
X1253152Y87412D03*
Y98042D03*
X1256319Y1335710D03*
X1247000Y1403517D03*
X1256859Y1420017D03*
X1249000Y1427017D03*
Y1434017D03*
X1253000D03*
X1263472Y87381D03*
X1271749Y1310540D03*
X1271726Y1327861D03*
X1275620Y1336492D03*
X1289215Y1335682D03*
X1281470Y1552937D03*
X1287372D03*
X1296386Y545340D03*
X1299986D03*
X1296156Y555965D03*
X1304653Y1310483D03*
X1304630Y1327804D03*
X1307857Y105870D03*
X1305187Y565788D03*
X1308524Y1336435D03*
X1331930Y61462D03*
X1322119Y1335625D03*
X1343840Y61428D03*
X1337453Y1310683D03*
X1337430Y1328004D03*
X1341324Y1336635D03*
X1355750Y61428D03*
X1361976Y614610D03*
X1350261Y632598D03*
X1354597D03*
X1354919Y1335825D03*
X1367950Y61428D03*
X1370035Y1330014D03*
X1373906Y1355966D03*
X1370012Y1347335D03*
X1383507Y632931D03*
X1387297Y665498D03*
X1387501Y1355156D03*
X1394676Y647510D03*
X1407543Y1006439D03*
X1403803D03*
X1400063D03*
X1416207Y665831D03*
X1420007Y697748D03*
X1415024Y1006439D03*
X1411283D03*
X1418764D03*
X1422504D03*
X1417711Y1258883D03*
X1421211D03*
X1409532Y1552937D03*
X1415434D03*
X1415622Y1610284D03*
X1410622D03*
X1413622Y1637859D03*
X1434262Y55409D03*
X1439049Y109960D03*
X1429169Y109830D03*
X1427276Y680090D03*
X1433724Y1006439D03*
X1429984D03*
X1426244D03*
X1438532Y1275277D03*
X1448549Y117160D03*
X1443049Y109960D03*
X1448807Y698411D03*
X1452765Y717424D03*
X1449334Y1272009D03*
X1453334D03*
X1442532Y1275277D03*
X1450500Y1627017D03*
X1445500D03*
X1440500D03*
X1450500Y1617517D03*
X1442579Y1667820D03*
X1447579D03*
X1452579D03*
X1459896Y58505D03*
X1454549Y109960D03*
X1460194Y699667D03*
X1457579Y1667820D03*
X1481725Y717988D03*
X1493276Y699667D03*
X1485897Y717655D03*
X1513644Y246442D03*
X1505477Y1270905D03*
X1526076Y699667D03*
X1518697Y717655D03*
X1514807Y717988D03*
X1533454Y88238D03*
X1537454D03*
X1542697Y562104D03*
X1547827Y695547D03*
X1551827D03*
X1547607Y717988D03*
X1556178Y1262880D03*
X1558077Y1273305D03*
X1554377D03*
X1545644Y1552937D03*
X1551546D03*
X1559206Y677727D03*
X1560157Y1262880D03*
X1584597Y661946D03*
X1580597D03*
X1580737Y696048D03*
X1583177Y1262305D03*
X1587177D03*
X1575680Y1299996D03*
X1588800Y303688D03*
X1591976Y643958D03*
X1591177Y1262305D03*
X1617400Y303688D03*
X1617506Y564943D03*
X1617597Y642946D03*
X1613597D03*
X1613507Y662279D03*
X1629000Y386017D03*
Y393017D03*
X1624976Y624958D03*
X1646510Y428561D03*
X1646507Y643279D03*
X1645155Y1391337D03*
X1634327Y1406457D03*
X1662000Y218017D03*
X1651910Y230004D03*
X1652610Y397219D03*
X1661110Y428719D03*
X1653413Y1374031D03*
X1657284Y1399983D03*
X1653390Y1391352D03*
X1649197Y1391285D03*
X1653667Y1440258D03*
X1658167D03*
X1662465Y1438691D03*
X1657892Y1452377D03*
X1653614Y1452356D03*
X1650513Y1708701D03*
Y1715701D03*
Y1723851D03*
Y1730851D03*
X1673872Y428162D03*
X1670879Y1398983D03*
X1666290Y1438724D03*
X1670147Y1438666D03*
X1673706Y1560517D03*
X1675360Y1709019D03*
Y1723769D03*
X1684942Y228429D03*
X1686154Y428702D03*
X1686195Y1374131D03*
X1690066Y1400083D03*
X1686172Y1391452D03*
X1688243Y1666319D03*
X1692415Y1666257D03*
X1679816Y1666320D03*
X1685513Y1715701D03*
Y1708701D03*
X1704624Y428192D03*
X1701124D03*
X1703661Y1399083D03*
X1718608Y101101D03*
X1721418Y125184D03*
X1717418D03*
X1713312Y138239D03*
X1715044Y407062D03*
X1718931Y407054D03*
X1710408Y420462D03*
X1720845Y1673851D03*
X1710360Y1709019D03*
X1722608Y105901D03*
X1736418Y125184D03*
X1729418D03*
X1725418D03*
X1730364Y171468D03*
X1722500Y368879D03*
X1725500Y377879D03*
X1735945Y1556388D03*
X1728633Y1705207D03*
X1724633Y1712207D03*
Y1705207D03*
Y1720357D03*
Y1727357D03*
X1746918Y125184D03*
X1743418Y128684D03*
X1740688Y1531121D03*
X1737914Y1570224D03*
X1737979Y1577422D03*
X1739279Y1584495D03*
X1750380Y1710325D03*
X1749480Y1720675D03*
X1764478Y117144D03*
X1756051Y1580349D03*
X1758963Y1685982D03*
X1763463D03*
X1771688Y1556388D03*
X1773657Y1570724D03*
X1790738Y82384D03*
X1784133Y162916D03*
Y155827D03*
X1783448Y207474D03*
X1791794Y1580049D03*
X1819705Y163889D03*
G54D50*
X66229Y1542339D03*
X57370D03*
X59142D03*
X60914D03*
X62685D03*
X64457D03*
X73315D03*
X71544D03*
X69772D03*
X68000D03*
X94407Y151279D03*
X92438D03*
X90470D03*
X88501D03*
Y162303D03*
X90470D03*
X92438D03*
X94407D03*
X93113Y1542339D03*
X94885D03*
X96657D03*
X110081Y1376461D03*
X104766D03*
X108310D03*
X106538D03*
X111853D03*
X109058Y1542339D03*
X107287D03*
X105515D03*
X103743D03*
X101972D03*
X98428D03*
X100200D03*
X120711Y1376461D03*
X113625D03*
X117168D03*
X118940D03*
X115396D03*
X137366D03*
X140910D03*
X139138D03*
X153311D03*
X142681D03*
X146225D03*
X149768D03*
X144453D03*
X151540D03*
X147996D03*
X170066D03*
X186011D03*
X175381D03*
X178925D03*
X182468D03*
X173610D03*
X171838D03*
X177153D03*
X184240D03*
X180696D03*
X208281D03*
X202966D03*
X211825D03*
X215368D03*
X206510D03*
X204738D03*
X210053D03*
X213596D03*
X218911D03*
X217140D03*
X241081D03*
X235766D03*
X244625D03*
X239310D03*
X237538D03*
X242853D03*
X250345Y653656D03*
X252116D03*
X253888D03*
X255660D03*
X257431D03*
X259203D03*
X251711Y1376461D03*
X248168D03*
X249940D03*
X246396D03*
X266290Y653656D03*
X264518D03*
X262746D03*
X260975D03*
X274681Y1330315D03*
X269366D03*
X272910D03*
X271138D03*
X289206Y149291D03*
X287237D03*
X285269D03*
X283300D03*
Y160315D03*
X285269D03*
X287237D03*
X289206D03*
X283075Y687897D03*
X284846D03*
X286618D03*
X288390D03*
X290161D03*
X285311Y1330315D03*
X278225D03*
X281768D03*
X276453D03*
X283540D03*
X279996D03*
X299020Y687897D03*
X297248D03*
X295476D03*
X293705D03*
X291933D03*
X302262Y1330287D03*
X304034D03*
X315845Y708047D03*
X317616D03*
X319388D03*
X318207Y1330287D03*
X307577D03*
X311121D03*
X314664D03*
X305806D03*
X309349D03*
X316436D03*
X312892D03*
X321160Y708047D03*
X322931D03*
X331790D03*
X330018D03*
X328246D03*
X326475D03*
X324703D03*
X335166Y1330230D03*
X348905Y707779D03*
X340481Y1330230D03*
X344025D03*
X347568D03*
X338710D03*
X336938D03*
X342253D03*
X349340D03*
X345796D03*
X350676Y707779D03*
X352448D03*
X354220D03*
X355991D03*
X364850D03*
X363078D03*
X361306D03*
X359535D03*
X357763D03*
X351111Y1330230D03*
X373281Y1330430D03*
X367966D03*
X376825D03*
X371510D03*
X369738D03*
X375053D03*
X378596D03*
X381945Y707847D03*
X383716D03*
X385488D03*
X387260D03*
X389031D03*
X394346D03*
X392575D03*
X390803D03*
X383911Y1330430D03*
X380368D03*
X382140D03*
X397890Y707847D03*
X396118D03*
X405863Y1349761D03*
X400548D03*
X409407D03*
X404092D03*
X402320D03*
X407635D03*
X414945Y690047D03*
X416716D03*
X418488D03*
X420260D03*
X422031D03*
X423803D03*
X416493Y1349761D03*
X412950D03*
X414722D03*
X411178D03*
X430890Y690047D03*
X429118D03*
X427346D03*
X425575D03*
X447345Y665447D03*
X449116D03*
X450888D03*
X452660D03*
X454431D03*
X463290D03*
X461518D03*
X459746D03*
X457975D03*
X456203D03*
X479945Y638947D03*
X481716D03*
X483488D03*
X485260D03*
X487031D03*
X495890D03*
X494118D03*
X492346D03*
X490575D03*
X488803D03*
X513245Y604847D03*
X515016D03*
X516788D03*
X518560D03*
X520331D03*
X529190D03*
X527418D03*
X525646D03*
X523875D03*
X522103D03*
X613182Y219365D03*
X611213D03*
X609245D03*
X607276D03*
Y230389D03*
X609245D03*
X611213D03*
X613182D03*
X717637Y1394470D03*
X712322D03*
X721181D03*
X715866D03*
X714094D03*
X719409D03*
X722952D03*
X728267D03*
X724724D03*
X726496D03*
X750419Y1394570D03*
X745104D03*
X748648D03*
X746876D03*
X752191D03*
X761049D03*
X753963D03*
X757506D03*
X759278D03*
X755734D03*
X826467Y131386D03*
X824498D03*
X822530D03*
X820561D03*
Y142410D03*
X822530D03*
X824498D03*
X826467D03*
X850432Y208879D03*
X848463D03*
X846495D03*
X844526D03*
Y219903D03*
X846495D03*
X848463D03*
X850432D03*
X1076504Y1376442D03*
X1080048D03*
X1078276D03*
X1092449D03*
X1081819D03*
X1085363D03*
X1088906D03*
X1083591D03*
X1090678D03*
X1087134D03*
X1109104D03*
X1125049D03*
X1114419D03*
X1117963D03*
X1121506D03*
X1112648D03*
X1110876D03*
X1116191D03*
X1123278D03*
X1119734D03*
X1147119D03*
X1141804D03*
X1150663D03*
X1154206D03*
X1145348D03*
X1143576D03*
X1148891D03*
X1152434D03*
X1157749D03*
X1155978D03*
X1180019D03*
X1174704D03*
X1183563D03*
X1178248D03*
X1176476D03*
X1181791D03*
X1190649D03*
X1187106D03*
X1188878D03*
X1185334D03*
X1212819D03*
X1207504D03*
X1211048D03*
X1209276D03*
X1214591D03*
X1223449D03*
X1216363D03*
X1219906D03*
X1221678D03*
X1218134D03*
X1250810Y1330296D03*
X1245495D03*
X1254354D03*
X1257897D03*
X1249039D03*
X1247267D03*
X1252582D03*
X1259669D03*
X1256125D03*
X1261440D03*
X1282855Y401213D03*
X1280886D03*
X1278918D03*
X1276949D03*
Y412237D03*
X1278918D03*
X1280886D03*
X1282855D03*
X1283706Y1330268D03*
X1278391D03*
X1287250D03*
X1281935D03*
X1280163D03*
X1285478D03*
X1289021D03*
X1294336D03*
X1290793D03*
X1292565D03*
X1316610Y1330211D03*
X1311295D03*
X1314839D03*
X1313067D03*
X1318382D03*
X1327240D03*
X1320154D03*
X1323697D03*
X1325469D03*
X1321925D03*
X1344095Y1330411D03*
X1347639D03*
X1345867D03*
X1360897Y622990D03*
X1362668D03*
X1360040Y1330411D03*
X1349410D03*
X1352954D03*
X1356497D03*
X1351182D03*
X1358269D03*
X1354725D03*
X1364440Y622990D03*
X1366212D03*
X1367983D03*
X1376842D03*
X1375070D03*
X1373298D03*
X1371527D03*
X1369755D03*
X1376677Y1349742D03*
X1378449D03*
X1393597Y655890D03*
X1392622Y1349742D03*
X1381992D03*
X1385536D03*
X1389079D03*
X1380221D03*
X1383764D03*
X1390851D03*
X1387307D03*
X1395368Y655890D03*
X1397140D03*
X1398912D03*
X1400683D03*
X1407770D03*
X1405998D03*
X1404227D03*
X1402455D03*
X1409542D03*
X1426197Y688470D03*
X1427968D03*
X1429740D03*
X1431512D03*
X1433283D03*
X1438598D03*
X1436827D03*
X1435055D03*
X1442142D03*
X1440370D03*
X1459115Y708047D03*
X1460886D03*
X1462658D03*
X1464430D03*
X1466201D03*
X1467973D03*
X1475060D03*
X1473288D03*
X1471516D03*
X1469745D03*
X1492197Y708215D03*
X1493968D03*
X1495740D03*
X1497512D03*
X1499283D03*
X1508142D03*
X1506370D03*
X1504598D03*
X1502827D03*
X1501055D03*
X1524997Y708047D03*
X1526768D03*
X1528540D03*
X1530312D03*
X1532083D03*
X1540942D03*
X1539170D03*
X1537398D03*
X1535627D03*
X1533855D03*
X1557201Y294904D03*
X1555233D03*
X1553264D03*
Y305928D03*
X1555233D03*
X1557201D03*
X1559170Y294904D03*
Y305928D03*
X1558127Y686107D03*
X1559898D03*
X1561670D03*
X1563442D03*
X1565213D03*
X1572300D03*
X1570528D03*
X1568757D03*
X1566985D03*
X1574072D03*
X1590897Y652338D03*
X1592668D03*
X1594440D03*
X1596212D03*
X1597983D03*
X1601527D03*
X1599755D03*
X1606842D03*
X1605070D03*
X1603298D03*
X1623897Y633338D03*
X1625668D03*
X1627440D03*
X1629212D03*
X1630983D03*
X1639842D03*
X1638070D03*
X1636298D03*
X1634527D03*
X1632755D03*
X1660055Y1393759D03*
X1661827D03*
X1676000D03*
X1665370D03*
X1668914D03*
X1672457D03*
X1663599D03*
X1667142D03*
X1674229D03*
X1670685D03*
X1692026Y1680733D03*
X1690057D03*
X1686120D03*
X1688089D03*
X1686120Y1691757D03*
X1692026D03*
X1688089D03*
X1690057D03*
X1698152Y1393859D03*
X1692837D03*
X1701696D03*
X1705239D03*
X1696381D03*
X1694609D03*
X1699924D03*
X1707011D03*
X1703467D03*
X1708782D03*
X1735976Y364872D03*
X1734008D03*
X1732039D03*
Y375896D03*
X1734008D03*
X1735976D03*
X1737945Y364872D03*
Y375896D03*
X1744653Y1575375D03*
X1746425D03*
X1748197D03*
X1749968D03*
X1751740D03*
X1760598D03*
X1758827D03*
X1757055D03*
X1755283D03*
X1753512D03*
X1780396D03*
X1796341D03*
X1794570D03*
X1792798D03*
X1791026D03*
X1789255D03*
X1782168D03*
X1783940D03*
X1785711D03*
X1787483D03*
G54D107*
X195345Y1407483D03*
Y1427365D03*
X347380Y616161D03*
Y636043D03*
X356251Y1369970D03*
Y1389852D03*
X466581Y573882D03*
Y593764D03*
X1133565Y1409036D03*
Y1428918D03*
X1345073Y1391844D03*
Y1411726D03*
X1454057Y619617D03*
Y639499D03*
G54D206*
X694226Y144488D03*
Y225984D03*
G54D233*
X804455Y1345269D03*
G54D251*
X905815Y1155362D03*
X952840D03*
X1315608Y561302D03*
X1621733Y560957D03*
G54D171*
X478794Y293510D03*
X565794Y302510D03*
G54D153*
X418293Y1612725D03*
X1125516Y1646941D03*
G54D135*
X313500Y247472D03*
X309760Y256528D03*
X317240D03*
X881000Y310972D03*
X877260Y320028D03*
X884740D03*
X1638500Y386972D03*
X1634760Y396028D03*
X1642240D03*
G54D126*
X269887Y600916D03*
Y598554D03*
X280123D03*
G54D144*
X380447Y135157D03*
X370999D03*
X380447Y142637D03*
X370999Y138897D03*
Y142637D03*
X1002126Y428366D03*
Y420886D03*
X992678D03*
Y424626D03*
Y428366D03*
X1445372Y52933D03*
Y56673D03*
Y60413D03*
X1454820D03*
Y52933D03*
G54D15*
X23031Y197224D03*
Y202224D03*
Y207224D03*
Y212224D03*
X39173Y197224D03*
Y202224D03*
Y207224D03*
Y212224D03*
X105975Y197241D03*
Y202241D03*
Y207241D03*
Y212241D03*
X122117Y197241D03*
Y202241D03*
Y207241D03*
Y212241D03*
X1255315Y236594D03*
Y241594D03*
Y246594D03*
Y251594D03*
X1271457Y236594D03*
Y241594D03*
Y246594D03*
Y251594D03*
X1341535Y236594D03*
Y251594D03*
Y246594D03*
Y241594D03*
X1357677Y236594D03*
Y251594D03*
Y246594D03*
Y241594D03*
G54D60*
X79740Y1418669D03*
X72260D03*
X76000Y1427331D03*
G54D162*
X455968Y288258D03*
Y294058D03*
X543208Y297268D03*
Y303068D03*
X646176Y206895D03*
Y201095D03*
X651612Y206890D03*
Y201090D03*
X983328Y211433D03*
X988228D03*
X983328Y217233D03*
X988228D03*
X1110000Y1680900D03*
Y1675100D03*
X1115217Y1680875D03*
Y1675075D03*
X1812174Y191599D03*
Y185799D03*
X1811827Y202598D03*
Y208398D03*
X1817674Y191799D03*
Y197599D03*
G54D252*
X910741Y1641723D03*
X947553D03*
G54D117*
X270414Y64236D03*
X288918D03*
X953693Y187871D03*
X972197D03*
X1686919Y386516D03*
X1705423D03*
X1730367Y75039D03*
X1748871D03*
G54D243*
X897439Y1144562D03*
X944464D03*
X1303767Y548297D03*
X1613357Y550157D03*
G54D270*
X1211531Y128748D03*
Y133866D03*
X1217831Y131307D03*
G54D51*
X67668Y1559357D03*
X74668D03*
X125298Y1564553D03*
X118298D03*
X125348Y1557644D03*
X118348D03*
X165360Y414250D03*
X158360D03*
X185140Y413710D03*
X184959Y1559098D03*
X184933Y1565952D03*
X192140Y413710D03*
X201789Y591145D03*
Y599245D03*
X191959Y1559098D03*
X191933Y1565952D03*
X208789Y591145D03*
Y599245D03*
X253166Y67826D03*
X260166D03*
X251969Y78930D03*
X258969D03*
X359408Y274970D03*
X366408D03*
X554078Y199041D03*
X561078D03*
X673700Y1521200D03*
X666700D03*
X673633Y1536745D03*
X666633D03*
X673633Y1543599D03*
X666633D03*
X685720Y83362D03*
X692720D03*
X783673Y1355396D03*
Y1362296D03*
X781494Y1409557D03*
X774494D03*
X797969Y1357980D03*
X790673Y1355396D03*
Y1362296D03*
X804969Y1357980D03*
X855576Y234068D03*
X862576D03*
X901500Y1117787D03*
Y1110979D03*
Y1124595D03*
Y1131403D03*
X914700Y1116200D03*
Y1109200D03*
X908500Y1117787D03*
Y1110979D03*
X914700Y1123200D03*
X908500Y1124595D03*
Y1131403D03*
X914700Y1130200D03*
X921700Y1116200D03*
Y1109200D03*
Y1123200D03*
Y1130200D03*
X944500Y1116200D03*
Y1109200D03*
Y1130200D03*
Y1123200D03*
X960442Y175917D03*
X953442D03*
X958419Y1117534D03*
Y1110534D03*
X951500Y1116200D03*
Y1109200D03*
X958419Y1124534D03*
X958300Y1131403D03*
X951500Y1130200D03*
Y1123200D03*
X965419Y1117534D03*
Y1110534D03*
Y1124534D03*
X965300Y1131403D03*
X1037394Y1658146D03*
X1044394D03*
X1126250Y1606927D03*
X1122250Y1615727D03*
X1130250D03*
X1199806Y1598952D03*
X1192806D03*
X1199832Y1592098D03*
X1192832D03*
X1217193Y145739D03*
X1224193D03*
X1302077Y151217D03*
X1295077D03*
X1320014Y519675D03*
X1306766Y532113D03*
X1313766D03*
X1320014Y540375D03*
Y533475D03*
Y526575D03*
X1327014Y519675D03*
Y540375D03*
Y533475D03*
Y526575D03*
X1633139Y533130D03*
X1626139D03*
X1633139Y526230D03*
X1626139D03*
X1633139Y540030D03*
X1626139D03*
X1673258Y1411694D03*
X1674574Y1554200D03*
X1674507Y1576599D03*
Y1569745D03*
X1680258Y1411694D03*
X1681574Y1554200D03*
X1681507Y1576599D03*
Y1569745D03*
X1730096Y63051D03*
X1737096D03*
X1750642Y93075D03*
X1752067Y299637D03*
X1745067D03*
X1757642Y93075D03*
X1757279Y1597550D03*
X1764279D03*
X1757279Y1604950D03*
X1764279D03*
X1808013Y1598316D03*
X1801013D03*
X1808013Y1605816D03*
X1801013D03*
G54D42*
X61057Y64434D03*
Y62334D03*
X64657Y64434D03*
Y62334D03*
X72057Y70434D03*
Y68334D03*
X75657Y70434D03*
Y68334D03*
X86657Y64434D03*
Y62334D03*
X94057Y70434D03*
Y68334D03*
X83057Y64434D03*
Y62334D03*
X105057Y64434D03*
Y62334D03*
X108657Y64434D03*
Y62334D03*
X97657Y70434D03*
Y68334D03*
X127057Y64434D03*
Y62334D03*
X119657Y70434D03*
Y68334D03*
X116057Y70434D03*
Y68334D03*
X138057Y70434D03*
Y68334D03*
X130657Y64434D03*
Y62334D03*
X141657Y70434D03*
Y68334D03*
X152657Y64434D03*
Y62334D03*
X149057Y64434D03*
Y62334D03*
X164861Y70434D03*
Y68334D03*
X161261Y70434D03*
Y68334D03*
X169251Y1467595D03*
Y1469695D03*
X171433Y1521331D03*
Y1526631D03*
Y1528731D03*
Y1523431D03*
X159000Y1535950D03*
Y1532650D03*
Y1530550D03*
Y1538050D03*
Y1543450D03*
Y1541350D03*
X183261Y70434D03*
Y68334D03*
X175861Y64434D03*
Y62334D03*
X172261Y64434D03*
Y62334D03*
X175951Y1457895D03*
Y1459995D03*
X179551Y1457895D03*
Y1459995D03*
X172851Y1467595D03*
Y1469695D03*
X194261Y64434D03*
Y62334D03*
X197861Y64434D03*
Y62334D03*
X186861Y70434D03*
Y68334D03*
X189351Y1477295D03*
X192951D03*
X199651Y1467595D03*
Y1469695D03*
X196051Y1467595D03*
Y1469695D03*
X189351Y1479395D03*
X192951D03*
X200126Y1607286D03*
Y1609386D03*
X188066Y1607286D03*
Y1609386D03*
X191666Y1607286D03*
Y1609386D03*
X205395Y70434D03*
Y68334D03*
X216395Y64434D03*
Y62334D03*
X208995Y70434D03*
Y68334D03*
X206351Y1457895D03*
Y1459995D03*
X202751Y1457895D03*
Y1459995D03*
X216151Y1477295D03*
Y1479395D03*
X212186Y1607286D03*
Y1609386D03*
X215786Y1607286D03*
Y1609386D03*
X203726Y1607286D03*
Y1609386D03*
X230995Y70434D03*
Y68334D03*
X227395Y70434D03*
Y68334D03*
X219995Y64434D03*
Y62334D03*
X229551Y1457895D03*
Y1459995D03*
X219751Y1477295D03*
X222851Y1467595D03*
Y1469695D03*
X226451Y1467595D03*
Y1469695D03*
X219751Y1479395D03*
X224246Y1607286D03*
Y1609386D03*
X227846Y1607286D03*
Y1609386D03*
X233151Y1457895D03*
Y1459995D03*
X242951Y1477295D03*
Y1479395D03*
X236306Y1607286D03*
Y1609386D03*
X239906Y1607286D03*
Y1609386D03*
X256351Y1457895D03*
Y1459995D03*
X259951Y1457895D03*
Y1459995D03*
X249651Y1467595D03*
Y1469695D03*
X246551Y1477295D03*
X253251Y1467595D03*
Y1469695D03*
X246551Y1479395D03*
X254470Y1555340D03*
Y1553240D03*
X260426Y1607286D03*
Y1609386D03*
X248366Y1607286D03*
Y1609386D03*
X251966Y1607286D03*
Y1609386D03*
X273351Y1457895D03*
Y1459995D03*
X269751Y1457895D03*
Y1459995D03*
X271580Y1552250D03*
X268380Y1551550D03*
X271580Y1554350D03*
X261530Y1553220D03*
Y1555320D03*
X268380Y1558650D03*
Y1556550D03*
Y1553650D03*
X276086Y1607286D03*
Y1609386D03*
X272486Y1607286D03*
Y1609386D03*
X264026Y1607286D03*
Y1609386D03*
X283000Y1516750D03*
Y1518850D03*
X286200Y1516750D03*
Y1518850D03*
X283000Y1521750D03*
X286200D03*
X283000Y1523850D03*
X286200D03*
X284546Y1607286D03*
Y1609386D03*
X288146Y1607286D03*
Y1609386D03*
X304013Y1457895D03*
Y1459995D03*
X297313Y1467595D03*
Y1469695D03*
X300913Y1467595D03*
Y1469695D03*
X299495Y1521331D03*
Y1526631D03*
Y1528731D03*
Y1523431D03*
X303999Y1550788D03*
X300199Y1553688D03*
Y1555788D03*
X303999Y1552888D03*
Y1557888D03*
Y1555788D03*
X296606Y1607286D03*
Y1609386D03*
X300206Y1607286D03*
Y1609386D03*
X307613Y1457895D03*
Y1459995D03*
X317413Y1477295D03*
Y1479395D03*
X307199Y1550788D03*
X311476Y1557039D03*
Y1554939D03*
Y1562039D03*
Y1559939D03*
X307199Y1552888D03*
Y1557888D03*
Y1555788D03*
X320726Y1607286D03*
Y1609386D03*
X308666Y1607286D03*
Y1609386D03*
X312266Y1607286D03*
Y1609386D03*
X330813Y1457895D03*
Y1459995D03*
X334413Y1457895D03*
Y1459995D03*
X324113Y1467595D03*
Y1469695D03*
X321013Y1477295D03*
X327713Y1467595D03*
Y1469695D03*
X321013Y1479395D03*
X332786Y1607286D03*
Y1609386D03*
X324326Y1607286D03*
Y1609386D03*
X347813Y1477295D03*
X344213D03*
X347813Y1479395D03*
X344213D03*
X344846Y1607286D03*
Y1609386D03*
X348446Y1607286D03*
Y1609386D03*
X336386Y1607286D03*
Y1609386D03*
X361213Y1457895D03*
Y1459995D03*
X357613Y1457895D03*
Y1459995D03*
X350913Y1467595D03*
Y1469695D03*
X354513Y1467595D03*
Y1469695D03*
X356906Y1607286D03*
Y1609386D03*
X360506Y1607286D03*
Y1609386D03*
X377713Y1467595D03*
Y1469695D03*
X374613Y1477295D03*
X371013D03*
X374613Y1479395D03*
X371013D03*
X368966Y1607286D03*
Y1609386D03*
X372566Y1607286D03*
Y1609386D03*
X388013Y1457895D03*
Y1459995D03*
X384413Y1457895D03*
Y1459995D03*
X381313Y1467595D03*
Y1469695D03*
X390082Y1551550D03*
Y1553650D03*
Y1558650D03*
Y1556550D03*
X395009Y1587339D03*
Y1585239D03*
X384457Y1593936D03*
Y1591836D03*
X406243Y112951D03*
Y110851D03*
Y116351D03*
Y118451D03*
X409443Y126201D03*
Y124101D03*
Y129601D03*
Y131701D03*
X401413Y1457895D03*
Y1459995D03*
X397813Y1457895D03*
Y1459995D03*
X399642Y1551550D03*
X396442D03*
X404200Y1560750D03*
Y1562850D03*
X407600Y1560750D03*
Y1562850D03*
X399642Y1553650D03*
X396442Y1558650D03*
Y1556550D03*
Y1553650D03*
X402983Y1552879D03*
Y1554979D03*
X406086Y1552840D03*
Y1554940D03*
X411062Y1521750D03*
X414262D03*
X411062Y1516750D03*
Y1518850D03*
X414262Y1516750D03*
Y1518850D03*
X411062Y1523850D03*
X414262D03*
X411320Y1555250D03*
Y1553150D03*
X440124Y1457895D03*
Y1459995D03*
X433424Y1467595D03*
Y1469695D03*
X437024Y1467595D03*
Y1469695D03*
X435606Y1521331D03*
Y1526631D03*
Y1528731D03*
Y1523431D03*
X435513Y1531694D03*
Y1533794D03*
X426600Y1562070D03*
Y1564170D03*
X430000Y1562070D03*
Y1564170D03*
X429963Y1557147D03*
Y1559247D03*
X426850Y1557096D03*
Y1559196D03*
X443724Y1457895D03*
Y1459995D03*
X453524Y1477295D03*
Y1479395D03*
X443810Y1550788D03*
X440610D03*
X449597Y1557039D03*
Y1554939D03*
X443810Y1552888D03*
X446240Y1557908D03*
Y1555808D03*
X440610Y1552888D03*
X443040Y1557908D03*
Y1555808D03*
X450749Y1571104D03*
Y1573204D03*
X446218Y1590517D03*
Y1588417D03*
X452239Y1607286D03*
Y1609386D03*
X466924Y1457895D03*
Y1459995D03*
X463824Y1467595D03*
Y1469695D03*
X460224Y1467595D03*
Y1469695D03*
X457124Y1477295D03*
Y1479395D03*
X457317Y1557509D03*
Y1555409D03*
X464299Y1607286D03*
Y1609386D03*
X467899Y1607286D03*
Y1609386D03*
X455839Y1607286D03*
Y1609386D03*
X470524Y1457895D03*
Y1459995D03*
X483924Y1477295D03*
X480324D03*
X483924Y1479395D03*
X480324D03*
X476359Y1607286D03*
Y1609386D03*
X479959Y1607286D03*
Y1609386D03*
X493724Y1457895D03*
Y1459995D03*
X497324Y1457895D03*
Y1459995D03*
X487024Y1467595D03*
Y1469695D03*
X490624Y1467595D03*
Y1469695D03*
X488419Y1607286D03*
Y1609386D03*
X492019Y1607286D03*
Y1609386D03*
X513770Y105220D03*
Y107320D03*
D03*
Y109420D03*
X513824Y1467595D03*
Y1469695D03*
X510724Y1477295D03*
X507124D03*
X510724Y1479395D03*
X507124D03*
X512539Y1607286D03*
Y1609386D03*
X504079Y1607286D03*
Y1609386D03*
X500479Y1607286D03*
Y1609386D03*
X518270Y105220D03*
Y107320D03*
D03*
Y109420D03*
X520524Y1457895D03*
Y1459995D03*
X524124Y1457895D03*
Y1459995D03*
X517424Y1467595D03*
Y1469695D03*
X528470Y1551500D03*
X526193Y1558650D03*
Y1556550D03*
X528470Y1553600D03*
X528199Y1607286D03*
Y1609386D03*
X524599Y1607286D03*
Y1609386D03*
X516139Y1607286D03*
Y1609386D03*
X532920Y115280D03*
Y113180D03*
X537420Y115280D03*
Y113180D03*
Y111080D03*
Y113180D03*
X532920Y111080D03*
Y113180D03*
X537524Y1457895D03*
Y1459995D03*
X533924Y1457895D03*
Y1459995D03*
X544100Y1531540D03*
Y1533640D03*
X531580Y1551520D03*
X532553Y1558650D03*
Y1556550D03*
X531580Y1553620D03*
X540259Y1607286D03*
Y1609386D03*
X536659Y1607286D03*
Y1609386D03*
X547173Y1521750D03*
Y1516750D03*
Y1518850D03*
X550373Y1521750D03*
Y1516750D03*
Y1518850D03*
X547173Y1523850D03*
X550373D03*
X552319Y1607286D03*
Y1609386D03*
X548719Y1607286D03*
Y1609386D03*
X571786Y1457895D03*
Y1459995D03*
X568186Y1457895D03*
Y1459995D03*
X561486Y1467595D03*
Y1469695D03*
X565086Y1467595D03*
Y1469695D03*
X563668Y1521331D03*
Y1526631D03*
Y1528731D03*
Y1523431D03*
X571372Y1550788D03*
X568172D03*
X571372Y1552888D03*
Y1557888D03*
Y1555788D03*
X564372Y1553688D03*
Y1555788D03*
X568172Y1552888D03*
Y1557888D03*
Y1555788D03*
X572839Y1607286D03*
Y1609386D03*
X564379Y1607286D03*
Y1609386D03*
X560779Y1607286D03*
Y1609386D03*
X588286Y1467595D03*
Y1469695D03*
X585186Y1477295D03*
X581586D03*
X585186Y1479395D03*
X581586D03*
X575649Y1557039D03*
Y1554939D03*
Y1562039D03*
Y1559939D03*
X588499Y1607286D03*
Y1609386D03*
X584899Y1607286D03*
Y1609386D03*
X576439Y1607286D03*
Y1609386D03*
X594986Y1457895D03*
Y1459995D03*
X598586Y1457895D03*
Y1459995D03*
X591886Y1467595D03*
Y1469695D03*
X600559Y1607286D03*
Y1609386D03*
X596959Y1607286D03*
Y1609386D03*
X608386Y1477295D03*
X611986D03*
X618686Y1467595D03*
Y1469695D03*
X615086Y1467595D03*
Y1469695D03*
X608386Y1479395D03*
X611986D03*
X612619Y1607286D03*
Y1609386D03*
X609019Y1607286D03*
Y1609386D03*
X630147Y77961D03*
Y80061D03*
X633293Y77961D03*
Y80061D03*
X625386Y1457895D03*
Y1459995D03*
X621786Y1457895D03*
Y1459995D03*
X633139Y1607286D03*
Y1609386D03*
X624679Y1607286D03*
Y1609386D03*
X621079Y1607286D03*
Y1609386D03*
X648586Y1457895D03*
Y1459995D03*
X638786Y1477295D03*
X635186D03*
X645486Y1467595D03*
Y1469695D03*
X641886Y1467595D03*
Y1469695D03*
X638786Y1479395D03*
X635186D03*
X636739Y1607286D03*
Y1609386D03*
X639800Y1648750D03*
Y1650850D03*
X644549Y1648750D03*
Y1650850D03*
X661986Y1457895D03*
Y1459995D03*
X652186Y1457895D03*
Y1459995D03*
X660615Y1551550D03*
X654255D03*
X660615Y1558650D03*
Y1556550D03*
Y1553650D03*
X654255Y1558650D03*
Y1556550D03*
Y1553650D03*
X663439Y1640404D03*
X663003Y1649150D03*
Y1651250D03*
X663439Y1642504D03*
X665586Y1457895D03*
Y1459995D03*
X668206Y1505139D03*
Y1503039D03*
X663815Y1551550D03*
Y1553650D03*
X666729Y1640404D03*
X667985Y1649014D03*
Y1651114D03*
X666729Y1642504D03*
X1138331Y1565295D03*
X1137320Y1554012D03*
Y1556112D03*
X1138480Y1574096D03*
Y1571996D03*
X1138331Y1567395D03*
X1152186Y1565424D03*
X1146689Y1568275D03*
Y1570375D03*
X1142959Y1568294D03*
Y1570394D03*
X1152186Y1567524D03*
X1166873Y1565650D03*
Y1563550D03*
Y1576450D03*
Y1574350D03*
Y1568950D03*
Y1571050D03*
X1162615Y1591163D03*
Y1593263D03*
X1163688Y1661052D03*
Y1663152D03*
X1159688Y1661052D03*
Y1663152D03*
X1183824Y1490895D03*
X1177124Y1500595D03*
Y1502695D03*
X1180724Y1500595D03*
Y1502695D03*
X1183824Y1492995D03*
X1179306Y1559631D03*
Y1561731D03*
Y1556431D03*
Y1554331D03*
X1187424Y1490895D03*
Y1492995D03*
X1197224Y1510295D03*
Y1512395D03*
X1199539Y1640286D03*
X1195939D03*
X1199539Y1642386D03*
X1195939D03*
X1190334Y1666276D03*
Y1664176D03*
X1185676Y1692980D03*
Y1695080D03*
X1210624Y1490895D03*
X1214224D03*
X1203924Y1500595D03*
Y1502695D03*
X1210624Y1492995D03*
X1214224D03*
X1207524Y1500595D03*
Y1502695D03*
X1200824Y1510295D03*
Y1512395D03*
X1211599Y1640286D03*
X1207999D03*
X1211599Y1642386D03*
X1207999D03*
X1224024Y1510295D03*
Y1512395D03*
X1227624Y1510295D03*
Y1512395D03*
X1223659Y1640286D03*
X1220059D03*
X1223659Y1642386D03*
X1220059D03*
X1241024Y1490895D03*
X1237424D03*
X1241024Y1492995D03*
X1237424D03*
X1230724Y1500595D03*
Y1502695D03*
X1234324Y1500595D03*
Y1502695D03*
X1244179Y1640286D03*
X1235719D03*
X1232119D03*
X1244179Y1642386D03*
X1235719D03*
X1232119D03*
X1257524Y1500595D03*
Y1502695D03*
X1250824Y1510295D03*
Y1512395D03*
X1254424Y1510295D03*
Y1512395D03*
X1259839Y1640286D03*
X1256239D03*
X1247779D03*
X1259839Y1642386D03*
X1256239D03*
X1247779D03*
X1264224Y1490895D03*
X1267824D03*
X1264224Y1492995D03*
X1261124Y1500595D03*
Y1502695D03*
X1267824Y1492995D03*
X1262253Y1588300D03*
Y1586200D03*
X1269153Y1586410D03*
Y1588510D03*
X1271899Y1640286D03*
X1268299D03*
X1271899Y1642386D03*
X1268299D03*
X1277624Y1490895D03*
X1281224D03*
X1277624Y1492995D03*
X1281224D03*
X1276253Y1591650D03*
Y1589550D03*
Y1586650D03*
Y1584550D03*
X1279453Y1587350D03*
Y1585250D03*
X1283959Y1640286D03*
X1280359D03*
X1283959Y1642386D03*
X1280359D03*
X1290873Y1549750D03*
Y1551850D03*
X1294073Y1549750D03*
Y1551850D03*
X1290873Y1554750D03*
Y1556850D03*
X1294073Y1554750D03*
Y1556850D03*
X1304479Y1640286D03*
X1296019D03*
X1292419D03*
X1304479Y1642386D03*
X1296019D03*
X1292419D03*
X1311886Y1490895D03*
X1315486D03*
X1311886Y1492995D03*
X1305186Y1500595D03*
Y1502695D03*
X1308786Y1500595D03*
Y1502695D03*
X1315486Y1492995D03*
X1307368Y1559631D03*
Y1561731D03*
Y1556431D03*
Y1554331D03*
X1319349Y1590039D03*
Y1587939D03*
Y1595039D03*
Y1592939D03*
X1315072Y1585888D03*
Y1583788D03*
Y1590888D03*
Y1588788D03*
X1308072Y1586688D03*
Y1588788D03*
X1311872Y1585888D03*
Y1583788D03*
Y1590888D03*
Y1588788D03*
X1316539Y1640286D03*
X1308079D03*
X1316539Y1642386D03*
X1308079D03*
X1331986Y1500595D03*
Y1502695D03*
X1325286Y1510295D03*
Y1512395D03*
X1328886Y1510295D03*
Y1512395D03*
X1332199Y1640286D03*
X1328599D03*
X1320139D03*
X1332199Y1642386D03*
X1328599D03*
X1320139D03*
X1342286Y1490895D03*
X1338686D03*
X1335586Y1500595D03*
Y1502695D03*
X1342286Y1492995D03*
X1338686D03*
X1344259Y1640286D03*
X1340659D03*
X1344259Y1642386D03*
X1340659D03*
X1358786Y1500595D03*
Y1502695D03*
X1362386Y1500595D03*
Y1502695D03*
X1355686Y1510295D03*
Y1512395D03*
X1352086Y1510295D03*
Y1512395D03*
X1356319Y1640286D03*
X1352719D03*
X1356319Y1642386D03*
X1352719D03*
X1369086Y1490895D03*
X1365486D03*
X1369086Y1492995D03*
X1365486D03*
X1378886Y1510295D03*
Y1512395D03*
X1376839Y1640286D03*
X1368379D03*
X1364779D03*
X1376839Y1642386D03*
X1368379D03*
X1364779D03*
X1392286Y1490895D03*
X1385586Y1500595D03*
Y1502695D03*
X1392286Y1492995D03*
X1389186Y1500595D03*
Y1502695D03*
X1382486Y1510295D03*
Y1512395D03*
X1383800Y1604750D03*
Y1606850D03*
X1387000Y1604750D03*
Y1606850D03*
X1390200Y1604750D03*
Y1606850D03*
X1393400Y1604750D03*
Y1606850D03*
X1380439Y1640286D03*
Y1642386D03*
X1405686Y1490895D03*
X1395886D03*
X1405686Y1492995D03*
X1395886D03*
X1404315Y1591650D03*
Y1589550D03*
Y1586650D03*
Y1584550D03*
X1397955Y1591650D03*
Y1589550D03*
X1407515Y1586650D03*
Y1584550D03*
X1397955Y1586650D03*
Y1584550D03*
X1409286Y1490895D03*
Y1492995D03*
X1418935Y1549750D03*
Y1551850D03*
X1422135Y1549750D03*
Y1551850D03*
X1418935Y1554750D03*
Y1556850D03*
X1422135Y1554750D03*
Y1556850D03*
X1451598Y1490895D03*
X1447998D03*
X1441298Y1500595D03*
Y1502695D03*
X1444898Y1500595D03*
Y1502695D03*
X1451598Y1492995D03*
X1447998D03*
X1443480Y1559631D03*
Y1561731D03*
Y1556431D03*
Y1554331D03*
X1451184Y1585888D03*
Y1583788D03*
Y1590888D03*
Y1588788D03*
X1444184Y1586688D03*
Y1588788D03*
X1447984Y1585888D03*
Y1583788D03*
Y1590888D03*
Y1588788D03*
X1468098Y1500595D03*
Y1502695D03*
X1464998Y1510295D03*
Y1512395D03*
X1461398Y1510295D03*
Y1512395D03*
X1455461Y1590039D03*
Y1587939D03*
Y1595039D03*
Y1592939D03*
X1459713Y1631377D03*
Y1633477D03*
X1463313Y1631377D03*
Y1633477D03*
X1465500Y1668450D03*
Y1670550D03*
X1478398Y1490895D03*
X1474798D03*
X1478398Y1492995D03*
X1474798D03*
X1471698Y1500595D03*
Y1502695D03*
X1475773Y1640286D03*
X1472173D03*
X1475773Y1642386D03*
X1472173D03*
X1481000Y1684050D03*
Y1681950D03*
X1494898Y1500595D03*
Y1502695D03*
X1498498Y1500595D03*
Y1502695D03*
X1491798Y1510295D03*
Y1512395D03*
X1488198Y1510295D03*
Y1512395D03*
X1496293Y1640286D03*
X1487833D03*
X1484233D03*
X1496293Y1642386D03*
X1487833D03*
X1484233D03*
X1505198Y1490895D03*
X1501598D03*
X1505198Y1492995D03*
X1501598D03*
X1511953Y1640286D03*
X1508353D03*
X1499893D03*
X1511953Y1642386D03*
X1508353D03*
X1499893D03*
X1528398Y1490895D03*
Y1492995D03*
X1521698Y1500595D03*
Y1502695D03*
X1525298Y1500595D03*
Y1502695D03*
X1518598Y1510295D03*
Y1512395D03*
X1514998Y1510295D03*
Y1512395D03*
X1524013Y1640286D03*
X1520413D03*
X1524013Y1642386D03*
X1520413D03*
X1539062Y64437D03*
Y62337D03*
X1535462Y64437D03*
Y62337D03*
X1541798Y1490895D03*
X1531998D03*
X1541798Y1492995D03*
X1531998D03*
X1540427Y1591650D03*
Y1589550D03*
Y1586650D03*
Y1584550D03*
X1534067Y1591650D03*
Y1589550D03*
Y1586650D03*
Y1584550D03*
X1536073Y1640286D03*
X1532473D03*
X1536073Y1642386D03*
X1532473D03*
X1550062Y70437D03*
Y68337D03*
X1557462Y64437D03*
Y62337D03*
X1546462Y70437D03*
Y68337D03*
X1545398Y1490895D03*
Y1492995D03*
X1555047Y1549750D03*
Y1551850D03*
X1558247Y1549750D03*
Y1551850D03*
X1555047Y1554750D03*
Y1556850D03*
X1558247Y1554750D03*
Y1556850D03*
X1543627Y1587350D03*
Y1585250D03*
X1556593Y1640286D03*
X1548133D03*
X1544533D03*
X1556593Y1642386D03*
X1548133D03*
X1544533D03*
X1568462Y70437D03*
Y68337D03*
X1572062Y70437D03*
Y68337D03*
X1561062Y64437D03*
Y62337D03*
X1569360Y1500595D03*
Y1502695D03*
X1572960Y1500595D03*
Y1502695D03*
X1571542Y1559631D03*
Y1561731D03*
Y1556431D03*
Y1554331D03*
X1572246Y1586688D03*
Y1588788D03*
X1572253Y1640286D03*
X1568653D03*
X1560193D03*
X1572253Y1642386D03*
X1568653D03*
X1560193D03*
X1583062Y64437D03*
Y62337D03*
X1579462Y64437D03*
Y62337D03*
X1579660Y1490895D03*
X1576060D03*
X1579660Y1492995D03*
X1576060D03*
X1583523Y1590039D03*
Y1587939D03*
Y1595039D03*
Y1592939D03*
X1579246Y1585888D03*
Y1583788D03*
Y1590888D03*
Y1588788D03*
X1576046Y1585888D03*
Y1583788D03*
Y1590888D03*
Y1588788D03*
X1584313Y1640286D03*
X1580713D03*
X1584313Y1642386D03*
X1580713D03*
X1590462Y70437D03*
Y68337D03*
X1601462Y64437D03*
Y62337D03*
X1594062Y70437D03*
Y68337D03*
X1602860Y1490895D03*
Y1492995D03*
X1596160Y1500595D03*
Y1502695D03*
X1599760Y1500595D03*
Y1502695D03*
X1593060Y1510295D03*
Y1512395D03*
X1589460Y1510295D03*
Y1512395D03*
X1596373Y1640286D03*
X1592773D03*
X1596373Y1642386D03*
X1592773D03*
X1616062Y70437D03*
Y68337D03*
X1605062Y64437D03*
Y62337D03*
X1612462Y70437D03*
Y68337D03*
X1606460Y1490895D03*
Y1492995D03*
X1616260Y1510295D03*
Y1512395D03*
X1616893Y1640286D03*
X1608433D03*
X1604833D03*
X1616893Y1642386D03*
X1608433D03*
X1604833D03*
X1623462Y64437D03*
Y62337D03*
X1627062Y64437D03*
Y62337D03*
X1629660Y1490895D03*
Y1492995D03*
X1622960Y1500595D03*
Y1502695D03*
X1626560Y1500595D03*
Y1502695D03*
X1619860Y1510295D03*
Y1512395D03*
X1632553Y1640286D03*
X1628953D03*
X1620493D03*
X1632553Y1642386D03*
X1628953D03*
X1620493D03*
X1639266Y70437D03*
Y68337D03*
X1635666Y70437D03*
Y68337D03*
X1646666Y64437D03*
Y62337D03*
X1633260Y1490895D03*
Y1492995D03*
X1646660Y1510295D03*
Y1512395D03*
X1643060Y1510295D03*
Y1512395D03*
X1644613Y1640286D03*
X1641013D03*
X1644613Y1642386D03*
X1641013D03*
X1650266Y64437D03*
Y62337D03*
X1661266Y70437D03*
Y68337D03*
X1657666Y70437D03*
Y68337D03*
X1660060Y1490895D03*
X1656460D03*
X1649760Y1500595D03*
Y1502695D03*
X1653360Y1500595D03*
Y1502695D03*
X1660060Y1492995D03*
X1656460D03*
X1662129Y1591650D03*
Y1589550D03*
Y1586650D03*
Y1584550D03*
X1651146Y1667366D03*
Y1669466D03*
X1656136Y1667236D03*
Y1669336D03*
X1668666Y64437D03*
Y62337D03*
X1672266Y64437D03*
Y62337D03*
X1669860Y1490895D03*
X1673460D03*
X1669860Y1492995D03*
X1673460D03*
X1676345Y1535704D03*
Y1533604D03*
X1668489Y1591650D03*
Y1589550D03*
Y1586650D03*
Y1584550D03*
X1671689Y1586650D03*
Y1584550D03*
X1671400Y1665250D03*
Y1667350D03*
X1674600Y1658950D03*
Y1661050D03*
X1671400Y1658950D03*
Y1661050D03*
X1679800Y70437D03*
Y68337D03*
X1690800Y64437D03*
Y62337D03*
X1683400Y70437D03*
Y68337D03*
X1690650Y1579742D03*
Y1577642D03*
X1681000Y1658950D03*
Y1661050D03*
X1677800Y1658950D03*
Y1661050D03*
X1701800Y70437D03*
Y68337D03*
X1694400Y64437D03*
Y62337D03*
X1705400Y70437D03*
Y68337D03*
X1693850Y1579742D03*
Y1577642D03*
G54D108*
X191038Y1572954D03*
Y1579954D03*
X197853Y1579110D03*
Y1586110D03*
X204768Y1579134D03*
Y1586134D03*
X289239Y598826D03*
Y605826D03*
X292747Y1578722D03*
Y1585722D03*
X296139Y598826D03*
X303039D03*
X296139Y605826D03*
X303039D03*
X299938Y1578884D03*
Y1585884D03*
X309939Y598826D03*
X317961Y598861D03*
X309939Y605826D03*
X317961Y605861D03*
X352618Y271310D03*
Y264310D03*
X392153Y209695D03*
Y216695D03*
X463751Y299601D03*
X456871Y299661D03*
X463751Y306601D03*
X456871Y306661D03*
X543871Y315661D03*
Y308661D03*
X550751Y315601D03*
Y308601D03*
X552400Y1578652D03*
X559348Y1578724D03*
X552400Y1585652D03*
X559348Y1585724D03*
X682200Y1521300D03*
Y1514300D03*
X773456Y253292D03*
Y260292D03*
X958452Y162103D03*
Y169103D03*
X969390Y209089D03*
Y216089D03*
X1198911Y1605954D03*
Y1612954D03*
X1205758Y1612274D03*
X1212608D03*
X1205758Y1619274D03*
X1212608D03*
X1295960Y1611652D03*
X1302908Y1611664D03*
X1295960Y1618652D03*
X1302908Y1618664D03*
X1312506Y94027D03*
Y101027D03*
X1567175Y571888D03*
Y578888D03*
X1560074Y1611242D03*
X1566978Y1611364D03*
X1560074Y1618242D03*
X1566978Y1618364D03*
X1597499Y558988D03*
Y565988D03*
X1590399Y558988D03*
Y565988D03*
X1667570Y414332D03*
Y421332D03*
X1679850Y435172D03*
Y428172D03*
X1690074Y1547300D03*
Y1554300D03*
X1750788Y183596D03*
Y190596D03*
X1749833Y205902D03*
Y212902D03*
X1764848Y183533D03*
Y190533D03*
X1757848Y183533D03*
Y190533D03*
X1763983Y205965D03*
X1756923Y205902D03*
X1763983Y212965D03*
X1756923Y212902D03*
X1765070Y255527D03*
X1757970Y255427D03*
X1765070Y262527D03*
X1757970Y262427D03*
X1771848Y183533D03*
Y190533D03*
X1770848Y211565D03*
Y204565D03*
X1777848Y211565D03*
Y204565D03*
G54D261*
X1029035Y455244D03*
Y457803D03*
Y460362D03*
Y462921D03*
Y465480D03*
Y468039D03*
Y470599D03*
Y473158D03*
Y475717D03*
Y478276D03*
Y480835D03*
Y483394D03*
X1051083Y462921D03*
Y460362D03*
Y457803D03*
Y455244D03*
Y478276D03*
Y475717D03*
Y473158D03*
Y470599D03*
Y468039D03*
Y465480D03*
Y483394D03*
Y480835D03*
X1118614Y455244D03*
Y457803D03*
Y460362D03*
Y462921D03*
Y465480D03*
Y468039D03*
Y470599D03*
Y473158D03*
Y475717D03*
Y478276D03*
Y480835D03*
Y483394D03*
X1140662Y462921D03*
Y460362D03*
Y457803D03*
Y455244D03*
Y478276D03*
Y475717D03*
Y473158D03*
Y470599D03*
Y468039D03*
Y465480D03*
Y483394D03*
Y480835D03*
G54D225*
X778687Y1573504D03*
Y1591222D03*
X792467Y1573504D03*
Y1591222D03*
X820687Y1573504D03*
Y1591222D03*
X834467Y1573504D03*
Y1591222D03*
X862687Y1573504D03*
Y1591222D03*
X876467Y1573504D03*
Y1591222D03*
X904687Y1573504D03*
Y1591222D03*
X918467Y1573504D03*
Y1591222D03*
G54D33*
X53333Y527713D03*
G54D24*
X36882Y282916D03*
Y277798D03*
X35017Y288500D03*
X36882Y312916D03*
Y307798D03*
X31329Y517025D03*
X31613Y1497914D03*
Y1502214D03*
X35444Y1668587D03*
Y1663587D03*
X51017Y303500D03*
X44017D03*
X38150Y1622896D03*
Y1626896D03*
X59742Y268223D03*
X59872Y280357D03*
Y276357D03*
Y272357D03*
X64517Y290000D03*
X59872Y310357D03*
X65625Y423746D03*
X61713Y1552869D03*
X82118Y140950D03*
X74271Y157191D03*
Y161191D03*
Y165191D03*
X81891Y386502D03*
X81908Y376026D03*
X72150Y521613D03*
Y525513D03*
Y543213D03*
Y539313D03*
X78713Y1549369D03*
X87072Y1307499D03*
X87092Y1311619D03*
X96017Y1412500D03*
Y1408000D03*
Y1417000D03*
Y1421500D03*
Y1444500D03*
X87017Y1440000D03*
Y1444500D03*
X96017Y1448500D03*
X87017D03*
X95528Y1552796D03*
X84000Y1663138D03*
X83959Y1667127D03*
X85437Y1698511D03*
Y1702511D03*
X85274Y1724331D03*
Y1720331D03*
X101771Y153691D03*
Y158191D03*
X105982Y1385562D03*
X107017Y1414500D03*
X104610Y1597797D03*
X112870Y1670313D03*
Y1674313D03*
X114517Y1712450D03*
X141509Y526997D03*
X134994Y679290D03*
Y675290D03*
X127434Y1382305D03*
X138582Y1385562D03*
X129585Y1709346D03*
X136835Y1709166D03*
X139784Y1718241D03*
X145017Y1433500D03*
Y1429500D03*
Y1437500D03*
X149870Y1670087D03*
X143870Y1682587D03*
X168377Y400560D03*
X160134Y1382305D03*
X171282Y1385562D03*
X172017Y1715000D03*
X162832Y1726500D03*
X172017Y1721000D03*
X174617Y412350D03*
X192937Y144962D03*
X194017Y149000D03*
X194517Y156500D03*
X193034Y1382305D03*
X204182Y1385562D03*
X210590Y1419187D03*
X206017Y1707000D03*
X206332Y1723000D03*
X220997Y120662D03*
Y124662D03*
X222369Y148750D03*
X218017Y156500D03*
X224537Y206820D03*
X229150Y571129D03*
X225834Y1382305D03*
X242237Y71862D03*
X232803Y711602D03*
X236982Y1385562D03*
X247314Y111743D03*
X256678Y140882D03*
X259828Y144882D03*
X260227Y207660D03*
X247557Y224370D03*
X248144Y640909D03*
X271973Y74536D03*
X273784Y99183D03*
X267067Y142892D03*
X267070Y159203D03*
Y155203D03*
X270017Y215000D03*
X262017Y221500D03*
X267936Y611172D03*
X262108Y644555D03*
X271515Y676901D03*
X270582Y1339416D03*
X276917Y136962D03*
X277017Y207000D03*
Y211000D03*
X283808Y570398D03*
X276918Y585178D03*
X282374Y674150D03*
X295464Y75673D03*
X298183Y71128D03*
X296570Y156203D03*
Y151703D03*
X294838Y678796D03*
X304245Y711142D03*
X292330Y1336131D03*
X303478Y1339388D03*
X317074Y91803D03*
X316017Y263000D03*
X314160Y694525D03*
X322559Y69863D03*
X334431Y165170D03*
X325908Y545521D03*
X328746Y566086D03*
X327608Y698946D03*
X325234Y1336074D03*
X343233Y225070D03*
X339017Y285000D03*
X337015Y731292D03*
X336382Y1339331D03*
X363713Y130165D03*
X352432Y215325D03*
X365832Y211361D03*
Y219361D03*
X352450Y211407D03*
X365832Y215361D03*
X358017Y307500D03*
X356124Y550415D03*
X353674Y562415D03*
Y566415D03*
Y570415D03*
Y574415D03*
X364649Y617438D03*
X360668Y698678D03*
X358034Y1336274D03*
X370980Y158028D03*
X373562Y225145D03*
Y228645D03*
X374072Y243615D03*
X370075Y731024D03*
X369182Y1339531D03*
X371279Y1387697D03*
X386510Y142937D03*
X392813Y138980D03*
X381105Y280370D03*
Y294370D03*
X391517Y311500D03*
X394017Y304000D03*
X393708Y698746D03*
X395923Y134980D03*
X405658Y148300D03*
X399888Y551915D03*
X403115Y731092D03*
X401764Y1358862D03*
X404523Y1631219D03*
X409017Y1637000D03*
X406017Y1645500D03*
Y1653500D03*
X419510Y59935D03*
X419354Y71665D03*
Y66865D03*
X420318Y99148D03*
X416768Y104148D03*
X412658Y144300D03*
Y148300D03*
X414457Y235442D03*
X415232Y250165D03*
Y258165D03*
Y266165D03*
X415683Y1006123D03*
Y1009864D03*
X425133Y1014766D03*
X415683Y1013604D03*
Y1028564D03*
X425115Y1018879D03*
X415683Y1021084D03*
Y1024824D03*
Y1017344D03*
X425115Y1023013D03*
X414017Y1657500D03*
X426708Y680946D03*
X436115Y713292D03*
X434962Y1014745D03*
X434958Y1018879D03*
Y1023013D03*
X438517Y1604200D03*
Y1600200D03*
X449422Y270911D03*
X443816Y1014745D03*
X454052D03*
X443816Y1018879D03*
X454052D03*
X443816Y1023013D03*
X454052D03*
X442017Y1622700D03*
Y1618700D03*
X462745Y70016D03*
X465913Y239764D03*
Y227764D03*
Y231764D03*
Y247764D03*
X459108Y656346D03*
X468515Y688692D03*
X465017Y1668000D03*
Y1659500D03*
X470017Y1680000D03*
X465017Y1676000D03*
X465517Y1697000D03*
X472370Y60029D03*
X472300Y55135D03*
X472370Y64975D03*
X473642Y90574D03*
Y105574D03*
Y100574D03*
Y95574D03*
X473707Y119644D03*
Y115644D03*
X473642Y110574D03*
X473707Y123644D03*
X483270Y206827D03*
X473445Y284738D03*
Y280858D03*
X481982Y578572D03*
X472517Y1655500D03*
Y1672000D03*
Y1701000D03*
Y1706500D03*
Y1714500D03*
X490014Y171625D03*
X489199Y193516D03*
Y189516D03*
X497749Y193516D03*
Y185516D03*
Y189516D03*
X486201Y233000D03*
X494551Y238119D03*
X491708Y629846D03*
X506024Y185516D03*
X501293Y205285D03*
X508293Y202404D03*
X501115Y662192D03*
X526517Y432500D03*
X525008Y595746D03*
X541713Y195256D03*
X543505Y218441D03*
Y230441D03*
Y239566D03*
X536517Y445500D03*
X534415Y628092D03*
X544254Y663689D03*
X551353Y152742D03*
X556095Y193541D03*
X553190Y399586D03*
Y414274D03*
Y423949D03*
X550517Y451000D03*
X559017Y477500D03*
X571253Y235821D03*
X560445Y293738D03*
Y289858D03*
X560517Y451000D03*
X572017Y462000D03*
Y466000D03*
X570017Y471500D03*
Y475500D03*
X583720Y164356D03*
Y169415D03*
X575554Y193516D03*
X575569Y197481D03*
X578041Y261171D03*
X583140Y411846D03*
Y423949D03*
Y435949D03*
X583723Y454242D03*
X577017Y475500D03*
Y479500D03*
X600284Y136408D03*
X600287Y132270D03*
X600286Y141640D03*
X591040Y208991D03*
X591046Y221277D03*
Y217277D03*
Y225277D03*
Y229277D03*
X590327Y400287D03*
Y404287D03*
X603017Y412000D03*
X590644Y458461D03*
X590723Y454242D03*
X590520Y468893D03*
X590538Y479631D03*
X594017Y493500D03*
X600288Y1266598D03*
Y1262598D03*
X612017Y440000D03*
X620546Y221777D03*
Y226277D03*
X629938Y474020D03*
X627419Y1357114D03*
X619376Y1367166D03*
X619294Y1386732D03*
X646331Y166053D03*
Y161862D03*
X646383Y174201D03*
X646331Y170053D03*
X643178Y473905D03*
X648917Y1728000D03*
Y1717138D03*
X641917Y1728000D03*
Y1722138D03*
Y1717138D03*
X648917Y1722138D03*
X641917Y1733000D03*
X648917D03*
X652517Y390000D03*
X656457Y461818D03*
X656440Y457755D03*
X661472Y486941D03*
X650582D03*
X661334Y495126D03*
X655753Y1371199D03*
X655685Y1378931D03*
X655719Y1375061D03*
X653317Y1698400D03*
X662517Y1708184D03*
X653317Y1712084D03*
X672562Y401567D03*
Y409320D03*
Y405488D03*
X672517Y457862D03*
Y453862D03*
Y461862D03*
Y477862D03*
Y465862D03*
X672433Y474268D03*
X672517Y482862D03*
X666803Y504895D03*
X674803D03*
X665517Y529500D03*
X671117Y1308002D03*
X677810Y1639704D03*
Y1643904D03*
X680470Y115868D03*
X680294Y1530526D03*
Y1526526D03*
X706940Y103308D03*
X702157Y1560573D03*
X702127Y1580523D03*
X702017Y1608500D03*
Y1600500D03*
X702658Y1616656D03*
X696934Y1670408D03*
X696972Y1674429D03*
X696856Y1678474D03*
X710217Y157762D03*
X730010Y90998D03*
X730040Y95158D03*
X735172Y1400414D03*
X725378Y1614743D03*
X751650Y111288D03*
X745752Y142050D03*
X748217Y167537D03*
X752127Y1576023D03*
Y1589023D03*
Y1584023D03*
X757135Y89348D03*
X756784Y276322D03*
X763760Y299279D03*
X763167Y1591733D03*
X757179Y1693369D03*
X774806Y158026D03*
X774820Y153728D03*
X777560Y299279D03*
X779017Y371000D03*
Y364000D03*
X772017D03*
X775186Y419464D03*
X775169Y455344D03*
Y463344D03*
Y459344D03*
Y476344D03*
Y472344D03*
Y487344D03*
Y491344D03*
Y499344D03*
Y495344D03*
X788283Y267822D03*
Y281822D03*
X789619Y415344D03*
X789517Y407500D03*
X789669Y439344D03*
Y451344D03*
Y463344D03*
Y459344D03*
Y455344D03*
Y471344D03*
X789838Y467646D03*
X790179Y483458D03*
X790396Y479511D03*
X790017Y507000D03*
X792363Y1328662D03*
X805576Y386791D03*
X805583Y381020D03*
Y376753D03*
X798517Y392500D03*
X806592Y422687D03*
X806403Y431344D03*
X806319Y463578D03*
X806231Y449802D03*
X806450Y471344D03*
X806563Y476159D03*
X806450Y487344D03*
X806519Y491344D03*
X806563Y480159D03*
X806517Y504000D03*
X806636Y495344D03*
X806517Y512000D03*
Y516000D03*
X808517Y534500D03*
X808225Y541448D03*
X804381Y1340762D03*
Y1336334D03*
X799517Y1330000D03*
X804788Y1351988D03*
X807928Y1364193D03*
X804667Y1574633D03*
Y1590633D03*
Y1598633D03*
Y1606633D03*
X820936Y415344D03*
Y419344D03*
X827200Y405347D03*
X820928Y423099D03*
X820936Y455344D03*
X820875Y463578D03*
Y471344D03*
Y467568D03*
X827685Y497912D03*
X831479Y58632D03*
X828237Y166862D03*
Y176362D03*
X836017Y393000D03*
X832017Y471000D03*
X840718Y490567D03*
X840754Y486478D03*
X840717Y482128D03*
X840603Y494661D03*
X848837Y162762D03*
X856320Y269057D03*
X856350Y273217D03*
X856238Y384030D03*
X846274Y507106D03*
X853036Y494585D03*
X852842Y503154D03*
X853108Y498861D03*
X846667Y1574633D03*
Y1590633D03*
Y1598633D03*
Y1606633D03*
X871237Y166362D03*
X859017Y395500D03*
X868537Y418720D03*
X879237Y171362D03*
Y176862D03*
X881242Y187449D03*
X881232Y183169D03*
X883945Y267407D03*
X877932Y289439D03*
X885017Y326000D03*
X885999Y1056033D03*
X902298Y606915D03*
X888667Y1574633D03*
Y1590633D03*
Y1598633D03*
Y1606633D03*
X916973Y570706D03*
X930667Y1582233D03*
Y1578233D03*
Y1586233D03*
X945060Y585200D03*
X945748Y614150D03*
X944573Y628662D03*
X958142Y198171D03*
X958994Y1498695D03*
X981641Y189347D03*
X984972Y260781D03*
Y271443D03*
X984601Y295641D03*
X988573Y516014D03*
Y521014D03*
Y526074D03*
Y531074D03*
X982360Y1498695D03*
X994429Y221233D03*
Y225233D03*
X1000851Y446175D03*
Y457175D03*
Y451675D03*
Y462675D03*
Y468175D03*
Y479175D03*
Y473675D03*
Y494175D03*
Y490175D03*
Y484675D03*
Y499675D03*
X1005726Y1498695D03*
X1009827Y153868D03*
X1013737Y198999D03*
X1013712Y207423D03*
X1013637Y203099D03*
X1013712Y214423D03*
Y222423D03*
Y218423D03*
Y226423D03*
X1015351Y287311D03*
Y298311D03*
X1021476Y397726D03*
X1007219Y433426D03*
X1014074Y420902D03*
X1011281Y484155D03*
X1008723Y510304D03*
X1013017Y560500D03*
X1021517Y566000D03*
X1029092Y1498695D03*
X1042619Y1646205D03*
X1042487Y1652082D03*
X1055034Y406560D03*
X1065763Y445499D03*
X1065813Y457959D03*
X1065781Y453655D03*
Y449655D03*
X1065811Y462525D03*
Y467000D03*
Y471500D03*
X1055997Y490037D03*
X1065781Y479655D03*
X1057663Y1311203D03*
Y1307203D03*
X1052458Y1498695D03*
X1074727Y457959D03*
X1077720Y1385543D03*
X1075824Y1498695D03*
X1090455Y446105D03*
Y440605D03*
Y462605D03*
Y457105D03*
Y451605D03*
Y468105D03*
X1083455Y472105D03*
X1090455Y489641D03*
Y484605D03*
Y494641D03*
X1091356Y1633726D03*
X1091398Y1629945D03*
X1098965Y479355D03*
X1099172Y1382286D03*
X1110320Y1385543D03*
X1099190Y1498695D03*
X1099540Y1634400D03*
X1099733Y1630123D03*
X1099017Y1639000D03*
X1124426Y398020D03*
X1126750Y52651D03*
X1133923Y52599D03*
X1133155Y56512D03*
X1133422Y380533D03*
Y385698D03*
X1131872Y1382286D03*
X1147335Y74738D03*
X1152210Y204835D03*
Y209835D03*
X1144755Y489819D03*
X1143020Y1385543D03*
X1147400Y1436579D03*
X1157655Y461691D03*
Y457691D03*
Y449691D03*
Y453691D03*
Y465691D03*
Y469691D03*
Y481691D03*
X1169049Y580602D03*
X1169109Y584622D03*
X1164772Y1382286D03*
X1171946Y89556D03*
Y93556D03*
X1179708Y95864D03*
X1175920Y1385543D03*
X1181117Y1433000D03*
X1192804Y61515D03*
X1192904Y57015D03*
X1192824Y52815D03*
X1186005Y87125D03*
Y91125D03*
X1192219Y164987D03*
Y160987D03*
X1188444Y436202D03*
Y444202D03*
X1199944Y460202D03*
X1188444Y452202D03*
X1200004Y465272D03*
X1200080Y470376D03*
X1197632Y1382088D03*
X1197017Y1396500D03*
Y1401000D03*
Y1410000D03*
Y1405500D03*
Y1424000D03*
X1188117Y1428500D03*
Y1433000D03*
X1197017Y1437500D03*
Y1447500D03*
Y1442500D03*
X1189872Y1673050D03*
X1189554Y1697850D03*
X1196554D03*
X1210098Y94846D03*
X1202273Y133866D03*
Y128748D03*
X1202529Y177187D03*
Y181187D03*
X1202560Y188942D03*
X1208720Y1385543D03*
X1208017Y1401000D03*
X1205214Y1673059D03*
X1204896Y1697859D03*
X1211896D03*
X1241710Y145239D03*
X1236971Y447255D03*
Y443255D03*
X1241834Y1418462D03*
X1241876Y1422362D03*
X1258124Y155730D03*
Y164051D03*
Y160051D03*
Y176051D03*
Y180551D03*
Y168051D03*
Y172051D03*
Y185051D03*
X1254964Y464372D03*
X1245844Y468152D03*
X1256017Y765000D03*
X1246711Y1339397D03*
X1272628Y150030D03*
X1270566Y390884D03*
X1262517Y390500D03*
X1262719Y411125D03*
Y407125D03*
Y415125D03*
X1268459Y1336112D03*
X1286624Y162051D03*
Y166051D03*
Y171551D03*
Y184051D03*
X1279607Y1339369D03*
X1281617Y1430000D03*
Y1434000D03*
X1295210Y133739D03*
Y125739D03*
Y129739D03*
Y145739D03*
X1290219Y403625D03*
Y408125D03*
X1304159Y537299D03*
X1293273Y552147D03*
X1304275Y556545D03*
X1291883Y597013D03*
X1301363Y1336055D03*
X1312511Y1339312D03*
X1334163Y1336255D03*
X1343277Y674443D03*
X1345311Y1339512D03*
X1368201Y100509D03*
X1372660Y613889D03*
X1366923Y1355715D03*
X1377893Y1358843D03*
X1382067Y646235D03*
X1391825Y1009863D03*
Y1013603D03*
Y1006122D03*
Y1017343D03*
Y1028563D03*
Y1024823D03*
Y1021083D03*
X1389010Y1670391D03*
X1382010Y1674391D03*
X1384562Y1704038D03*
X1382321Y1733118D03*
X1396774Y642765D03*
X1405360Y646789D03*
X1401257Y1014744D03*
Y1018878D03*
Y1023012D03*
X1405150Y1622167D03*
X1398150Y1626167D03*
X1402000Y1630167D03*
X1414767Y679135D03*
X1419958Y1014744D03*
X1411104D03*
X1419958Y1023012D03*
X1411100Y1018878D03*
X1419958D03*
X1411100Y1023012D03*
X1423814Y1619504D03*
Y1613966D03*
X1418832Y1642967D03*
X1432136Y244450D03*
X1430774Y675765D03*
X1437960Y679369D03*
X1430194Y1014744D03*
Y1023012D03*
Y1018878D03*
X1432826Y1609966D03*
X1433014Y1619566D03*
X1445136Y244450D03*
X1447367Y711715D03*
X1464922Y61563D03*
X1455759Y128242D03*
X1466774Y548977D03*
Y552977D03*
Y544977D03*
X1458774Y564977D03*
X1466774Y556977D03*
Y560977D03*
Y564977D03*
X1462274Y695265D03*
X1471922Y61563D03*
X1470878Y698946D03*
X1480285Y731292D03*
X1510774Y543977D03*
X1503960Y698946D03*
X1513367Y731292D03*
X1523836Y201250D03*
X1539034Y300816D03*
Y308816D03*
Y304816D03*
X1536760Y698946D03*
X1546881Y284575D03*
X1546167Y731292D03*
X1547191Y1266271D03*
X1547194Y1282188D03*
Y1278188D03*
Y1286188D03*
X1566534Y297316D03*
Y301816D03*
X1570160Y531220D03*
X1569890Y677006D03*
X1562005Y1273445D03*
X1579297Y709352D03*
X1581789Y1302278D03*
X1595970Y225250D03*
X1602660Y643237D03*
X1615826Y530739D03*
X1610636Y542733D03*
X1612067Y675583D03*
X1622459Y282728D03*
Y278520D03*
X1622426Y286742D03*
X1629766Y1420450D03*
X1629684Y1444016D03*
Y1440016D03*
X1642705Y627206D03*
X1635660Y624237D03*
X1645067Y656583D03*
X1634850Y1306874D03*
X1638007Y1410398D03*
X1639684Y1442228D03*
X1655042Y141762D03*
Y146762D03*
Y151762D03*
Y161762D03*
X1656683Y696318D03*
X1666273Y1432215D03*
X1666307Y1428345D03*
X1666341Y1424483D03*
X1666359Y1420567D03*
X1682905Y1399703D03*
X1688168Y1559526D03*
Y1563526D03*
X1692044Y1696422D03*
X1701811Y373773D03*
Y369773D03*
X1699901Y401485D03*
X1722435Y112867D03*
X1714707Y364962D03*
X1709851Y666238D03*
Y662238D03*
X1736826Y85339D03*
X1730096Y1530950D03*
Y1535250D03*
X1735446Y1649456D03*
X1726980Y1663465D03*
Y1667965D03*
Y1658965D03*
Y1672465D03*
X1748905Y100307D03*
X1746127Y305106D03*
X1751237Y372452D03*
X1740014Y1435005D03*
X1748996Y1585905D03*
X1738980Y1653965D03*
X1760585Y76797D03*
X1760555Y72637D03*
X1753453Y85407D03*
X1765996Y1582405D03*
X1778592Y190799D03*
X1768445Y1666984D03*
X1768406Y1670514D03*
X1767980Y1685465D03*
X1768325Y1674057D03*
X1767980Y1681702D03*
Y1678172D03*
Y1689965D03*
X1787680Y70987D03*
X1782195Y92927D03*
X1789907Y146834D03*
Y151834D03*
Y165834D03*
X1792288Y367866D03*
X1784816Y403932D03*
X1792288Y390411D03*
X1784816Y410432D03*
Y418932D03*
Y425432D03*
X1782811Y1585832D03*
X1822097Y147834D03*
X1815097Y151834D03*
X1817249Y371329D03*
X1824249D03*
Y367359D03*
X1823186Y383952D03*
Y379552D03*
X1817086Y395552D03*
X1816316Y407932D03*
X1815816Y421432D03*
Y427432D03*
X1815809Y431678D03*
X1844808Y161834D03*
G54D180*
X496693Y297114D03*
X519723D03*
X583693Y306114D03*
X606723D03*
G54D207*
X706780Y432492D03*
Y429342D03*
Y426192D03*
Y423043D03*
Y419893D03*
X703630Y432492D03*
Y429342D03*
Y426192D03*
Y423043D03*
Y419893D03*
X700481Y432492D03*
Y429342D03*
Y426192D03*
Y423043D03*
Y419893D03*
X697331Y432492D03*
Y429342D03*
Y426192D03*
Y423043D03*
Y419893D03*
X706780Y448240D03*
Y445090D03*
Y441940D03*
Y438791D03*
Y435641D03*
X703630Y448240D03*
Y445090D03*
Y441940D03*
Y438791D03*
Y435641D03*
X700481Y448240D03*
Y445090D03*
Y441940D03*
Y438791D03*
Y435641D03*
X697331Y448240D03*
Y445090D03*
Y441940D03*
Y438791D03*
Y435641D03*
X706780Y463988D03*
Y460838D03*
Y457688D03*
Y454539D03*
Y451389D03*
X703630Y463988D03*
Y460838D03*
Y457688D03*
Y454539D03*
Y451389D03*
X700481Y463988D03*
Y460838D03*
Y457688D03*
Y454539D03*
Y451389D03*
X697331Y463988D03*
Y460838D03*
Y457688D03*
Y454539D03*
Y451389D03*
X706780Y476586D03*
Y473436D03*
Y470287D03*
Y467137D03*
X703630Y476586D03*
Y473436D03*
Y470287D03*
Y467137D03*
X700481Y476586D03*
Y473436D03*
Y470287D03*
Y467137D03*
X697331Y476586D03*
Y473436D03*
Y470287D03*
Y467137D03*
X706780Y486035D03*
Y482885D03*
Y479736D03*
X703630Y486035D03*
Y482885D03*
Y479736D03*
X700481Y486035D03*
Y482885D03*
Y479736D03*
X697331Y486035D03*
Y482885D03*
Y479736D03*
X722528Y432492D03*
Y429342D03*
Y426192D03*
Y423043D03*
Y419893D03*
X719378Y432492D03*
Y429342D03*
Y426192D03*
Y423043D03*
Y419893D03*
X716229Y432492D03*
Y429342D03*
Y426192D03*
Y423043D03*
Y419893D03*
X713079Y432492D03*
Y429342D03*
Y426192D03*
Y423043D03*
Y419893D03*
X709930Y432492D03*
Y429342D03*
Y426192D03*
Y423043D03*
Y419893D03*
X722528Y448240D03*
Y445090D03*
Y441940D03*
Y438791D03*
Y435641D03*
X719378Y448240D03*
Y445090D03*
Y441940D03*
Y438791D03*
Y435641D03*
X716229Y448240D03*
Y445090D03*
Y441940D03*
Y438791D03*
Y435641D03*
X713079Y448240D03*
Y445090D03*
Y441940D03*
Y438791D03*
Y435641D03*
X709930Y448240D03*
Y445090D03*
Y441940D03*
Y438791D03*
Y435641D03*
X722528Y463988D03*
Y460838D03*
Y457688D03*
Y454539D03*
Y451389D03*
X719378Y463988D03*
Y460838D03*
Y457688D03*
Y454539D03*
Y451389D03*
X716229Y463988D03*
Y460838D03*
Y457688D03*
Y454539D03*
Y451389D03*
X713079Y463988D03*
Y460838D03*
Y457688D03*
Y454539D03*
Y451389D03*
X709930Y463988D03*
Y460838D03*
Y457688D03*
Y454539D03*
Y451389D03*
X722528Y476586D03*
Y473436D03*
Y470287D03*
Y467137D03*
X719378Y476586D03*
Y473436D03*
Y470287D03*
Y467137D03*
X716229Y476586D03*
Y473436D03*
Y470287D03*
Y467137D03*
X713079Y476586D03*
Y473436D03*
Y470287D03*
Y467137D03*
X709930Y476586D03*
Y473436D03*
Y470287D03*
Y467137D03*
X722528Y486035D03*
Y482885D03*
Y479736D03*
X719378Y486035D03*
Y482885D03*
Y479736D03*
X716229Y486035D03*
Y482885D03*
Y479736D03*
X713079Y486035D03*
Y482885D03*
Y479736D03*
X709930Y486035D03*
Y482885D03*
Y479736D03*
X738276Y432492D03*
Y429342D03*
Y426192D03*
Y423043D03*
Y419893D03*
X735126Y432492D03*
Y429342D03*
Y426192D03*
Y423043D03*
Y419893D03*
X731977Y432492D03*
Y429342D03*
Y426192D03*
Y423043D03*
Y419893D03*
X728827Y432492D03*
Y429342D03*
Y426192D03*
Y423043D03*
Y419893D03*
X725678Y432492D03*
Y429342D03*
Y426192D03*
Y423043D03*
Y419893D03*
X738276Y448240D03*
Y445090D03*
Y441940D03*
Y438791D03*
Y435641D03*
X735126Y448240D03*
Y445090D03*
Y441940D03*
Y438791D03*
Y435641D03*
X731977Y448240D03*
Y445090D03*
Y441940D03*
Y438791D03*
Y435641D03*
X728827Y448240D03*
Y445090D03*
Y441940D03*
Y438791D03*
Y435641D03*
X725678Y448240D03*
Y445090D03*
Y441940D03*
Y438791D03*
Y435641D03*
X738276Y463988D03*
Y460838D03*
Y457688D03*
Y454539D03*
Y451389D03*
X735126Y463988D03*
Y460838D03*
Y457688D03*
Y454539D03*
Y451389D03*
X731977Y463988D03*
Y460838D03*
Y457688D03*
Y454539D03*
Y451389D03*
X728827Y463988D03*
Y460838D03*
Y457688D03*
Y454539D03*
Y451389D03*
X725678Y463988D03*
Y460838D03*
Y457688D03*
Y454539D03*
Y451389D03*
X738276Y476586D03*
Y473436D03*
Y470287D03*
Y467137D03*
X735126Y476586D03*
Y473436D03*
Y470287D03*
Y467137D03*
X731977Y476586D03*
Y473436D03*
Y470287D03*
Y467137D03*
X728827Y476586D03*
Y473436D03*
Y470287D03*
Y467137D03*
X725678Y476586D03*
Y473436D03*
Y470287D03*
Y467137D03*
X738276Y486035D03*
Y482885D03*
Y479736D03*
X735126Y486035D03*
Y482885D03*
Y479736D03*
X731977Y486035D03*
Y482885D03*
Y479736D03*
X728827Y486035D03*
Y482885D03*
Y479736D03*
X725678Y486035D03*
Y482885D03*
Y479736D03*
X750874Y432492D03*
Y429342D03*
Y426192D03*
Y423043D03*
Y419893D03*
X747725Y432492D03*
Y429342D03*
Y426192D03*
Y423043D03*
Y419893D03*
X744575Y432492D03*
Y429342D03*
Y426192D03*
Y423043D03*
Y419893D03*
X741426Y432492D03*
Y429342D03*
Y426192D03*
Y423043D03*
Y419893D03*
X750874Y448240D03*
Y445090D03*
Y441940D03*
Y438791D03*
Y435641D03*
X747725Y448240D03*
Y445090D03*
Y441940D03*
Y438791D03*
Y435641D03*
X744575Y448240D03*
Y445090D03*
Y441940D03*
Y438791D03*
Y435641D03*
X741426Y448240D03*
Y445090D03*
Y441940D03*
Y438791D03*
Y435641D03*
X750874Y463988D03*
Y460838D03*
Y457688D03*
Y454539D03*
Y451389D03*
X747725Y463988D03*
Y460838D03*
Y457688D03*
Y454539D03*
Y451389D03*
X744575Y463988D03*
Y460838D03*
Y457688D03*
Y454539D03*
Y451389D03*
X741426Y463988D03*
Y460838D03*
Y457688D03*
Y454539D03*
Y451389D03*
X750874Y476586D03*
Y473436D03*
Y470287D03*
Y467137D03*
X747725Y476586D03*
Y473436D03*
Y470287D03*
Y467137D03*
X744575Y476586D03*
Y473436D03*
Y470287D03*
Y467137D03*
X741426Y476586D03*
Y473436D03*
Y470287D03*
Y467137D03*
X750874Y486035D03*
Y482885D03*
Y479736D03*
X747725Y486035D03*
Y482885D03*
Y479736D03*
X744575Y486035D03*
Y482885D03*
Y479736D03*
X741426Y486035D03*
Y482885D03*
Y479736D03*
X763473Y432492D03*
Y429342D03*
Y426192D03*
Y423043D03*
Y419893D03*
X760323Y432492D03*
Y429342D03*
Y426192D03*
Y423043D03*
Y419893D03*
X757174Y432492D03*
Y429342D03*
Y426192D03*
Y423043D03*
Y419893D03*
X754024Y432492D03*
Y429342D03*
Y426192D03*
Y423043D03*
Y419893D03*
X763473Y448240D03*
Y445090D03*
Y441940D03*
Y438791D03*
Y435641D03*
X760323Y448240D03*
Y445090D03*
Y441940D03*
Y438791D03*
Y435641D03*
X757174Y448240D03*
Y445090D03*
Y441940D03*
Y438791D03*
Y435641D03*
X754024Y448240D03*
Y445090D03*
Y441940D03*
Y438791D03*
Y435641D03*
X763473Y463988D03*
Y460838D03*
Y457688D03*
Y454539D03*
Y451389D03*
X760323Y463988D03*
Y460838D03*
Y457688D03*
Y454539D03*
Y451389D03*
X757174Y463988D03*
Y460838D03*
Y457688D03*
Y454539D03*
Y451389D03*
X754024Y463988D03*
Y460838D03*
Y457688D03*
Y454539D03*
Y451389D03*
X763473Y476586D03*
Y473436D03*
Y470287D03*
Y467137D03*
X760323Y476586D03*
Y473436D03*
Y470287D03*
Y467137D03*
X757174Y476586D03*
Y473436D03*
Y470287D03*
Y467137D03*
X754024Y476586D03*
Y473436D03*
Y470287D03*
Y467137D03*
X763473Y486035D03*
Y482885D03*
Y479736D03*
X760323Y486035D03*
Y482885D03*
Y479736D03*
X757174Y486035D03*
Y482885D03*
Y479736D03*
X754024Y486035D03*
Y482885D03*
Y479736D03*
G54D216*
X716697Y1579704D03*
Y1576160D03*
Y1581475D03*
Y1577932D03*
Y1586790D03*
Y1588562D03*
Y1583247D03*
Y1585018D03*
X742189Y1576160D03*
Y1577932D03*
Y1581475D03*
Y1579704D03*
Y1588562D03*
Y1586790D03*
Y1583247D03*
Y1585018D03*
G54D234*
X804457Y1348236D03*
G54D172*
X476826Y293510D03*
X563826Y302510D03*
G54D16*
X17363Y230264D03*
X10543Y230308D03*
X36595Y385068D03*
X32774Y525886D03*
X46834Y363428D03*
X50631Y1530187D03*
X42150Y1550596D03*
X46150D03*
X45633Y1595412D03*
X50133D03*
X55190Y363428D03*
X64442Y504481D03*
X53299Y546811D03*
X63148Y546776D03*
X58365D03*
X59427Y1646903D03*
X66127Y1681903D03*
X76378Y1409171D03*
X72378D03*
X79323Y1530043D03*
X72768Y1547312D03*
X76806Y1596423D03*
X78406Y1604723D03*
X73427Y1646903D03*
X68427D03*
X82127Y1681903D03*
X86374Y1530687D03*
X90127Y1681903D03*
X92257Y1721347D03*
X98101Y1363553D03*
X108511Y1547012D03*
X115016Y294713D03*
Y315147D03*
X118407Y521307D03*
X126910Y1364151D03*
X119632Y1381874D03*
X115066Y1529743D03*
X120353Y1649103D03*
X124353D03*
X116353D03*
X123353Y1690482D03*
X140360Y424096D03*
X130701Y1363553D03*
X140353Y1649103D03*
X128353D03*
X127353Y1690603D03*
X132767Y1723257D03*
X150318Y210474D03*
Y218474D03*
X152232Y1381874D03*
X143500Y1442516D03*
X147000D03*
X148353Y1649103D03*
X144253D03*
X147253Y1690603D03*
X154740Y1707516D03*
X149900Y1712882D03*
Y1719882D03*
X159510Y1363924D03*
X163401Y1363553D03*
X159427Y1690603D03*
X167500Y1715516D03*
X162740Y1707516D03*
X184932Y1381874D03*
X181760Y1707404D03*
X185760Y1725892D03*
X189410Y390676D03*
X192210Y1364151D03*
X196301Y1363553D03*
X194000Y1715016D03*
X189760Y1707404D03*
X211000Y1712016D03*
X228675Y564125D03*
X225110Y1364151D03*
X229101Y1363553D03*
X217832Y1381874D03*
X236266Y62378D03*
X240266D03*
X244266D03*
X232817Y564093D03*
X239843Y712264D03*
X248266Y62378D03*
X251487Y104776D03*
X255270Y211986D03*
X255466Y645275D03*
X257910Y1364151D03*
X250632Y1381874D03*
X275797Y124059D03*
X269405Y582051D03*
X262466Y595169D03*
X263866Y587970D03*
X269061Y644465D03*
X272955Y653096D03*
X272932Y670417D03*
X262701Y1317407D03*
X261778Y1364141D03*
X279783Y124084D03*
X288597Y215535D03*
X288949Y246427D03*
X276801Y578594D03*
X288196Y679516D03*
X284232Y1335728D03*
X305266Y68123D03*
X301315Y95815D03*
X305315D03*
X293000Y219516D03*
X292949Y246427D03*
X292705Y582970D03*
X301791Y678706D03*
X305685Y687337D03*
X305662Y704658D03*
X295597Y1317379D03*
X291510Y1317805D03*
X310339Y228367D03*
X320966Y699666D03*
X317128Y1335700D03*
X325617Y73879D03*
X333988Y593820D03*
X334561Y698856D03*
X324557Y1317943D03*
X328501Y1317322D03*
X346695Y234071D03*
X342000Y277516D03*
X348157Y571356D03*
X338455Y707487D03*
X338432Y724808D03*
X350032Y1335643D03*
X352608Y276846D03*
X355828Y291906D03*
X354026Y699398D03*
X357310Y1317920D03*
X361301Y1317522D03*
X378184Y468867D03*
X375943Y534212D03*
X367621Y698588D03*
X371515Y707219D03*
X371492Y724540D03*
X386703Y123853D03*
X390859Y123900D03*
X387184Y473011D03*
X382184Y501617D03*
X392184D03*
X380771Y534154D03*
X387066Y699466D03*
X390110Y1318120D03*
X382832Y1335843D03*
X393883Y1336853D03*
X382992Y1674962D03*
X387324Y1675011D03*
X392324D03*
X407299Y206636D03*
X403299D03*
Y214587D03*
X407299D03*
X406184Y501617D03*
X397184D03*
X400673Y570869D03*
X400661Y698656D03*
X404555Y707287D03*
X404532Y724608D03*
X399000Y1624229D03*
X397324Y1675011D03*
X409000Y1677516D03*
X423299Y206636D03*
X415299D03*
X419299D03*
X415299Y214587D03*
X419984Y501540D03*
X410984D03*
X424784Y501463D03*
X420066Y681666D03*
X423926Y1029020D03*
X422692Y1337451D03*
X415414Y1355174D03*
X413000Y1677516D03*
X438673Y77216D03*
X433685Y91173D03*
X429685D03*
X429673Y77216D03*
X433673Y84216D03*
X438673D03*
X437997Y160641D03*
X433997D03*
X439299Y206636D03*
X435299D03*
X427299D03*
X431299D03*
Y214587D03*
X427299D03*
X435299D03*
X439500Y486516D03*
X433661Y680856D03*
X437555Y689487D03*
X437532Y706808D03*
X435146Y1029020D03*
X427666D03*
X431406D03*
X438886D03*
X426561Y1337435D03*
X428500Y1634016D03*
X442673Y84216D03*
X449997Y160641D03*
X445997D03*
X449997Y153641D03*
X445997D03*
X453997Y160641D03*
X443299Y206636D03*
X447299D03*
Y214587D03*
X443299D03*
X452466Y657066D03*
X450107Y1029020D03*
X442626D03*
X453847D03*
X446366D03*
X447576Y1644498D03*
X443594Y1644543D03*
X461997Y160641D03*
X469997D03*
X457931Y215194D03*
X465699Y285576D03*
X468500Y490016D03*
X466061Y656256D03*
X469955Y664887D03*
X469932Y682208D03*
X457587Y1029020D03*
X457000Y1644016D03*
X465000Y1647516D03*
X468500Y1711516D03*
X473997Y160641D03*
X481997D03*
X477997D03*
X484063Y308488D03*
X485066Y630566D03*
X498385Y108215D03*
X498661Y629756D03*
X502555Y638387D03*
X502532Y655708D03*
X528304Y211013D03*
X518500Y429516D03*
X522500D03*
X518366Y596466D03*
X531961Y595656D03*
X539503Y595432D03*
X543371Y595444D03*
X535855Y604287D03*
X535832Y621608D03*
X540106Y659816D03*
X550196Y184772D03*
X552699Y294576D03*
X573911Y214712D03*
X571063Y317488D03*
X568451Y1265034D03*
X564509Y1265030D03*
X586394Y90189D03*
X578454Y83155D03*
X577859Y214712D03*
X586500Y458016D03*
Y464516D03*
X583125Y751881D03*
X579125D03*
X587521Y751949D03*
X590501Y90189D03*
X602280D03*
X602328Y103586D03*
X590512D03*
X593758Y418721D03*
X603456Y751895D03*
X599489Y751881D03*
X595489D03*
X591521Y751949D03*
X618182Y90189D03*
X618256Y103586D03*
X608794Y191277D03*
X615385Y398669D03*
X607456Y751895D03*
X615443Y751907D03*
X611443D03*
X621310Y175625D03*
X630609Y227491D03*
X626705Y299821D03*
X631505Y286871D03*
X630195Y1386973D03*
X626295D03*
X634095D03*
X642301Y150067D03*
X638000Y415516D03*
X634244Y507554D03*
X646236Y1353453D03*
X638436D03*
X642436D03*
X656000Y518016D03*
Y510016D03*
X650036Y1353453D03*
X653836D03*
X657836D03*
X672800Y371878D03*
X676800D03*
X675500Y393378D03*
X666948Y398203D03*
X678071Y1308705D03*
X684643Y108901D03*
X680800Y371878D03*
X684800D03*
X693367Y363420D03*
X683500Y393378D03*
X679500D03*
X691500D03*
X699520Y363420D03*
X708500Y507878D03*
X704666Y507833D03*
X708509Y523861D03*
X704500Y524378D03*
X700500D03*
X708500Y540378D03*
X704500D03*
X696283Y540803D03*
X702645Y618627D03*
X698645D03*
X705657Y1381562D03*
X703799Y1627709D03*
X705688Y1647458D03*
X706623Y1663092D03*
X708953Y128184D03*
X719334Y363378D03*
X711458Y363376D03*
X716300Y376878D03*
X719500Y393378D03*
X723500D03*
X716500Y507878D03*
X720500D03*
X712500D03*
X712484Y523067D03*
X723032Y524331D03*
X719518Y524347D03*
X716016Y524441D03*
X710464Y549489D03*
X711845Y587733D03*
X711907Y603369D03*
X722129Y661183D03*
X718129D03*
X719152Y1627597D03*
X715309Y1677059D03*
X721909Y1681387D03*
X737093Y87993D03*
X737340Y115751D03*
X735449Y372044D03*
X731406Y376847D03*
X731500Y393378D03*
X727500D03*
X724500Y507878D03*
X737324Y524019D03*
X730310Y524299D03*
X733811Y524253D03*
X726793Y524365D03*
X724500Y540378D03*
X734557Y1381917D03*
X738439Y1381662D03*
X727188Y1399693D03*
X724723Y1627036D03*
X729616Y1677277D03*
X725632Y1677276D03*
X737467Y1680623D03*
X741270Y115675D03*
X739500Y376878D03*
X743500D03*
X748500Y540378D03*
X740500D03*
X751770Y1628299D03*
X752187Y1675010D03*
X741326Y1677073D03*
X745537Y1677158D03*
X745382Y1687286D03*
X760193Y93364D03*
X760500Y109516D03*
X759000Y363878D03*
X763500Y376878D03*
X767500Y393378D03*
X763500D03*
X760500Y540378D03*
X756500D03*
X767339Y1382017D03*
X759970Y1399793D03*
X758030Y1663099D03*
X772000Y524378D03*
X771216Y1382017D03*
X806500Y1327016D03*
X812526Y1345269D03*
X808526D03*
X831540Y62859D03*
X834616Y104297D03*
X835114Y117714D03*
X833715Y225084D03*
X831000Y508516D03*
X841900Y542313D03*
X834750Y566238D03*
X856630Y63009D03*
X850016Y90267D03*
X858783Y224499D03*
X863294Y266052D03*
X863571Y293901D03*
X867571D03*
X886503Y271423D03*
X925468Y264163D03*
X920268Y272375D03*
X922447Y1152591D03*
X949263Y274672D03*
X965442Y164901D03*
X969472Y1152591D03*
X985500Y152315D03*
X989605Y179569D03*
X985445Y179599D03*
X988835Y191969D03*
X988460Y363552D03*
X1005735Y157959D03*
X1001395Y218439D03*
X1004460Y363552D03*
X1000460D03*
X996460D03*
X992460D03*
X1009618Y399081D03*
X1020202Y538292D03*
X1007011Y550165D03*
X1034838Y538292D03*
X1030000Y557516D03*
X1035500D03*
X1050104Y1662400D03*
X1069236Y393973D03*
X1075526Y424480D03*
X1069839Y1363534D03*
X1092948Y476371D03*
X1091370Y1381855D03*
X1095489Y1696120D03*
X1094514Y1715932D03*
X1102439Y1363534D03*
X1098648Y1364132D03*
X1108747Y1535896D03*
X1109522Y1551449D03*
X1109000Y1665516D03*
X1098514Y1722932D03*
X1123970Y1381855D03*
X1114117Y1535896D03*
X1121010Y1588914D03*
X1125010D03*
X1115027Y1593267D03*
X1115394Y1622843D03*
X1112500Y1665516D03*
X1135139Y1363534D03*
X1131248Y1364132D03*
X1137846Y1456464D03*
X1133846D03*
X1132168Y1623481D03*
X1136097Y1623484D03*
X1166203Y74293D03*
X1163948Y1364132D03*
X1168039Y1363534D03*
X1156670Y1381855D03*
X1184000Y425941D03*
X1172000Y427516D03*
X1180000D03*
X1176000D03*
X1196848Y1364132D03*
X1189570Y1381855D03*
X1189407Y1712034D03*
X1200839Y1363534D03*
X1214254Y1713952D03*
Y1706952D03*
Y1727952D03*
Y1720952D03*
X1230312Y91151D03*
X1229648Y1364132D03*
X1222370Y1381855D03*
X1238830Y1317388D03*
X1233516Y1364122D03*
X1259472Y87380D03*
X1248859Y1420016D03*
X1252859D03*
X1253000Y1427016D03*
X1273677Y762004D03*
X1271726Y1317360D03*
X1267639Y1317786D03*
X1260361Y1335709D03*
X1275981Y87630D03*
X1284764Y92320D03*
X1280764D03*
X1288677Y759004D03*
X1277677Y762004D03*
X1281677D03*
X1296200Y61427D03*
X1292786Y545339D03*
X1298886Y593571D03*
X1292677Y762504D03*
X1296677D03*
X1300677Y759004D03*
X1300686Y1317924D03*
X1304630Y1317303D03*
X1293257Y1335681D03*
X1308110Y61427D03*
X1307366Y549729D03*
X1320020Y61495D03*
X1333399Y92600D03*
X1332360Y558711D03*
X1333439Y1317901D03*
X1326161Y1335624D03*
X1337399Y92600D03*
X1341399D03*
X1348199D03*
X1337430Y1317503D03*
X1356199Y92566D03*
X1352199D03*
X1360109D03*
X1350772Y674684D03*
X1358961Y1335824D03*
X1366018Y614609D03*
X1366239Y1318101D03*
X1370012Y1336834D03*
X1379613Y613799D03*
X1383507Y622430D03*
X1383484Y639751D03*
X1391543Y1355155D03*
X1398718Y647509D03*
X1403808Y1029019D03*
X1407548D03*
X1400068D03*
X1403690Y1286281D03*
X1398821Y1337432D03*
X1412313Y646699D03*
X1416207Y655330D03*
X1416184Y672651D03*
X1422508Y1029019D03*
X1415028D03*
X1411288D03*
X1418768D03*
X1419622Y1610283D03*
X1415623Y1599175D03*
X1438262Y55408D03*
X1434513Y109916D03*
X1439049Y116959D03*
X1431318Y680089D03*
X1429989Y1029019D03*
X1433729D03*
X1426249D03*
X1446869Y108377D03*
X1443049Y116959D03*
X1444769Y168733D03*
X1439769D03*
X1449769D03*
X1439769Y176733D03*
X1449769D03*
X1441741Y596382D03*
X1444913Y679279D03*
X1448807Y687910D03*
X1448784Y705231D03*
X1440500Y1617516D03*
X1445500D03*
X1449070Y1681238D03*
X1445079Y1681194D03*
X1454549Y116959D03*
X1460508Y136459D03*
X1454769Y168733D03*
X1464236Y699666D03*
X1461702Y1667904D03*
X1483820Y125774D03*
X1477831Y698856D03*
X1481725Y707487D03*
X1481702Y724808D03*
X1491560Y594553D03*
X1497318Y699666D03*
X1513644Y222191D03*
Y213341D03*
X1513348Y256554D03*
X1510913Y698856D03*
X1527853Y562780D03*
X1514807Y707487D03*
X1514784Y724808D03*
X1539693Y538129D03*
X1537853Y562780D03*
X1530118Y699666D03*
X1543713Y698856D03*
X1547607Y707487D03*
X1547584Y724808D03*
X1561345Y574714D03*
X1563248Y677726D03*
X1584079Y561624D03*
X1576843Y676916D03*
X1580737Y685547D03*
X1580714Y702868D03*
X1579177Y1262304D03*
X1596018Y643957D03*
X1605286Y547189D03*
X1609286D03*
X1609613Y643147D03*
X1613507Y651778D03*
X1613484Y669099D03*
X1625000Y386016D03*
X1629018Y624957D03*
X1621000Y1432516D03*
X1638334Y558303D03*
X1646507Y632778D03*
X1646484Y650099D03*
X1641804Y1308077D03*
X1636167Y1438994D03*
X1661928Y224688D03*
X1659610Y397218D03*
X1653790Y428560D03*
X1657545D03*
X1650035D03*
X1649979Y619062D03*
X1654147Y619014D03*
X1651959Y692763D03*
X1653390Y1380851D03*
X1649024Y1406737D03*
X1653024D03*
X1656824D03*
X1660624D03*
X1654513Y1708700D03*
X1658513Y1711850D03*
X1654513Y1715700D03*
Y1723850D03*
Y1730850D03*
X1663610Y397218D03*
X1674921Y1398982D03*
X1668424Y1406737D03*
X1664424D03*
X1689000Y228516D03*
X1688504Y401576D03*
X1690154Y428701D03*
X1682290Y1381206D03*
X1686172Y1380951D03*
X1681000Y1433516D03*
Y1440016D03*
X1684012Y1666257D03*
X1689513Y1708700D03*
Y1715700D03*
X1693000Y228516D03*
X1694314Y428671D03*
X1695529Y1545284D03*
X1716931Y75771D03*
X1711798Y75783D03*
Y62295D03*
X1716558D03*
X1721344Y62472D03*
X1713418Y125183D03*
X1710426Y407679D03*
X1715072Y1381306D03*
X1718949D03*
X1707703Y1399082D03*
X1726608Y105900D03*
X1730202Y1596109D03*
X1726202D03*
X1725423Y1687172D03*
X1735463Y1688981D03*
X1729436Y1687181D03*
X1728633Y1712206D03*
Y1720356D03*
X1732633Y1723506D03*
X1728633Y1727356D03*
X1750918Y125183D03*
X1751983Y258153D03*
X1737914Y1563223D03*
X1747963Y1644881D03*
X1740463Y1688981D03*
X1745463D03*
X1757322Y125187D03*
X1766606Y1563079D03*
X1760051Y1580348D03*
X1757963Y1647981D03*
X1752963Y1644881D03*
X1762963Y1647981D03*
X1767638Y69632D03*
X1767891Y97336D03*
X1771891D03*
X1773657Y1563723D03*
X1790738Y75003D03*
X1793444Y180660D03*
X1797011D03*
X1789811D03*
X1795794Y1580048D03*
X1800511Y180660D03*
X1804111D03*
X1807711D03*
X1811711Y177560D03*
X1802349Y1562779D03*
X1819705Y156888D03*
X1816308Y202045D03*
G54D43*
X69323Y760178D03*
Y756832D03*
Y776911D03*
Y773564D03*
Y770218D03*
Y766871D03*
Y763525D03*
Y790297D03*
Y786950D03*
Y783604D03*
Y780257D03*
Y807029D03*
Y803682D03*
Y800336D03*
Y796989D03*
Y793643D03*
Y820415D03*
Y817068D03*
Y813722D03*
Y810375D03*
Y837147D03*
Y833800D03*
Y830454D03*
Y827108D03*
Y823761D03*
Y850533D03*
Y847186D03*
Y843840D03*
Y840493D03*
Y863919D03*
Y860572D03*
Y857226D03*
Y853879D03*
Y880651D03*
Y877304D03*
Y873958D03*
Y870611D03*
Y867265D03*
Y894037D03*
Y890690D03*
Y887344D03*
Y883997D03*
Y910769D03*
Y907423D03*
Y904076D03*
Y900730D03*
Y897383D03*
Y924155D03*
Y920808D03*
Y917462D03*
Y914115D03*
Y940887D03*
Y937541D03*
Y934194D03*
Y930848D03*
Y927501D03*
Y954273D03*
Y950926D03*
Y947580D03*
Y944234D03*
Y971005D03*
Y967659D03*
Y964312D03*
Y960966D03*
Y957619D03*
Y984391D03*
Y981045D03*
Y977698D03*
Y974352D03*
Y1001123D03*
Y997777D03*
Y994430D03*
Y991084D03*
Y987737D03*
Y1004470D03*
Y1027895D03*
Y1044627D03*
Y1041281D03*
Y1037934D03*
Y1034588D03*
Y1031241D03*
Y1058013D03*
Y1054667D03*
Y1051320D03*
Y1047974D03*
Y1074745D03*
Y1071399D03*
Y1068052D03*
Y1064706D03*
Y1061360D03*
Y1088131D03*
Y1084785D03*
Y1081438D03*
Y1078092D03*
Y1104863D03*
Y1101517D03*
Y1098171D03*
Y1094824D03*
Y1091478D03*
Y1118249D03*
Y1114903D03*
Y1111556D03*
Y1108210D03*
Y1134982D03*
Y1131635D03*
Y1128289D03*
Y1124942D03*
Y1121596D03*
Y1148367D03*
Y1145021D03*
Y1141675D03*
Y1138328D03*
Y1165100D03*
Y1161753D03*
Y1158407D03*
Y1155060D03*
Y1151714D03*
Y1178486D03*
Y1175139D03*
Y1171793D03*
Y1168446D03*
Y1191871D03*
Y1188525D03*
Y1185178D03*
Y1181832D03*
Y1208604D03*
Y1205257D03*
Y1201911D03*
Y1198564D03*
Y1195218D03*
Y1221989D03*
Y1218643D03*
Y1215297D03*
Y1211950D03*
Y1238722D03*
Y1235375D03*
Y1232029D03*
Y1228682D03*
Y1225336D03*
Y1252108D03*
Y1248761D03*
Y1245415D03*
Y1242068D03*
Y1255454D03*
X99024Y760178D03*
Y756832D03*
X85465Y760178D03*
Y756832D03*
X99024Y776911D03*
Y773564D03*
Y770218D03*
Y766871D03*
Y763525D03*
X85465Y776911D03*
Y773564D03*
Y770218D03*
Y766871D03*
Y763525D03*
X99024Y790297D03*
Y786950D03*
Y783604D03*
Y780257D03*
X85465Y790297D03*
Y786950D03*
Y783604D03*
Y780257D03*
X99024Y807029D03*
Y803682D03*
Y800336D03*
Y796989D03*
Y793643D03*
X85465Y807029D03*
Y803682D03*
Y800336D03*
Y796989D03*
Y793643D03*
X99024Y820415D03*
Y817068D03*
Y813722D03*
Y810375D03*
X85465Y820415D03*
Y817068D03*
Y813722D03*
Y810375D03*
X99024Y837147D03*
Y833800D03*
Y830454D03*
Y827108D03*
Y823761D03*
X85465Y837147D03*
Y833800D03*
Y830454D03*
Y827108D03*
Y823761D03*
X99024Y850533D03*
Y847186D03*
Y843840D03*
Y840493D03*
X85465Y850533D03*
Y847186D03*
Y843840D03*
Y840493D03*
X99024Y863919D03*
Y860572D03*
Y857226D03*
Y853879D03*
X85465Y863919D03*
Y860572D03*
Y857226D03*
Y853879D03*
X99024Y880651D03*
Y877304D03*
Y873958D03*
Y870611D03*
Y867265D03*
X85465Y880651D03*
Y877304D03*
Y873958D03*
Y870611D03*
Y867265D03*
X99024Y894037D03*
Y890690D03*
Y887344D03*
Y883997D03*
X85465Y894037D03*
Y890690D03*
Y887344D03*
Y883997D03*
X99024Y910769D03*
Y907423D03*
Y904076D03*
Y900730D03*
Y897383D03*
X85465Y910769D03*
Y907423D03*
Y904076D03*
Y900730D03*
Y897383D03*
X99024Y924155D03*
Y920808D03*
Y917462D03*
Y914115D03*
X85465Y924155D03*
Y920808D03*
Y917462D03*
Y914115D03*
X99024Y940887D03*
Y937541D03*
Y934194D03*
Y930848D03*
Y927501D03*
X85465Y940887D03*
Y937541D03*
Y934194D03*
Y930848D03*
Y927501D03*
X99024Y954273D03*
Y950926D03*
Y947580D03*
Y944234D03*
X85465Y954273D03*
Y950926D03*
Y947580D03*
Y944234D03*
X99024Y971005D03*
Y967659D03*
Y964312D03*
Y960966D03*
Y957619D03*
X85465Y971005D03*
Y967659D03*
Y964312D03*
Y960966D03*
Y957619D03*
X99024Y984391D03*
Y981045D03*
Y977698D03*
Y974352D03*
X85465Y984391D03*
Y981045D03*
Y977698D03*
Y974352D03*
X99024Y1001123D03*
Y997777D03*
Y994430D03*
Y991084D03*
Y987737D03*
X85465Y1001123D03*
Y997777D03*
Y994430D03*
Y991084D03*
Y987737D03*
X99024Y1004470D03*
X85465D03*
X99024Y1027895D03*
X85465D03*
X99024Y1044627D03*
Y1041281D03*
Y1037934D03*
Y1034588D03*
Y1031241D03*
X85465Y1044627D03*
Y1041281D03*
Y1037934D03*
Y1034588D03*
Y1031241D03*
X99024Y1058013D03*
Y1054667D03*
Y1051320D03*
Y1047974D03*
X85465Y1058013D03*
Y1054667D03*
Y1051320D03*
Y1047974D03*
X99024Y1074745D03*
Y1071399D03*
Y1068052D03*
Y1064706D03*
Y1061360D03*
X85465Y1074745D03*
Y1071399D03*
Y1068052D03*
Y1064706D03*
Y1061360D03*
X99024Y1088131D03*
Y1084785D03*
Y1081438D03*
Y1078092D03*
X85465Y1088131D03*
Y1084785D03*
Y1081438D03*
Y1078092D03*
X99024Y1104863D03*
Y1101517D03*
Y1098171D03*
Y1094824D03*
Y1091478D03*
X85465Y1104863D03*
Y1101517D03*
Y1098171D03*
Y1094824D03*
Y1091478D03*
X99024Y1118249D03*
Y1114903D03*
Y1111556D03*
Y1108210D03*
X85465Y1118249D03*
Y1114903D03*
Y1111556D03*
Y1108210D03*
X99024Y1134982D03*
Y1131635D03*
Y1128289D03*
Y1124942D03*
Y1121596D03*
X85465Y1134982D03*
Y1131635D03*
Y1128289D03*
Y1124942D03*
Y1121596D03*
X99024Y1148367D03*
Y1145021D03*
Y1141675D03*
Y1138328D03*
X85465Y1148367D03*
Y1145021D03*
Y1141675D03*
Y1138328D03*
X99024Y1165100D03*
Y1161753D03*
Y1158407D03*
Y1155060D03*
Y1151714D03*
X85465Y1165100D03*
Y1161753D03*
Y1158407D03*
Y1155060D03*
Y1151714D03*
X99024Y1178486D03*
Y1175139D03*
Y1171793D03*
Y1168446D03*
X85465Y1178486D03*
Y1175139D03*
Y1171793D03*
Y1168446D03*
X99024Y1191871D03*
Y1188525D03*
Y1185178D03*
Y1181832D03*
X85465Y1191871D03*
Y1188525D03*
Y1185178D03*
Y1181832D03*
X99024Y1208604D03*
Y1205257D03*
Y1201911D03*
Y1198564D03*
Y1195218D03*
X85465Y1208604D03*
Y1205257D03*
Y1201911D03*
Y1198564D03*
Y1195218D03*
X99024Y1221989D03*
Y1218643D03*
Y1215297D03*
Y1211950D03*
X85465Y1221989D03*
Y1218643D03*
Y1215297D03*
Y1211950D03*
X99024Y1238722D03*
Y1235375D03*
Y1232029D03*
Y1228682D03*
Y1225336D03*
X85465Y1238722D03*
Y1235375D03*
Y1232029D03*
Y1228682D03*
Y1225336D03*
X99024Y1252108D03*
Y1248761D03*
Y1245415D03*
Y1242068D03*
X85465Y1252108D03*
Y1248761D03*
Y1245415D03*
Y1242068D03*
X99024Y1255454D03*
X85465D03*
X128724Y760178D03*
Y756832D03*
X115166Y760178D03*
Y756832D03*
X128724Y776911D03*
Y773564D03*
Y770218D03*
Y766871D03*
Y763525D03*
X115166Y776911D03*
Y773564D03*
Y770218D03*
Y766871D03*
Y763525D03*
X128724Y790297D03*
Y786950D03*
Y783604D03*
Y780257D03*
X115166Y790297D03*
Y786950D03*
Y783604D03*
Y780257D03*
X128724Y807029D03*
Y803682D03*
Y800336D03*
Y796989D03*
Y793643D03*
X115166Y807029D03*
Y803682D03*
Y800336D03*
Y796989D03*
Y793643D03*
X128724Y820415D03*
Y817068D03*
Y813722D03*
Y810375D03*
X115166Y820415D03*
Y817068D03*
Y813722D03*
Y810375D03*
X128724Y837147D03*
Y833800D03*
Y830454D03*
Y827108D03*
Y823761D03*
X115166Y837147D03*
Y833800D03*
Y830454D03*
Y827108D03*
Y823761D03*
X128724Y850533D03*
Y847186D03*
Y843840D03*
Y840493D03*
X115166Y850533D03*
Y847186D03*
Y843840D03*
Y840493D03*
X128724Y863919D03*
Y860572D03*
Y857226D03*
Y853879D03*
X115166Y863919D03*
Y860572D03*
Y857226D03*
Y853879D03*
X128724Y880651D03*
Y877304D03*
Y873958D03*
Y870611D03*
Y867265D03*
X115166Y880651D03*
Y877304D03*
Y873958D03*
Y870611D03*
Y867265D03*
X128724Y894037D03*
Y890690D03*
Y887344D03*
Y883997D03*
X115166Y894037D03*
Y890690D03*
Y887344D03*
Y883997D03*
X128724Y910769D03*
Y907423D03*
Y904076D03*
Y900730D03*
Y897383D03*
X115166Y910769D03*
Y907423D03*
Y904076D03*
Y900730D03*
Y897383D03*
X128724Y924155D03*
Y920808D03*
Y917462D03*
Y914115D03*
X115166Y924155D03*
Y920808D03*
Y917462D03*
Y914115D03*
X128724Y940887D03*
Y937541D03*
Y934194D03*
Y930848D03*
Y927501D03*
X115166Y940887D03*
Y937541D03*
Y934194D03*
Y930848D03*
Y927501D03*
X128724Y954273D03*
Y950926D03*
Y947580D03*
Y944234D03*
X115166Y954273D03*
Y950926D03*
Y947580D03*
Y944234D03*
X128724Y971005D03*
Y967659D03*
Y964312D03*
Y960966D03*
Y957619D03*
X115166Y971005D03*
Y967659D03*
Y964312D03*
Y960966D03*
Y957619D03*
X128724Y984391D03*
Y981045D03*
Y977698D03*
Y974352D03*
X115166Y984391D03*
Y981045D03*
Y977698D03*
Y974352D03*
X128724Y1001123D03*
Y997777D03*
Y994430D03*
Y991084D03*
Y987737D03*
X115166Y1001123D03*
Y997777D03*
Y994430D03*
Y991084D03*
Y987737D03*
X128724Y1004470D03*
X115166D03*
X128724Y1027895D03*
X115166D03*
X128724Y1044627D03*
Y1041281D03*
Y1037934D03*
Y1034588D03*
Y1031241D03*
X115166Y1044627D03*
Y1041281D03*
Y1037934D03*
Y1034588D03*
Y1031241D03*
X128724Y1058013D03*
Y1054667D03*
Y1051320D03*
Y1047974D03*
X115166Y1058013D03*
Y1054667D03*
Y1051320D03*
Y1047974D03*
X128724Y1074745D03*
Y1071399D03*
Y1068052D03*
Y1064706D03*
Y1061360D03*
X115166Y1074745D03*
Y1071399D03*
Y1068052D03*
Y1064706D03*
Y1061360D03*
X128724Y1088131D03*
Y1084785D03*
Y1081438D03*
Y1078092D03*
X115166Y1088131D03*
Y1084785D03*
Y1081438D03*
Y1078092D03*
X128724Y1104863D03*
Y1101517D03*
Y1098171D03*
Y1094824D03*
Y1091478D03*
X115166Y1104863D03*
Y1101517D03*
Y1098171D03*
Y1094824D03*
Y1091478D03*
X128724Y1118249D03*
Y1114903D03*
Y1111556D03*
Y1108210D03*
X115166Y1118249D03*
Y1114903D03*
Y1111556D03*
Y1108210D03*
X128724Y1134982D03*
Y1131635D03*
Y1128289D03*
Y1124942D03*
Y1121596D03*
X115166Y1134982D03*
Y1131635D03*
Y1128289D03*
Y1124942D03*
Y1121596D03*
X128724Y1148367D03*
Y1145021D03*
Y1141675D03*
Y1138328D03*
X115166Y1148367D03*
Y1145021D03*
Y1141675D03*
Y1138328D03*
X128724Y1165100D03*
Y1161753D03*
Y1158407D03*
Y1155060D03*
Y1151714D03*
X115166Y1165100D03*
Y1161753D03*
Y1158407D03*
Y1155060D03*
Y1151714D03*
X128724Y1178486D03*
Y1175139D03*
Y1171793D03*
Y1168446D03*
X115166Y1178486D03*
Y1175139D03*
Y1171793D03*
Y1168446D03*
X128724Y1191871D03*
Y1188525D03*
Y1185178D03*
Y1181832D03*
X115166Y1191871D03*
Y1188525D03*
Y1185178D03*
Y1181832D03*
X128724Y1208604D03*
Y1205257D03*
Y1201911D03*
Y1198564D03*
Y1195218D03*
X115166Y1208604D03*
Y1205257D03*
Y1201911D03*
Y1198564D03*
Y1195218D03*
X128724Y1221989D03*
Y1218643D03*
Y1215297D03*
Y1211950D03*
X115166Y1221989D03*
Y1218643D03*
Y1215297D03*
Y1211950D03*
X128724Y1238722D03*
Y1235375D03*
Y1232029D03*
Y1228682D03*
Y1225336D03*
X115166Y1238722D03*
Y1235375D03*
Y1232029D03*
Y1228682D03*
Y1225336D03*
X128724Y1252108D03*
Y1248761D03*
Y1245415D03*
Y1242068D03*
X115166Y1252108D03*
Y1248761D03*
Y1245415D03*
Y1242068D03*
X128724Y1255454D03*
X115166D03*
X158425Y760178D03*
Y756832D03*
X144866Y760178D03*
Y756832D03*
X158425Y776911D03*
Y773564D03*
Y770218D03*
Y766871D03*
Y763525D03*
X144866Y776911D03*
Y773564D03*
Y770218D03*
Y766871D03*
Y763525D03*
X158425Y790297D03*
Y786950D03*
Y783604D03*
Y780257D03*
X144866Y790297D03*
Y786950D03*
Y783604D03*
Y780257D03*
X158425Y807029D03*
Y803682D03*
Y800336D03*
Y796989D03*
Y793643D03*
X144866Y807029D03*
Y803682D03*
Y800336D03*
Y796989D03*
Y793643D03*
X158425Y820415D03*
Y817068D03*
Y813722D03*
Y810375D03*
X144866Y820415D03*
Y817068D03*
Y813722D03*
Y810375D03*
X158425Y837147D03*
Y833800D03*
Y830454D03*
Y827108D03*
Y823761D03*
X144866Y837147D03*
Y833800D03*
Y830454D03*
Y827108D03*
Y823761D03*
X158425Y850533D03*
Y847186D03*
Y843840D03*
Y840493D03*
X144866Y850533D03*
Y847186D03*
Y843840D03*
Y840493D03*
X158425Y863919D03*
Y860572D03*
Y857226D03*
Y853879D03*
X144866Y863919D03*
Y860572D03*
Y857226D03*
Y853879D03*
X158425Y880651D03*
Y877304D03*
Y873958D03*
Y870611D03*
Y867265D03*
X144866Y880651D03*
Y877304D03*
Y873958D03*
Y870611D03*
Y867265D03*
X158425Y894037D03*
Y890690D03*
Y887344D03*
Y883997D03*
X144866Y894037D03*
Y890690D03*
Y887344D03*
Y883997D03*
X158425Y910769D03*
Y907423D03*
Y904076D03*
Y900730D03*
Y897383D03*
X144866Y910769D03*
Y907423D03*
Y904076D03*
Y900730D03*
Y897383D03*
X158425Y924155D03*
Y920808D03*
Y917462D03*
Y914115D03*
X144866Y924155D03*
Y920808D03*
Y917462D03*
Y914115D03*
X158425Y940887D03*
Y937541D03*
Y934194D03*
Y930848D03*
Y927501D03*
X144866Y940887D03*
Y937541D03*
Y934194D03*
Y930848D03*
Y927501D03*
X158425Y954273D03*
Y950926D03*
Y947580D03*
Y944234D03*
X144866Y954273D03*
Y950926D03*
Y947580D03*
Y944234D03*
X158425Y971005D03*
Y967659D03*
Y964312D03*
Y960966D03*
Y957619D03*
X144866Y971005D03*
Y967659D03*
Y964312D03*
Y960966D03*
Y957619D03*
X158425Y984391D03*
Y981045D03*
Y977698D03*
Y974352D03*
X144866Y984391D03*
Y981045D03*
Y977698D03*
Y974352D03*
X158425Y1001123D03*
Y997777D03*
Y994430D03*
Y991084D03*
Y987737D03*
X144866Y1001123D03*
Y997777D03*
Y994430D03*
Y991084D03*
Y987737D03*
X158425Y1004470D03*
X144866D03*
X158425Y1027895D03*
X144866D03*
X158425Y1044627D03*
Y1041281D03*
Y1037934D03*
Y1034588D03*
Y1031241D03*
X144866Y1044627D03*
Y1041281D03*
Y1037934D03*
Y1034588D03*
Y1031241D03*
X158425Y1058013D03*
Y1054667D03*
Y1051320D03*
Y1047974D03*
X144866Y1058013D03*
Y1054667D03*
Y1051320D03*
Y1047974D03*
X158425Y1074745D03*
Y1071399D03*
Y1068052D03*
Y1064706D03*
Y1061360D03*
X144866Y1074745D03*
Y1071399D03*
Y1068052D03*
Y1064706D03*
Y1061360D03*
X158425Y1088131D03*
Y1084785D03*
Y1081438D03*
Y1078092D03*
X144866Y1088131D03*
Y1084785D03*
Y1081438D03*
Y1078092D03*
X158425Y1104863D03*
Y1101517D03*
Y1098171D03*
Y1094824D03*
Y1091478D03*
X144866Y1104863D03*
Y1101517D03*
Y1098171D03*
Y1094824D03*
Y1091478D03*
X158425Y1118249D03*
Y1114903D03*
Y1111556D03*
Y1108210D03*
X144866Y1118249D03*
Y1114903D03*
Y1111556D03*
Y1108210D03*
X158425Y1134982D03*
Y1131635D03*
Y1128289D03*
Y1124942D03*
Y1121596D03*
X144866Y1134982D03*
Y1131635D03*
Y1128289D03*
Y1124942D03*
Y1121596D03*
X158425Y1148367D03*
Y1145021D03*
Y1141675D03*
Y1138328D03*
X144866Y1148367D03*
Y1145021D03*
Y1141675D03*
Y1138328D03*
X158425Y1165100D03*
Y1161753D03*
Y1158407D03*
Y1155060D03*
Y1151714D03*
X144866Y1165100D03*
Y1161753D03*
Y1158407D03*
Y1155060D03*
Y1151714D03*
X158425Y1178486D03*
Y1175139D03*
Y1171793D03*
Y1168446D03*
X144866Y1178486D03*
Y1175139D03*
Y1171793D03*
Y1168446D03*
X158425Y1191871D03*
Y1188525D03*
Y1185178D03*
Y1181832D03*
X144866Y1191871D03*
Y1188525D03*
Y1185178D03*
Y1181832D03*
X158425Y1208604D03*
Y1205257D03*
Y1201911D03*
Y1198564D03*
Y1195218D03*
X144866Y1208604D03*
Y1205257D03*
Y1201911D03*
Y1198564D03*
Y1195218D03*
X158425Y1221989D03*
Y1218643D03*
Y1215297D03*
Y1211950D03*
X144866Y1221989D03*
Y1218643D03*
Y1215297D03*
Y1211950D03*
X158425Y1238722D03*
Y1235375D03*
Y1232029D03*
Y1228682D03*
Y1225336D03*
X144866Y1238722D03*
Y1235375D03*
Y1232029D03*
Y1228682D03*
Y1225336D03*
X158425Y1252108D03*
Y1248761D03*
Y1245415D03*
Y1242068D03*
X144866Y1252108D03*
Y1248761D03*
Y1245415D03*
Y1242068D03*
X158425Y1255454D03*
X144866D03*
X188126Y760178D03*
Y756832D03*
X174567Y760178D03*
Y756832D03*
X188126Y776911D03*
Y773564D03*
Y770218D03*
Y766871D03*
Y763525D03*
X174567Y776911D03*
Y773564D03*
Y770218D03*
Y766871D03*
Y763525D03*
X188126Y790297D03*
Y786950D03*
Y783604D03*
Y780257D03*
X174567Y790297D03*
Y786950D03*
Y783604D03*
Y780257D03*
X188126Y807029D03*
Y803682D03*
Y800336D03*
Y796989D03*
Y793643D03*
X174567Y807029D03*
Y803682D03*
Y800336D03*
Y796989D03*
Y793643D03*
X188126Y820415D03*
Y817068D03*
Y813722D03*
Y810375D03*
X174567Y820415D03*
Y817068D03*
Y813722D03*
Y810375D03*
X188126Y837147D03*
Y833800D03*
Y830454D03*
Y827108D03*
Y823761D03*
X174567Y837147D03*
Y833800D03*
Y830454D03*
Y827108D03*
Y823761D03*
X188126Y850533D03*
Y847186D03*
Y843840D03*
Y840493D03*
X174567Y850533D03*
Y847186D03*
Y843840D03*
Y840493D03*
X188126Y863919D03*
Y860572D03*
Y857226D03*
Y853879D03*
X174567Y863919D03*
Y860572D03*
Y857226D03*
Y853879D03*
X188126Y880651D03*
Y877304D03*
Y873958D03*
Y870611D03*
Y867265D03*
X174567Y880651D03*
Y877304D03*
Y873958D03*
Y870611D03*
Y867265D03*
X188126Y894037D03*
Y890690D03*
Y887344D03*
Y883997D03*
X174567Y894037D03*
Y890690D03*
Y887344D03*
Y883997D03*
X188126Y910769D03*
Y907423D03*
Y904076D03*
Y900730D03*
Y897383D03*
X174567Y910769D03*
Y907423D03*
Y904076D03*
Y900730D03*
Y897383D03*
X188126Y924155D03*
Y920808D03*
Y917462D03*
Y914115D03*
X174567Y924155D03*
Y920808D03*
Y917462D03*
Y914115D03*
X188126Y940887D03*
Y937541D03*
Y934194D03*
Y930848D03*
Y927501D03*
X174567Y940887D03*
Y937541D03*
Y934194D03*
Y930848D03*
Y927501D03*
X188126Y954273D03*
Y950926D03*
Y947580D03*
Y944234D03*
X174567Y954273D03*
Y950926D03*
Y947580D03*
Y944234D03*
X188126Y971005D03*
Y967659D03*
Y964312D03*
Y960966D03*
Y957619D03*
X174567Y971005D03*
Y967659D03*
Y964312D03*
Y960966D03*
Y957619D03*
X188126Y984391D03*
Y981045D03*
Y977698D03*
Y974352D03*
X174567Y984391D03*
Y981045D03*
Y977698D03*
Y974352D03*
X188126Y1001123D03*
Y997777D03*
Y994430D03*
Y991084D03*
Y987737D03*
X174567Y1001123D03*
Y997777D03*
Y994430D03*
Y991084D03*
Y987737D03*
X188126Y1004470D03*
X174567D03*
X188126Y1027895D03*
X174567D03*
X188126Y1044627D03*
Y1041281D03*
Y1037934D03*
Y1034588D03*
Y1031241D03*
X174567Y1044627D03*
Y1041281D03*
Y1037934D03*
Y1034588D03*
Y1031241D03*
X188126Y1058013D03*
Y1054667D03*
Y1051320D03*
Y1047974D03*
X174567Y1058013D03*
Y1054667D03*
Y1051320D03*
Y1047974D03*
X188126Y1074745D03*
Y1071399D03*
Y1068052D03*
Y1064706D03*
Y1061360D03*
X174567Y1074745D03*
Y1071399D03*
Y1068052D03*
Y1064706D03*
Y1061360D03*
X188126Y1088131D03*
Y1084785D03*
Y1081438D03*
Y1078092D03*
X174567Y1088131D03*
Y1084785D03*
Y1081438D03*
Y1078092D03*
X188126Y1104863D03*
Y1101517D03*
Y1098171D03*
Y1094824D03*
Y1091478D03*
X174567Y1104863D03*
Y1101517D03*
Y1098171D03*
Y1094824D03*
Y1091478D03*
X188126Y1118249D03*
Y1114903D03*
Y1111556D03*
Y1108210D03*
X174567Y1118249D03*
Y1114903D03*
Y1111556D03*
Y1108210D03*
X188126Y1134982D03*
Y1131635D03*
Y1128289D03*
Y1124942D03*
Y1121596D03*
X174567Y1134982D03*
Y1131635D03*
Y1128289D03*
Y1124942D03*
Y1121596D03*
X188126Y1148367D03*
Y1145021D03*
Y1141675D03*
Y1138328D03*
X174567Y1148367D03*
Y1145021D03*
Y1141675D03*
Y1138328D03*
X188126Y1165100D03*
Y1161753D03*
Y1158407D03*
Y1155060D03*
Y1151714D03*
X174567Y1165100D03*
Y1161753D03*
Y1158407D03*
Y1155060D03*
Y1151714D03*
X188126Y1178486D03*
Y1175139D03*
Y1171793D03*
Y1168446D03*
X174567Y1178486D03*
Y1175139D03*
Y1171793D03*
Y1168446D03*
X188126Y1191871D03*
Y1188525D03*
Y1185178D03*
Y1181832D03*
X174567Y1191871D03*
Y1188525D03*
Y1185178D03*
Y1181832D03*
X188126Y1208604D03*
Y1205257D03*
Y1201911D03*
Y1198564D03*
Y1195218D03*
X174567Y1208604D03*
Y1205257D03*
Y1201911D03*
Y1198564D03*
Y1195218D03*
X188126Y1221989D03*
Y1218643D03*
Y1215297D03*
Y1211950D03*
X174567Y1221989D03*
Y1218643D03*
Y1215297D03*
Y1211950D03*
X188126Y1238722D03*
Y1235375D03*
Y1232029D03*
Y1228682D03*
Y1225336D03*
X174567Y1238722D03*
Y1235375D03*
Y1232029D03*
Y1228682D03*
Y1225336D03*
X188126Y1252108D03*
Y1248761D03*
Y1245415D03*
Y1242068D03*
X174567Y1252108D03*
Y1248761D03*
Y1245415D03*
Y1242068D03*
X188126Y1255454D03*
X174567D03*
X217827Y760178D03*
Y756832D03*
X204268Y760178D03*
Y756832D03*
X217827Y776911D03*
Y773564D03*
Y770218D03*
Y766871D03*
Y763525D03*
X204268Y776911D03*
Y773564D03*
Y770218D03*
Y766871D03*
Y763525D03*
X217827Y790297D03*
Y786950D03*
Y783604D03*
Y780257D03*
X204268Y790297D03*
Y786950D03*
Y783604D03*
Y780257D03*
X217827Y807029D03*
Y803682D03*
Y800336D03*
Y796989D03*
Y793643D03*
X204268Y807029D03*
Y803682D03*
Y800336D03*
Y796989D03*
Y793643D03*
X217827Y820415D03*
Y817068D03*
Y813722D03*
Y810375D03*
X204268Y820415D03*
Y817068D03*
Y813722D03*
Y810375D03*
X217827Y837147D03*
Y833800D03*
Y830454D03*
Y827108D03*
Y823761D03*
X204268Y837147D03*
Y833800D03*
Y830454D03*
Y827108D03*
Y823761D03*
X217827Y850533D03*
Y847186D03*
Y843840D03*
Y840493D03*
X204268Y850533D03*
Y847186D03*
Y843840D03*
Y840493D03*
X217827Y863919D03*
Y860572D03*
Y857226D03*
Y853879D03*
X204268Y863919D03*
Y860572D03*
Y857226D03*
Y853879D03*
X217827Y880651D03*
Y877304D03*
Y873958D03*
Y870611D03*
Y867265D03*
X204268Y880651D03*
Y877304D03*
Y873958D03*
Y870611D03*
Y867265D03*
X217827Y894037D03*
Y890690D03*
Y887344D03*
Y883997D03*
X204268Y894037D03*
Y890690D03*
Y887344D03*
Y883997D03*
X217827Y910769D03*
Y907423D03*
Y904076D03*
Y900730D03*
Y897383D03*
X204268Y910769D03*
Y907423D03*
Y904076D03*
Y900730D03*
Y897383D03*
X217827Y924155D03*
Y920808D03*
Y917462D03*
Y914115D03*
X204268Y924155D03*
Y920808D03*
Y917462D03*
Y914115D03*
X217827Y940887D03*
Y937541D03*
Y934194D03*
Y930848D03*
Y927501D03*
X204268Y940887D03*
Y937541D03*
Y934194D03*
Y930848D03*
Y927501D03*
X217827Y954273D03*
Y950926D03*
Y947580D03*
Y944234D03*
X204268Y954273D03*
Y950926D03*
Y947580D03*
Y944234D03*
X217827Y971005D03*
Y967659D03*
Y964312D03*
Y960966D03*
Y957619D03*
X204268Y971005D03*
Y967659D03*
Y964312D03*
Y960966D03*
Y957619D03*
X217827Y984391D03*
Y981045D03*
Y977698D03*
Y974352D03*
X204268Y984391D03*
Y981045D03*
Y977698D03*
Y974352D03*
X217827Y1001123D03*
Y997777D03*
Y994430D03*
Y991084D03*
Y987737D03*
X204268Y1001123D03*
Y997777D03*
Y994430D03*
Y991084D03*
Y987737D03*
X217827Y1004470D03*
X204268D03*
X217827Y1027895D03*
X204268D03*
X217827Y1044627D03*
Y1041281D03*
Y1037934D03*
Y1034588D03*
Y1031241D03*
X204268Y1044627D03*
Y1041281D03*
Y1037934D03*
Y1034588D03*
Y1031241D03*
X217827Y1058013D03*
Y1054667D03*
Y1051320D03*
Y1047974D03*
X204268Y1058013D03*
Y1054667D03*
Y1051320D03*
Y1047974D03*
X217827Y1074745D03*
Y1071399D03*
Y1068052D03*
Y1064706D03*
Y1061360D03*
X204268Y1074745D03*
Y1071399D03*
Y1068052D03*
Y1064706D03*
Y1061360D03*
X217827Y1088131D03*
Y1084785D03*
Y1081438D03*
Y1078092D03*
X204268Y1088131D03*
Y1084785D03*
Y1081438D03*
Y1078092D03*
X217827Y1104863D03*
Y1101517D03*
Y1098171D03*
Y1094824D03*
Y1091478D03*
X204268Y1104863D03*
Y1101517D03*
Y1098171D03*
Y1094824D03*
Y1091478D03*
X217827Y1118249D03*
Y1114903D03*
Y1111556D03*
Y1108210D03*
X204268Y1118249D03*
Y1114903D03*
Y1111556D03*
Y1108210D03*
X217827Y1134982D03*
Y1131635D03*
Y1128289D03*
Y1124942D03*
Y1121596D03*
X204268Y1134982D03*
Y1131635D03*
Y1128289D03*
Y1124942D03*
Y1121596D03*
X217827Y1148367D03*
Y1145021D03*
Y1141675D03*
Y1138328D03*
X204268Y1148367D03*
Y1145021D03*
Y1141675D03*
Y1138328D03*
X217827Y1165100D03*
Y1161753D03*
Y1158407D03*
Y1155060D03*
Y1151714D03*
X204268Y1165100D03*
Y1161753D03*
Y1158407D03*
Y1155060D03*
Y1151714D03*
X217827Y1178486D03*
Y1175139D03*
Y1171793D03*
Y1168446D03*
X204268Y1178486D03*
Y1175139D03*
Y1171793D03*
Y1168446D03*
X217827Y1191871D03*
Y1188525D03*
Y1185178D03*
Y1181832D03*
X204268Y1191871D03*
Y1188525D03*
Y1185178D03*
Y1181832D03*
X217827Y1208604D03*
Y1205257D03*
Y1201911D03*
Y1198564D03*
Y1195218D03*
X204268Y1208604D03*
Y1205257D03*
Y1201911D03*
Y1198564D03*
Y1195218D03*
X217827Y1221989D03*
Y1218643D03*
Y1215297D03*
Y1211950D03*
X204268Y1221989D03*
Y1218643D03*
Y1215297D03*
Y1211950D03*
X217827Y1238722D03*
Y1235375D03*
Y1232029D03*
Y1228682D03*
Y1225336D03*
X204268Y1238722D03*
Y1235375D03*
Y1232029D03*
Y1228682D03*
Y1225336D03*
X217827Y1252108D03*
Y1248761D03*
Y1245415D03*
Y1242068D03*
X204268Y1252108D03*
Y1248761D03*
Y1245415D03*
Y1242068D03*
X217827Y1255454D03*
X204268D03*
X233969Y760178D03*
Y756832D03*
Y776911D03*
Y773564D03*
Y770218D03*
Y766871D03*
Y763525D03*
Y790297D03*
Y786950D03*
Y783604D03*
Y780257D03*
Y807029D03*
Y803682D03*
Y800336D03*
Y796989D03*
Y793643D03*
Y820415D03*
Y817068D03*
Y813722D03*
Y810375D03*
Y837147D03*
Y833800D03*
Y830454D03*
Y827108D03*
Y823761D03*
Y850533D03*
Y847186D03*
Y843840D03*
Y840493D03*
Y863919D03*
Y860572D03*
Y857226D03*
Y853879D03*
Y880651D03*
Y877304D03*
Y873958D03*
Y870611D03*
Y867265D03*
Y894037D03*
Y890690D03*
Y887344D03*
Y883997D03*
Y910769D03*
Y907423D03*
Y904076D03*
Y900730D03*
Y897383D03*
Y924155D03*
Y920808D03*
Y917462D03*
Y914115D03*
Y940887D03*
Y937541D03*
Y934194D03*
Y930848D03*
Y927501D03*
Y954273D03*
Y950926D03*
Y947580D03*
Y944234D03*
Y971005D03*
Y967659D03*
Y964312D03*
Y960966D03*
Y957619D03*
Y984391D03*
Y981045D03*
Y977698D03*
Y974352D03*
Y1001123D03*
Y997777D03*
Y994430D03*
Y991084D03*
Y987737D03*
Y1004470D03*
Y1027895D03*
Y1044627D03*
Y1041281D03*
Y1037934D03*
Y1034588D03*
Y1031241D03*
Y1058013D03*
Y1054667D03*
Y1051320D03*
Y1047974D03*
Y1074745D03*
Y1071399D03*
Y1068052D03*
Y1064706D03*
Y1061360D03*
Y1088131D03*
Y1084785D03*
Y1081438D03*
Y1078092D03*
Y1104863D03*
Y1101517D03*
Y1098171D03*
Y1094824D03*
Y1091478D03*
Y1118249D03*
Y1114903D03*
Y1111556D03*
Y1108210D03*
Y1134982D03*
Y1131635D03*
Y1128289D03*
Y1124942D03*
Y1121596D03*
Y1148367D03*
Y1145021D03*
Y1141675D03*
Y1138328D03*
Y1165100D03*
Y1161753D03*
Y1158407D03*
Y1155060D03*
Y1151714D03*
Y1178486D03*
Y1175139D03*
Y1171793D03*
Y1168446D03*
Y1191871D03*
Y1188525D03*
Y1185178D03*
Y1181832D03*
Y1208604D03*
Y1205257D03*
Y1201911D03*
Y1198564D03*
Y1195218D03*
Y1221989D03*
Y1218643D03*
Y1215297D03*
Y1211950D03*
Y1238722D03*
Y1235375D03*
Y1232029D03*
Y1228682D03*
Y1225336D03*
Y1252108D03*
Y1248761D03*
Y1245415D03*
Y1242068D03*
Y1255454D03*
X647354Y760178D03*
Y756832D03*
Y776911D03*
Y773564D03*
Y770218D03*
Y766871D03*
Y763525D03*
Y790297D03*
Y786950D03*
Y783604D03*
Y780257D03*
Y807029D03*
Y803682D03*
Y800336D03*
Y796989D03*
Y793643D03*
Y820415D03*
Y817068D03*
Y813722D03*
Y810375D03*
Y837147D03*
Y833800D03*
Y830454D03*
Y827108D03*
Y823761D03*
Y850533D03*
Y847186D03*
Y843840D03*
Y840493D03*
Y863919D03*
Y860572D03*
Y857226D03*
Y853879D03*
Y880651D03*
Y877304D03*
Y873958D03*
Y870611D03*
Y867265D03*
Y894037D03*
Y890690D03*
Y887344D03*
Y883997D03*
Y910769D03*
Y907423D03*
Y904076D03*
Y900730D03*
Y897383D03*
Y924155D03*
Y920808D03*
Y917462D03*
Y914115D03*
Y940887D03*
Y937541D03*
Y934194D03*
Y930848D03*
Y927501D03*
Y954273D03*
Y950926D03*
Y947580D03*
Y944234D03*
Y971005D03*
Y967659D03*
Y964312D03*
Y960966D03*
Y957619D03*
Y984391D03*
Y981045D03*
Y977698D03*
Y974352D03*
Y1001123D03*
Y997777D03*
Y994430D03*
Y991084D03*
Y987737D03*
Y1004470D03*
Y1027895D03*
Y1044627D03*
Y1041281D03*
Y1037934D03*
Y1034588D03*
Y1031241D03*
Y1058013D03*
Y1054667D03*
Y1051320D03*
Y1047974D03*
Y1074745D03*
Y1071399D03*
Y1068052D03*
Y1064706D03*
Y1061360D03*
Y1088131D03*
Y1084785D03*
Y1081438D03*
Y1078092D03*
Y1104863D03*
Y1101517D03*
Y1098171D03*
Y1094824D03*
Y1091478D03*
Y1118249D03*
Y1114903D03*
Y1111556D03*
Y1108210D03*
Y1134982D03*
Y1131635D03*
Y1128289D03*
Y1124942D03*
Y1121596D03*
Y1148367D03*
Y1145021D03*
Y1141675D03*
Y1138328D03*
Y1165100D03*
Y1161753D03*
Y1158407D03*
Y1155060D03*
Y1151714D03*
Y1178486D03*
Y1175139D03*
Y1171793D03*
Y1168446D03*
Y1191871D03*
Y1188525D03*
Y1185178D03*
Y1181832D03*
Y1208604D03*
Y1205257D03*
Y1201911D03*
Y1198564D03*
Y1195218D03*
Y1221989D03*
Y1218643D03*
Y1215297D03*
Y1211950D03*
Y1238722D03*
Y1235375D03*
Y1232029D03*
Y1228682D03*
Y1225336D03*
Y1252108D03*
Y1248761D03*
Y1245415D03*
Y1242068D03*
Y1255454D03*
X663496Y760178D03*
Y756832D03*
Y776911D03*
Y773564D03*
Y770218D03*
Y766871D03*
Y763525D03*
Y790297D03*
Y786950D03*
Y783604D03*
Y780257D03*
Y807029D03*
Y803682D03*
Y800336D03*
Y796989D03*
Y793643D03*
Y820415D03*
Y817068D03*
Y813722D03*
Y810375D03*
Y837147D03*
Y833800D03*
Y830454D03*
Y827108D03*
Y823761D03*
Y850533D03*
Y847186D03*
Y843840D03*
Y840493D03*
Y863919D03*
Y860572D03*
Y857226D03*
Y853879D03*
Y880651D03*
Y877304D03*
Y873958D03*
Y870611D03*
Y867265D03*
Y894037D03*
Y890690D03*
Y887344D03*
Y883997D03*
Y910769D03*
Y907423D03*
Y904076D03*
Y900730D03*
Y897383D03*
Y924155D03*
Y920808D03*
Y917462D03*
Y914115D03*
Y940887D03*
Y937541D03*
Y934194D03*
Y930848D03*
Y927501D03*
Y954273D03*
Y950926D03*
Y947580D03*
Y944234D03*
Y971005D03*
Y967659D03*
Y964312D03*
Y960966D03*
Y957619D03*
Y984391D03*
Y981045D03*
Y977698D03*
Y974352D03*
Y1001123D03*
Y997777D03*
Y994430D03*
Y991084D03*
Y987737D03*
Y1004470D03*
Y1027895D03*
Y1044627D03*
Y1041281D03*
Y1037934D03*
Y1034588D03*
Y1031241D03*
Y1058013D03*
Y1054667D03*
Y1051320D03*
Y1047974D03*
Y1074745D03*
Y1071399D03*
Y1068052D03*
Y1064706D03*
Y1061360D03*
Y1088131D03*
Y1084785D03*
Y1081438D03*
Y1078092D03*
Y1104863D03*
Y1101517D03*
Y1098171D03*
Y1094824D03*
Y1091478D03*
Y1118249D03*
Y1114903D03*
Y1111556D03*
Y1108210D03*
Y1134982D03*
Y1131635D03*
Y1128289D03*
Y1124942D03*
Y1121596D03*
Y1148367D03*
Y1145021D03*
Y1141675D03*
Y1138328D03*
Y1165100D03*
Y1161753D03*
Y1158407D03*
Y1155060D03*
Y1151714D03*
Y1178486D03*
Y1175139D03*
Y1171793D03*
Y1168446D03*
Y1191871D03*
Y1188525D03*
Y1185178D03*
Y1181832D03*
Y1208604D03*
Y1205257D03*
Y1201911D03*
Y1198564D03*
Y1195218D03*
Y1221989D03*
Y1218643D03*
Y1215297D03*
Y1211950D03*
Y1238722D03*
Y1235375D03*
Y1232029D03*
Y1228682D03*
Y1225336D03*
Y1252108D03*
Y1248761D03*
Y1245415D03*
Y1242068D03*
Y1255454D03*
X677055Y760178D03*
Y756832D03*
Y776911D03*
Y773564D03*
Y770218D03*
Y766871D03*
Y763525D03*
Y790297D03*
Y786950D03*
Y783604D03*
Y780257D03*
Y807029D03*
Y803682D03*
Y800336D03*
Y796989D03*
Y793643D03*
Y820415D03*
Y817068D03*
Y813722D03*
Y810375D03*
Y837147D03*
Y833800D03*
Y830454D03*
Y827108D03*
Y823761D03*
Y850533D03*
Y847186D03*
Y843840D03*
Y840493D03*
Y863919D03*
Y860572D03*
Y857226D03*
Y853879D03*
Y880651D03*
Y877304D03*
Y873958D03*
Y870611D03*
Y867265D03*
Y894037D03*
Y890690D03*
Y887344D03*
Y883997D03*
Y910769D03*
Y907423D03*
Y904076D03*
Y900730D03*
Y897383D03*
Y924155D03*
Y920808D03*
Y917462D03*
Y914115D03*
Y940887D03*
Y937541D03*
Y934194D03*
Y930848D03*
Y927501D03*
Y954273D03*
Y950926D03*
Y947580D03*
Y944234D03*
Y971005D03*
Y967659D03*
Y964312D03*
Y960966D03*
Y957619D03*
Y984391D03*
Y981045D03*
Y977698D03*
Y974352D03*
Y1001123D03*
Y997777D03*
Y994430D03*
Y991084D03*
Y987737D03*
Y1004470D03*
Y1027895D03*
Y1044627D03*
Y1041281D03*
Y1037934D03*
Y1034588D03*
Y1031241D03*
Y1058013D03*
Y1054667D03*
Y1051320D03*
Y1047974D03*
Y1074745D03*
Y1071399D03*
Y1068052D03*
Y1064706D03*
Y1061360D03*
Y1088131D03*
Y1084785D03*
Y1081438D03*
Y1078092D03*
Y1104863D03*
Y1101517D03*
Y1098171D03*
Y1094824D03*
Y1091478D03*
Y1118249D03*
Y1114903D03*
Y1111556D03*
Y1108210D03*
Y1134982D03*
Y1131635D03*
Y1128289D03*
Y1124942D03*
Y1121596D03*
Y1148367D03*
Y1145021D03*
Y1141675D03*
Y1138328D03*
Y1165100D03*
Y1161753D03*
Y1158407D03*
Y1155060D03*
Y1151714D03*
Y1178486D03*
Y1175139D03*
Y1171793D03*
Y1168446D03*
Y1191871D03*
Y1188525D03*
Y1185178D03*
Y1181832D03*
Y1208604D03*
Y1205257D03*
Y1201911D03*
Y1198564D03*
Y1195218D03*
Y1221989D03*
Y1218643D03*
Y1215297D03*
Y1211950D03*
Y1238722D03*
Y1235375D03*
Y1232029D03*
Y1228682D03*
Y1225336D03*
Y1252108D03*
Y1248761D03*
Y1245415D03*
Y1242068D03*
Y1255454D03*
X693197Y760178D03*
Y756832D03*
Y776911D03*
Y773564D03*
Y770218D03*
Y766871D03*
Y763525D03*
Y790297D03*
Y786950D03*
Y783604D03*
Y780257D03*
Y807029D03*
Y803682D03*
Y800336D03*
Y796989D03*
Y793643D03*
Y820415D03*
Y817068D03*
Y813722D03*
Y810375D03*
Y837147D03*
Y833800D03*
Y830454D03*
Y827108D03*
Y823761D03*
Y850533D03*
Y847186D03*
Y843840D03*
Y840493D03*
Y863919D03*
Y860572D03*
Y857226D03*
Y853879D03*
Y880651D03*
Y877304D03*
Y873958D03*
Y870611D03*
Y867265D03*
Y894037D03*
Y890690D03*
Y887344D03*
Y883997D03*
Y910769D03*
Y907423D03*
Y904076D03*
Y900730D03*
Y897383D03*
Y924155D03*
Y920808D03*
Y917462D03*
Y914115D03*
Y940887D03*
Y937541D03*
Y934194D03*
Y930848D03*
Y927501D03*
Y954273D03*
Y950926D03*
Y947580D03*
Y944234D03*
Y971005D03*
Y967659D03*
Y964312D03*
Y960966D03*
Y957619D03*
Y984391D03*
Y981045D03*
Y977698D03*
Y974352D03*
Y1001123D03*
Y997777D03*
Y994430D03*
Y991084D03*
Y987737D03*
Y1004470D03*
Y1027895D03*
Y1044627D03*
Y1041281D03*
Y1037934D03*
Y1034588D03*
Y1031241D03*
Y1058013D03*
Y1054667D03*
Y1051320D03*
Y1047974D03*
Y1074745D03*
Y1071399D03*
Y1068052D03*
Y1064706D03*
Y1061360D03*
Y1088131D03*
Y1084785D03*
Y1081438D03*
Y1078092D03*
Y1104863D03*
Y1101517D03*
Y1098171D03*
Y1094824D03*
Y1091478D03*
Y1118249D03*
Y1114903D03*
Y1111556D03*
Y1108210D03*
Y1134982D03*
Y1131635D03*
Y1128289D03*
Y1124942D03*
Y1121596D03*
Y1148367D03*
Y1145021D03*
Y1141675D03*
Y1138328D03*
Y1165100D03*
Y1161753D03*
Y1158407D03*
Y1155060D03*
Y1151714D03*
Y1178486D03*
Y1175139D03*
Y1171793D03*
Y1168446D03*
Y1191871D03*
Y1188525D03*
Y1185178D03*
Y1181832D03*
Y1208604D03*
Y1205257D03*
Y1201911D03*
Y1198564D03*
Y1195218D03*
Y1221989D03*
Y1218643D03*
Y1215297D03*
Y1211950D03*
Y1238722D03*
Y1235375D03*
Y1232029D03*
Y1228682D03*
Y1225336D03*
Y1252108D03*
Y1248761D03*
Y1245415D03*
Y1242068D03*
Y1255454D03*
X706756Y760178D03*
Y756832D03*
Y776911D03*
Y773564D03*
Y770218D03*
Y766871D03*
Y763525D03*
Y790297D03*
Y786950D03*
Y783604D03*
Y780257D03*
Y807029D03*
Y803682D03*
Y800336D03*
Y796989D03*
Y793643D03*
Y820415D03*
Y817068D03*
Y813722D03*
Y810375D03*
Y837147D03*
Y833800D03*
Y830454D03*
Y827108D03*
Y823761D03*
Y850533D03*
Y847186D03*
Y843840D03*
Y840493D03*
Y863919D03*
Y860572D03*
Y857226D03*
Y853879D03*
Y880651D03*
Y877304D03*
Y873958D03*
Y870611D03*
Y867265D03*
Y894037D03*
Y890690D03*
Y887344D03*
Y883997D03*
Y910769D03*
Y907423D03*
Y904076D03*
Y900730D03*
Y897383D03*
Y924155D03*
Y920808D03*
Y917462D03*
Y914115D03*
Y940887D03*
Y937541D03*
Y934194D03*
Y930848D03*
Y927501D03*
Y954273D03*
Y950926D03*
Y947580D03*
Y944234D03*
Y971005D03*
Y967659D03*
Y964312D03*
Y960966D03*
Y957619D03*
Y984391D03*
Y981045D03*
Y977698D03*
Y974352D03*
Y1001123D03*
Y997777D03*
Y994430D03*
Y991084D03*
Y987737D03*
Y1004470D03*
Y1027895D03*
Y1044627D03*
Y1041281D03*
Y1037934D03*
Y1034588D03*
Y1031241D03*
Y1058013D03*
Y1054667D03*
Y1051320D03*
Y1047974D03*
Y1074745D03*
Y1071399D03*
Y1068052D03*
Y1064706D03*
Y1061360D03*
Y1088131D03*
Y1084785D03*
Y1081438D03*
Y1078092D03*
Y1104863D03*
Y1101517D03*
Y1098171D03*
Y1094824D03*
Y1091478D03*
Y1118249D03*
Y1114903D03*
Y1111556D03*
Y1108210D03*
Y1134982D03*
Y1131635D03*
Y1128289D03*
Y1124942D03*
Y1121596D03*
Y1148367D03*
Y1145021D03*
Y1141675D03*
Y1138328D03*
Y1165100D03*
Y1161753D03*
Y1158407D03*
Y1155060D03*
Y1151714D03*
Y1178486D03*
Y1175139D03*
Y1171793D03*
Y1168446D03*
Y1191871D03*
Y1188525D03*
Y1185178D03*
Y1181832D03*
Y1208604D03*
Y1205257D03*
Y1201911D03*
Y1198564D03*
Y1195218D03*
Y1221989D03*
Y1218643D03*
Y1215297D03*
Y1211950D03*
Y1238722D03*
Y1235375D03*
Y1232029D03*
Y1228682D03*
Y1225336D03*
Y1252108D03*
Y1248761D03*
Y1245415D03*
Y1242068D03*
Y1255454D03*
X722898Y760178D03*
Y756832D03*
Y776911D03*
Y773564D03*
Y770218D03*
Y766871D03*
Y763525D03*
Y790297D03*
Y786950D03*
Y783604D03*
Y780257D03*
Y807029D03*
Y803682D03*
Y800336D03*
Y796989D03*
Y793643D03*
Y820415D03*
Y817068D03*
Y813722D03*
Y810375D03*
Y837147D03*
Y833800D03*
Y830454D03*
Y827108D03*
Y823761D03*
Y850533D03*
Y847186D03*
Y843840D03*
Y840493D03*
Y863919D03*
Y860572D03*
Y857226D03*
Y853879D03*
Y880651D03*
Y877304D03*
Y873958D03*
Y870611D03*
Y867265D03*
Y894037D03*
Y890690D03*
Y887344D03*
Y883997D03*
Y910769D03*
Y907423D03*
Y904076D03*
Y900730D03*
Y897383D03*
Y924155D03*
Y920808D03*
Y917462D03*
Y914115D03*
Y940887D03*
Y937541D03*
Y934194D03*
Y930848D03*
Y927501D03*
Y954273D03*
Y950926D03*
Y947580D03*
Y944234D03*
Y971005D03*
Y967659D03*
Y964312D03*
Y960966D03*
Y957619D03*
Y984391D03*
Y981045D03*
Y977698D03*
Y974352D03*
Y1001123D03*
Y997777D03*
Y994430D03*
Y991084D03*
Y987737D03*
Y1004470D03*
Y1027895D03*
Y1044627D03*
Y1041281D03*
Y1037934D03*
Y1034588D03*
Y1031241D03*
Y1058013D03*
Y1054667D03*
Y1051320D03*
Y1047974D03*
Y1074745D03*
Y1071399D03*
Y1068052D03*
Y1064706D03*
Y1061360D03*
Y1088131D03*
Y1084785D03*
Y1081438D03*
Y1078092D03*
Y1104863D03*
Y1101517D03*
Y1098171D03*
Y1094824D03*
Y1091478D03*
Y1118249D03*
Y1114903D03*
Y1111556D03*
Y1108210D03*
Y1134982D03*
Y1131635D03*
Y1128289D03*
Y1124942D03*
Y1121596D03*
Y1148367D03*
Y1145021D03*
Y1141675D03*
Y1138328D03*
Y1165100D03*
Y1161753D03*
Y1158407D03*
Y1155060D03*
Y1151714D03*
Y1178486D03*
Y1175139D03*
Y1171793D03*
Y1168446D03*
Y1191871D03*
Y1188525D03*
Y1185178D03*
Y1181832D03*
Y1208604D03*
Y1205257D03*
Y1201911D03*
Y1198564D03*
Y1195218D03*
Y1221989D03*
Y1218643D03*
Y1215297D03*
Y1211950D03*
Y1238722D03*
Y1235375D03*
Y1232029D03*
Y1228682D03*
Y1225336D03*
Y1252108D03*
Y1248761D03*
Y1245415D03*
Y1242068D03*
Y1255454D03*
X736457Y760178D03*
Y756832D03*
Y776911D03*
Y773564D03*
Y770218D03*
Y766871D03*
Y763525D03*
Y790297D03*
Y786950D03*
Y783604D03*
Y780257D03*
Y807029D03*
Y803682D03*
Y800336D03*
Y796989D03*
Y793643D03*
Y820415D03*
Y817068D03*
Y813722D03*
Y810375D03*
Y837147D03*
Y833800D03*
Y830454D03*
Y827108D03*
Y823761D03*
Y850533D03*
Y847186D03*
Y843840D03*
Y840493D03*
Y863919D03*
Y860572D03*
Y857226D03*
Y853879D03*
Y880651D03*
Y877304D03*
Y873958D03*
Y870611D03*
Y867265D03*
Y894037D03*
Y890690D03*
Y887344D03*
Y883997D03*
Y910769D03*
Y907423D03*
Y904076D03*
Y900730D03*
Y897383D03*
Y924155D03*
Y920808D03*
Y917462D03*
Y914115D03*
Y940887D03*
Y937541D03*
Y934194D03*
Y930848D03*
Y927501D03*
Y954273D03*
Y950926D03*
Y947580D03*
Y944234D03*
Y971005D03*
Y967659D03*
Y964312D03*
Y960966D03*
Y957619D03*
Y984391D03*
Y981045D03*
Y977698D03*
Y974352D03*
Y1001123D03*
Y997777D03*
Y994430D03*
Y991084D03*
Y987737D03*
Y1004470D03*
Y1027895D03*
Y1044627D03*
Y1041281D03*
Y1037934D03*
Y1034588D03*
Y1031241D03*
Y1058013D03*
Y1054667D03*
Y1051320D03*
Y1047974D03*
Y1074745D03*
Y1071399D03*
Y1068052D03*
Y1064706D03*
Y1061360D03*
Y1088131D03*
Y1084785D03*
Y1081438D03*
Y1078092D03*
Y1104863D03*
Y1101517D03*
Y1098171D03*
Y1094824D03*
Y1091478D03*
Y1118249D03*
Y1114903D03*
Y1111556D03*
Y1108210D03*
Y1134982D03*
Y1131635D03*
Y1128289D03*
Y1124942D03*
Y1121596D03*
Y1148367D03*
Y1145021D03*
Y1141675D03*
Y1138328D03*
Y1165100D03*
Y1161753D03*
Y1158407D03*
Y1155060D03*
Y1151714D03*
Y1178486D03*
Y1175139D03*
Y1171793D03*
Y1168446D03*
Y1191871D03*
Y1188525D03*
Y1185178D03*
Y1181832D03*
Y1208604D03*
Y1205257D03*
Y1201911D03*
Y1198564D03*
Y1195218D03*
Y1221989D03*
Y1218643D03*
Y1215297D03*
Y1211950D03*
Y1238722D03*
Y1235375D03*
Y1232029D03*
Y1228682D03*
Y1225336D03*
Y1252108D03*
Y1248761D03*
Y1245415D03*
Y1242068D03*
Y1255454D03*
X752599Y760178D03*
Y756832D03*
Y776911D03*
Y773564D03*
Y770218D03*
Y766871D03*
Y763525D03*
Y790297D03*
Y786950D03*
Y783604D03*
Y780257D03*
Y807029D03*
Y803682D03*
Y800336D03*
Y796989D03*
Y793643D03*
Y820415D03*
Y817068D03*
Y813722D03*
Y810375D03*
Y837147D03*
Y833800D03*
Y830454D03*
Y827108D03*
Y823761D03*
Y850533D03*
Y847186D03*
Y843840D03*
Y840493D03*
Y863919D03*
Y860572D03*
Y857226D03*
Y853879D03*
Y880651D03*
Y877304D03*
Y873958D03*
Y870611D03*
Y867265D03*
Y894037D03*
Y890690D03*
Y887344D03*
Y883997D03*
Y910769D03*
Y907423D03*
Y904076D03*
Y900730D03*
Y897383D03*
Y924155D03*
Y920808D03*
Y917462D03*
Y914115D03*
Y940887D03*
Y937541D03*
Y934194D03*
Y930848D03*
Y927501D03*
Y954273D03*
Y950926D03*
Y947580D03*
Y944234D03*
Y971005D03*
Y967659D03*
Y964312D03*
Y960966D03*
Y957619D03*
Y984391D03*
Y981045D03*
Y977698D03*
Y974352D03*
Y1001123D03*
Y997777D03*
Y994430D03*
Y991084D03*
Y987737D03*
Y1004470D03*
Y1027895D03*
Y1044627D03*
Y1041281D03*
Y1037934D03*
Y1034588D03*
Y1031241D03*
Y1058013D03*
Y1054667D03*
Y1051320D03*
Y1047974D03*
Y1074745D03*
Y1071399D03*
Y1068052D03*
Y1064706D03*
Y1061360D03*
Y1088131D03*
Y1084785D03*
Y1081438D03*
Y1078092D03*
Y1104863D03*
Y1101517D03*
Y1098171D03*
Y1094824D03*
Y1091478D03*
Y1118249D03*
Y1114903D03*
Y1111556D03*
Y1108210D03*
Y1134982D03*
Y1131635D03*
Y1128289D03*
Y1124942D03*
Y1121596D03*
Y1148367D03*
Y1145021D03*
Y1141675D03*
Y1138328D03*
Y1165100D03*
Y1161753D03*
Y1158407D03*
Y1155060D03*
Y1151714D03*
Y1178486D03*
Y1175139D03*
Y1171793D03*
Y1168446D03*
Y1191871D03*
Y1188525D03*
Y1185178D03*
Y1181832D03*
Y1208604D03*
Y1205257D03*
Y1201911D03*
Y1198564D03*
Y1195218D03*
Y1221989D03*
Y1218643D03*
Y1215297D03*
Y1211950D03*
Y1238722D03*
Y1235375D03*
Y1232029D03*
Y1228682D03*
Y1225336D03*
Y1252108D03*
Y1248761D03*
Y1245415D03*
Y1242068D03*
Y1255454D03*
X766158Y760178D03*
Y756832D03*
Y776911D03*
Y773564D03*
Y770218D03*
Y766871D03*
Y763525D03*
Y790297D03*
Y786950D03*
Y783604D03*
Y780257D03*
Y807029D03*
Y803682D03*
Y800336D03*
Y796989D03*
Y793643D03*
Y820415D03*
Y817068D03*
Y813722D03*
Y810375D03*
Y837147D03*
Y833800D03*
Y830454D03*
Y827108D03*
Y823761D03*
Y850533D03*
Y847186D03*
Y843840D03*
Y840493D03*
Y863919D03*
Y860572D03*
Y857226D03*
Y853879D03*
Y880651D03*
Y877304D03*
Y873958D03*
Y870611D03*
Y867265D03*
Y894037D03*
Y890690D03*
Y887344D03*
Y883997D03*
Y910769D03*
Y907423D03*
Y904076D03*
Y900730D03*
Y897383D03*
Y924155D03*
Y920808D03*
Y917462D03*
Y914115D03*
Y940887D03*
Y937541D03*
Y934194D03*
Y930848D03*
Y927501D03*
Y954273D03*
Y950926D03*
Y947580D03*
Y944234D03*
Y971005D03*
Y967659D03*
Y964312D03*
Y960966D03*
Y957619D03*
Y984391D03*
Y981045D03*
Y977698D03*
Y974352D03*
Y1001123D03*
Y997777D03*
Y994430D03*
Y991084D03*
Y987737D03*
Y1004470D03*
Y1027895D03*
Y1044627D03*
Y1041281D03*
Y1037934D03*
Y1034588D03*
Y1031241D03*
Y1058013D03*
Y1054667D03*
Y1051320D03*
Y1047974D03*
Y1074745D03*
Y1071399D03*
Y1068052D03*
Y1064706D03*
Y1061360D03*
Y1088131D03*
Y1084785D03*
Y1081438D03*
Y1078092D03*
Y1104863D03*
Y1101517D03*
Y1098171D03*
Y1094824D03*
Y1091478D03*
Y1118249D03*
Y1114903D03*
Y1111556D03*
Y1108210D03*
Y1134982D03*
Y1131635D03*
Y1128289D03*
Y1124942D03*
Y1121596D03*
Y1148367D03*
Y1145021D03*
Y1141675D03*
Y1138328D03*
Y1165100D03*
Y1161753D03*
Y1158407D03*
Y1155060D03*
Y1151714D03*
Y1178486D03*
Y1175139D03*
Y1171793D03*
Y1168446D03*
Y1191871D03*
Y1188525D03*
Y1185178D03*
Y1181832D03*
Y1208604D03*
Y1205257D03*
Y1201911D03*
Y1198564D03*
Y1195218D03*
Y1221989D03*
Y1218643D03*
Y1215297D03*
Y1211950D03*
Y1238722D03*
Y1235375D03*
Y1232029D03*
Y1228682D03*
Y1225336D03*
Y1252108D03*
Y1248761D03*
Y1245415D03*
Y1242068D03*
Y1255454D03*
X782300Y760178D03*
Y756832D03*
Y776911D03*
Y773564D03*
Y770218D03*
Y766871D03*
Y763525D03*
Y790297D03*
Y786950D03*
Y783604D03*
Y780257D03*
Y807029D03*
Y803682D03*
Y800336D03*
Y796989D03*
Y793643D03*
Y820415D03*
Y817068D03*
Y813722D03*
Y810375D03*
Y837147D03*
Y833800D03*
Y830454D03*
Y827108D03*
Y823761D03*
Y850533D03*
Y847186D03*
Y843840D03*
Y840493D03*
Y863919D03*
Y860572D03*
Y857226D03*
Y853879D03*
Y880651D03*
Y877304D03*
Y873958D03*
Y870611D03*
Y867265D03*
Y894037D03*
Y890690D03*
Y887344D03*
Y883997D03*
Y910769D03*
Y907423D03*
Y904076D03*
Y900730D03*
Y897383D03*
Y924155D03*
Y920808D03*
Y917462D03*
Y914115D03*
Y940887D03*
Y937541D03*
Y934194D03*
Y930848D03*
Y927501D03*
Y954273D03*
Y950926D03*
Y947580D03*
Y944234D03*
Y971005D03*
Y967659D03*
Y964312D03*
Y960966D03*
Y957619D03*
Y984391D03*
Y981045D03*
Y977698D03*
Y974352D03*
Y1001123D03*
Y997777D03*
Y994430D03*
Y991084D03*
Y987737D03*
Y1004470D03*
Y1027895D03*
Y1044627D03*
Y1041281D03*
Y1037934D03*
Y1034588D03*
Y1031241D03*
Y1058013D03*
Y1054667D03*
Y1051320D03*
Y1047974D03*
Y1074745D03*
Y1071399D03*
Y1068052D03*
Y1064706D03*
Y1061360D03*
Y1088131D03*
Y1084785D03*
Y1081438D03*
Y1078092D03*
Y1104863D03*
Y1101517D03*
Y1098171D03*
Y1094824D03*
Y1091478D03*
Y1118249D03*
Y1114903D03*
Y1111556D03*
Y1108210D03*
Y1134982D03*
Y1131635D03*
Y1128289D03*
Y1124942D03*
Y1121596D03*
Y1148367D03*
Y1145021D03*
Y1141675D03*
Y1138328D03*
Y1165100D03*
Y1161753D03*
Y1158407D03*
Y1155060D03*
Y1151714D03*
Y1178486D03*
Y1175139D03*
Y1171793D03*
Y1168446D03*
Y1191871D03*
Y1188525D03*
Y1185178D03*
Y1181832D03*
Y1208604D03*
Y1205257D03*
Y1201911D03*
Y1198564D03*
Y1195218D03*
Y1221989D03*
Y1218643D03*
Y1215297D03*
Y1211950D03*
Y1238722D03*
Y1235375D03*
Y1232029D03*
Y1228682D03*
Y1225336D03*
Y1252108D03*
Y1248761D03*
Y1245415D03*
Y1242068D03*
Y1255454D03*
X795858Y760178D03*
Y756832D03*
Y776911D03*
Y773564D03*
Y770218D03*
Y766871D03*
Y763525D03*
Y790297D03*
Y786950D03*
Y783604D03*
Y780257D03*
Y807029D03*
Y803682D03*
Y800336D03*
Y796989D03*
Y793643D03*
Y820415D03*
Y817068D03*
Y813722D03*
Y810375D03*
Y837147D03*
Y833800D03*
Y830454D03*
Y827108D03*
Y823761D03*
Y850533D03*
Y847186D03*
Y843840D03*
Y840493D03*
Y863919D03*
Y860572D03*
Y857226D03*
Y853879D03*
Y880651D03*
Y877304D03*
Y873958D03*
Y870611D03*
Y867265D03*
Y894037D03*
Y890690D03*
Y887344D03*
Y883997D03*
Y910769D03*
Y907423D03*
Y904076D03*
Y900730D03*
Y897383D03*
Y924155D03*
Y920808D03*
Y917462D03*
Y914115D03*
Y940887D03*
Y937541D03*
Y934194D03*
Y930848D03*
Y927501D03*
Y954273D03*
Y950926D03*
Y947580D03*
Y944234D03*
Y971005D03*
Y967659D03*
Y964312D03*
Y960966D03*
Y957619D03*
Y984391D03*
Y981045D03*
Y977698D03*
Y974352D03*
Y1001123D03*
Y997777D03*
Y994430D03*
Y991084D03*
Y987737D03*
Y1004470D03*
Y1027895D03*
Y1044627D03*
Y1041281D03*
Y1037934D03*
Y1034588D03*
Y1031241D03*
Y1058013D03*
Y1054667D03*
Y1051320D03*
Y1047974D03*
Y1074745D03*
Y1071399D03*
Y1068052D03*
Y1064706D03*
Y1061360D03*
Y1088131D03*
Y1084785D03*
Y1081438D03*
Y1078092D03*
Y1104863D03*
Y1101517D03*
Y1098171D03*
Y1094824D03*
Y1091478D03*
Y1118249D03*
Y1114903D03*
Y1111556D03*
Y1108210D03*
Y1134982D03*
Y1131635D03*
Y1128289D03*
Y1124942D03*
Y1121596D03*
Y1148367D03*
Y1145021D03*
Y1141675D03*
Y1138328D03*
Y1165100D03*
Y1161753D03*
Y1158407D03*
Y1155060D03*
Y1151714D03*
Y1178486D03*
Y1175139D03*
Y1171793D03*
Y1168446D03*
Y1191871D03*
Y1188525D03*
Y1185178D03*
Y1181832D03*
Y1208604D03*
Y1205257D03*
Y1201911D03*
Y1198564D03*
Y1195218D03*
Y1221989D03*
Y1218643D03*
Y1215297D03*
Y1211950D03*
Y1238722D03*
Y1235375D03*
Y1232029D03*
Y1228682D03*
Y1225336D03*
Y1252108D03*
Y1248761D03*
Y1245415D03*
Y1242068D03*
Y1255454D03*
X812000Y760178D03*
Y756832D03*
Y776911D03*
Y773564D03*
Y770218D03*
Y766871D03*
Y763525D03*
Y790297D03*
Y786950D03*
Y783604D03*
Y780257D03*
Y807029D03*
Y803682D03*
Y800336D03*
Y796989D03*
Y793643D03*
Y820415D03*
Y817068D03*
Y813722D03*
Y810375D03*
Y837147D03*
Y833800D03*
Y830454D03*
Y827108D03*
Y823761D03*
Y850533D03*
Y847186D03*
Y843840D03*
Y840493D03*
Y863919D03*
Y860572D03*
Y857226D03*
Y853879D03*
Y880651D03*
Y877304D03*
Y873958D03*
Y870611D03*
Y867265D03*
Y894037D03*
Y890690D03*
Y887344D03*
Y883997D03*
Y910769D03*
Y907423D03*
Y904076D03*
Y900730D03*
Y897383D03*
Y924155D03*
Y920808D03*
Y917462D03*
Y914115D03*
Y940887D03*
Y937541D03*
Y934194D03*
Y930848D03*
Y927501D03*
Y954273D03*
Y950926D03*
Y947580D03*
Y944234D03*
Y971005D03*
Y967659D03*
Y964312D03*
Y960966D03*
Y957619D03*
Y984391D03*
Y981045D03*
Y977698D03*
Y974352D03*
Y1001123D03*
Y997777D03*
Y994430D03*
Y991084D03*
Y987737D03*
Y1004470D03*
Y1027895D03*
Y1044627D03*
Y1041281D03*
Y1037934D03*
Y1034588D03*
Y1031241D03*
Y1058013D03*
Y1054667D03*
Y1051320D03*
Y1047974D03*
Y1074745D03*
Y1071399D03*
Y1068052D03*
Y1064706D03*
Y1061360D03*
Y1088131D03*
Y1084785D03*
Y1081438D03*
Y1078092D03*
Y1104863D03*
Y1101517D03*
Y1098171D03*
Y1094824D03*
Y1091478D03*
Y1118249D03*
Y1114903D03*
Y1111556D03*
Y1108210D03*
Y1134982D03*
Y1131635D03*
Y1128289D03*
Y1124942D03*
Y1121596D03*
Y1148367D03*
Y1145021D03*
Y1141675D03*
Y1138328D03*
Y1165100D03*
Y1161753D03*
Y1158407D03*
Y1155060D03*
Y1151714D03*
Y1178486D03*
Y1175139D03*
Y1171793D03*
Y1168446D03*
Y1191871D03*
Y1188525D03*
Y1185178D03*
Y1181832D03*
Y1208604D03*
Y1205257D03*
Y1201911D03*
Y1198564D03*
Y1195218D03*
Y1221989D03*
Y1218643D03*
Y1215297D03*
Y1211950D03*
Y1238722D03*
Y1235375D03*
Y1232029D03*
Y1228682D03*
Y1225336D03*
Y1252108D03*
Y1248761D03*
Y1245415D03*
Y1242068D03*
Y1255454D03*
X1045465Y760177D03*
Y756831D03*
Y776910D03*
Y773563D03*
Y770217D03*
Y766870D03*
Y763524D03*
Y790296D03*
Y786949D03*
Y783603D03*
Y780256D03*
Y807028D03*
Y803681D03*
Y800335D03*
Y796988D03*
Y793642D03*
Y820414D03*
Y817067D03*
Y813721D03*
Y810374D03*
Y837146D03*
Y833799D03*
Y830453D03*
Y827107D03*
Y823760D03*
Y850532D03*
Y847185D03*
Y843839D03*
Y840492D03*
Y863918D03*
Y860571D03*
Y857225D03*
Y853878D03*
Y880650D03*
Y877303D03*
Y873957D03*
Y870610D03*
Y867264D03*
Y894036D03*
Y890689D03*
Y887343D03*
Y883996D03*
Y910768D03*
Y907422D03*
Y904075D03*
Y900729D03*
Y897382D03*
Y924154D03*
Y920807D03*
Y917461D03*
Y914114D03*
Y940886D03*
Y937540D03*
Y934193D03*
Y930847D03*
Y927500D03*
Y954272D03*
Y950925D03*
Y947579D03*
Y944233D03*
Y971004D03*
Y967658D03*
Y964311D03*
Y960965D03*
Y957618D03*
Y984390D03*
Y981044D03*
Y977697D03*
Y974351D03*
Y1001122D03*
Y997776D03*
Y994429D03*
Y991083D03*
Y987736D03*
Y1004469D03*
Y1027894D03*
Y1044626D03*
Y1041280D03*
Y1037933D03*
Y1034587D03*
Y1031240D03*
Y1058012D03*
Y1054666D03*
Y1051319D03*
Y1047973D03*
Y1074744D03*
Y1071398D03*
Y1068051D03*
Y1064705D03*
Y1061359D03*
Y1088130D03*
Y1084784D03*
Y1081437D03*
Y1078091D03*
Y1104862D03*
Y1101516D03*
Y1098170D03*
Y1094823D03*
Y1091477D03*
Y1118248D03*
Y1114902D03*
Y1111555D03*
Y1108209D03*
Y1134981D03*
Y1131634D03*
Y1128288D03*
Y1124941D03*
Y1121595D03*
Y1148366D03*
Y1145020D03*
Y1141674D03*
Y1138327D03*
Y1165099D03*
Y1161752D03*
Y1158406D03*
Y1155059D03*
Y1151713D03*
Y1178485D03*
Y1175138D03*
Y1171792D03*
Y1168445D03*
Y1191870D03*
Y1188524D03*
Y1185177D03*
Y1181831D03*
Y1208603D03*
Y1205256D03*
Y1201910D03*
Y1198563D03*
Y1195217D03*
Y1221988D03*
Y1218642D03*
Y1215296D03*
Y1211949D03*
Y1238721D03*
Y1235374D03*
Y1232028D03*
Y1228681D03*
Y1225335D03*
Y1252107D03*
Y1248760D03*
Y1245414D03*
Y1242067D03*
Y1255453D03*
X1061607Y760177D03*
Y756831D03*
Y776910D03*
Y773563D03*
Y770217D03*
Y766870D03*
Y763524D03*
Y790296D03*
Y786949D03*
Y783603D03*
Y780256D03*
Y807028D03*
Y803681D03*
Y800335D03*
Y796988D03*
Y793642D03*
Y820414D03*
Y817067D03*
Y813721D03*
Y810374D03*
Y837146D03*
Y833799D03*
Y830453D03*
Y827107D03*
Y823760D03*
Y850532D03*
Y847185D03*
Y843839D03*
Y840492D03*
Y863918D03*
Y860571D03*
Y857225D03*
Y853878D03*
Y880650D03*
Y877303D03*
Y873957D03*
Y870610D03*
Y867264D03*
Y894036D03*
Y890689D03*
Y887343D03*
Y883996D03*
Y910768D03*
Y907422D03*
Y904075D03*
Y900729D03*
Y897382D03*
Y924154D03*
Y920807D03*
Y917461D03*
Y914114D03*
Y940886D03*
Y937540D03*
Y934193D03*
Y930847D03*
Y927500D03*
Y954272D03*
Y950925D03*
Y947579D03*
Y944233D03*
Y971004D03*
Y967658D03*
Y964311D03*
Y960965D03*
Y957618D03*
Y984390D03*
Y981044D03*
Y977697D03*
Y974351D03*
Y1001122D03*
Y997776D03*
Y994429D03*
Y991083D03*
Y987736D03*
Y1004469D03*
Y1027894D03*
Y1044626D03*
Y1041280D03*
Y1037933D03*
Y1034587D03*
Y1031240D03*
Y1058012D03*
Y1054666D03*
Y1051319D03*
Y1047973D03*
Y1074744D03*
Y1071398D03*
Y1068051D03*
Y1064705D03*
Y1061359D03*
Y1088130D03*
Y1084784D03*
Y1081437D03*
Y1078091D03*
Y1104862D03*
Y1101516D03*
Y1098170D03*
Y1094823D03*
Y1091477D03*
Y1118248D03*
Y1114902D03*
Y1111555D03*
Y1108209D03*
Y1134981D03*
Y1131634D03*
Y1128288D03*
Y1124941D03*
Y1121595D03*
Y1148366D03*
Y1145020D03*
Y1141674D03*
Y1138327D03*
Y1165099D03*
Y1161752D03*
Y1158406D03*
Y1155059D03*
Y1151713D03*
Y1178485D03*
Y1175138D03*
Y1171792D03*
Y1168445D03*
Y1191870D03*
Y1188524D03*
Y1185177D03*
Y1181831D03*
Y1208603D03*
Y1205256D03*
Y1201910D03*
Y1198563D03*
Y1195217D03*
Y1221988D03*
Y1218642D03*
Y1215296D03*
Y1211949D03*
Y1238721D03*
Y1235374D03*
Y1232028D03*
Y1228681D03*
Y1225335D03*
Y1252107D03*
Y1248760D03*
Y1245414D03*
Y1242067D03*
Y1255453D03*
X1075166Y760177D03*
Y756831D03*
Y776910D03*
Y773563D03*
Y770217D03*
Y766870D03*
Y763524D03*
Y790296D03*
Y786949D03*
Y783603D03*
Y780256D03*
Y807028D03*
Y803681D03*
Y800335D03*
Y796988D03*
Y793642D03*
Y820414D03*
Y817067D03*
Y813721D03*
Y810374D03*
Y837146D03*
Y833799D03*
Y830453D03*
Y827107D03*
Y823760D03*
Y850532D03*
Y847185D03*
Y843839D03*
Y840492D03*
Y863918D03*
Y860571D03*
Y857225D03*
Y853878D03*
Y880650D03*
Y877303D03*
Y873957D03*
Y870610D03*
Y867264D03*
Y894036D03*
Y890689D03*
Y887343D03*
Y883996D03*
Y910768D03*
Y907422D03*
Y904075D03*
Y900729D03*
Y897382D03*
Y924154D03*
Y920807D03*
Y917461D03*
Y914114D03*
Y940886D03*
Y937540D03*
Y934193D03*
Y930847D03*
Y927500D03*
Y954272D03*
Y950925D03*
Y947579D03*
Y944233D03*
Y971004D03*
Y967658D03*
Y964311D03*
Y960965D03*
Y957618D03*
Y984390D03*
Y981044D03*
Y977697D03*
Y974351D03*
Y1001122D03*
Y997776D03*
Y994429D03*
Y991083D03*
Y987736D03*
Y1004469D03*
Y1027894D03*
Y1044626D03*
Y1041280D03*
Y1037933D03*
Y1034587D03*
Y1031240D03*
Y1058012D03*
Y1054666D03*
Y1051319D03*
Y1047973D03*
Y1074744D03*
Y1071398D03*
Y1068051D03*
Y1064705D03*
Y1061359D03*
Y1088130D03*
Y1084784D03*
Y1081437D03*
Y1078091D03*
Y1104862D03*
Y1101516D03*
Y1098170D03*
Y1094823D03*
Y1091477D03*
Y1118248D03*
Y1114902D03*
Y1111555D03*
Y1108209D03*
Y1134981D03*
Y1131634D03*
Y1128288D03*
Y1124941D03*
Y1121595D03*
Y1148366D03*
Y1145020D03*
Y1141674D03*
Y1138327D03*
Y1165099D03*
Y1161752D03*
Y1158406D03*
Y1155059D03*
Y1151713D03*
Y1178485D03*
Y1175138D03*
Y1171792D03*
Y1168445D03*
Y1191870D03*
Y1188524D03*
Y1185177D03*
Y1181831D03*
Y1208603D03*
Y1205256D03*
Y1201910D03*
Y1198563D03*
Y1195217D03*
Y1221988D03*
Y1218642D03*
Y1215296D03*
Y1211949D03*
Y1238721D03*
Y1235374D03*
Y1232028D03*
Y1228681D03*
Y1225335D03*
Y1252107D03*
Y1248760D03*
Y1245414D03*
Y1242067D03*
Y1255453D03*
X1091308Y760177D03*
Y756831D03*
Y776910D03*
Y773563D03*
Y770217D03*
Y766870D03*
Y763524D03*
Y790296D03*
Y786949D03*
Y783603D03*
Y780256D03*
Y807028D03*
Y803681D03*
Y800335D03*
Y796988D03*
Y793642D03*
Y820414D03*
Y817067D03*
Y813721D03*
Y810374D03*
Y837146D03*
Y833799D03*
Y830453D03*
Y827107D03*
Y823760D03*
Y850532D03*
Y847185D03*
Y843839D03*
Y840492D03*
Y863918D03*
Y860571D03*
Y857225D03*
Y853878D03*
Y880650D03*
Y877303D03*
Y873957D03*
Y870610D03*
Y867264D03*
Y894036D03*
Y890689D03*
Y887343D03*
Y883996D03*
Y910768D03*
Y907422D03*
Y904075D03*
Y900729D03*
Y897382D03*
Y924154D03*
Y920807D03*
Y917461D03*
Y914114D03*
Y940886D03*
Y937540D03*
Y934193D03*
Y930847D03*
Y927500D03*
Y954272D03*
Y950925D03*
Y947579D03*
Y944233D03*
Y971004D03*
Y967658D03*
Y964311D03*
Y960965D03*
Y957618D03*
Y984390D03*
Y981044D03*
Y977697D03*
Y974351D03*
Y1001122D03*
Y997776D03*
Y994429D03*
Y991083D03*
Y987736D03*
Y1004469D03*
Y1027894D03*
Y1044626D03*
Y1041280D03*
Y1037933D03*
Y1034587D03*
Y1031240D03*
Y1058012D03*
Y1054666D03*
Y1051319D03*
Y1047973D03*
Y1074744D03*
Y1071398D03*
Y1068051D03*
Y1064705D03*
Y1061359D03*
Y1088130D03*
Y1084784D03*
Y1081437D03*
Y1078091D03*
Y1104862D03*
Y1101516D03*
Y1098170D03*
Y1094823D03*
Y1091477D03*
Y1118248D03*
Y1114902D03*
Y1111555D03*
Y1108209D03*
Y1134981D03*
Y1131634D03*
Y1128288D03*
Y1124941D03*
Y1121595D03*
Y1148366D03*
Y1145020D03*
Y1141674D03*
Y1138327D03*
Y1165099D03*
Y1161752D03*
Y1158406D03*
Y1155059D03*
Y1151713D03*
Y1178485D03*
Y1175138D03*
Y1171792D03*
Y1168445D03*
Y1191870D03*
Y1188524D03*
Y1185177D03*
Y1181831D03*
Y1208603D03*
Y1205256D03*
Y1201910D03*
Y1198563D03*
Y1195217D03*
Y1221988D03*
Y1218642D03*
Y1215296D03*
Y1211949D03*
Y1238721D03*
Y1235374D03*
Y1232028D03*
Y1228681D03*
Y1225335D03*
Y1252107D03*
Y1248760D03*
Y1245414D03*
Y1242067D03*
Y1255453D03*
X1104866Y760177D03*
Y756831D03*
Y776910D03*
Y773563D03*
Y770217D03*
Y766870D03*
Y763524D03*
Y790296D03*
Y786949D03*
Y783603D03*
Y780256D03*
Y807028D03*
Y803681D03*
Y800335D03*
Y796988D03*
Y793642D03*
Y820414D03*
Y817067D03*
Y813721D03*
Y810374D03*
Y837146D03*
Y833799D03*
Y830453D03*
Y827107D03*
Y823760D03*
Y850532D03*
Y847185D03*
Y843839D03*
Y840492D03*
Y863918D03*
Y860571D03*
Y857225D03*
Y853878D03*
Y880650D03*
Y877303D03*
Y873957D03*
Y870610D03*
Y867264D03*
Y894036D03*
Y890689D03*
Y887343D03*
Y883996D03*
Y910768D03*
Y907422D03*
Y904075D03*
Y900729D03*
Y897382D03*
Y924154D03*
Y920807D03*
Y917461D03*
Y914114D03*
Y940886D03*
Y937540D03*
Y934193D03*
Y930847D03*
Y927500D03*
Y954272D03*
Y950925D03*
Y947579D03*
Y944233D03*
Y971004D03*
Y967658D03*
Y964311D03*
Y960965D03*
Y957618D03*
Y984390D03*
Y981044D03*
Y977697D03*
Y974351D03*
Y1001122D03*
Y997776D03*
Y994429D03*
Y991083D03*
Y987736D03*
Y1004469D03*
Y1027894D03*
Y1044626D03*
Y1041280D03*
Y1037933D03*
Y1034587D03*
Y1031240D03*
Y1058012D03*
Y1054666D03*
Y1051319D03*
Y1047973D03*
Y1074744D03*
Y1071398D03*
Y1068051D03*
Y1064705D03*
Y1061359D03*
Y1088130D03*
Y1084784D03*
Y1081437D03*
Y1078091D03*
Y1104862D03*
Y1101516D03*
Y1098170D03*
Y1094823D03*
Y1091477D03*
Y1118248D03*
Y1114902D03*
Y1111555D03*
Y1108209D03*
Y1134981D03*
Y1131634D03*
Y1128288D03*
Y1124941D03*
Y1121595D03*
Y1148366D03*
Y1145020D03*
Y1141674D03*
Y1138327D03*
Y1165099D03*
Y1161752D03*
Y1158406D03*
Y1155059D03*
Y1151713D03*
Y1178485D03*
Y1175138D03*
Y1171792D03*
Y1168445D03*
Y1191870D03*
Y1188524D03*
Y1185177D03*
Y1181831D03*
Y1208603D03*
Y1205256D03*
Y1201910D03*
Y1198563D03*
Y1195217D03*
Y1221988D03*
Y1218642D03*
Y1215296D03*
Y1211949D03*
Y1238721D03*
Y1235374D03*
Y1232028D03*
Y1228681D03*
Y1225335D03*
Y1252107D03*
Y1248760D03*
Y1245414D03*
Y1242067D03*
Y1255453D03*
X1121008Y760177D03*
Y756831D03*
Y776910D03*
Y773563D03*
Y770217D03*
Y766870D03*
Y763524D03*
Y790296D03*
Y786949D03*
Y783603D03*
Y780256D03*
Y807028D03*
Y803681D03*
Y800335D03*
Y796988D03*
Y793642D03*
Y820414D03*
Y817067D03*
Y813721D03*
Y810374D03*
Y837146D03*
Y833799D03*
Y830453D03*
Y827107D03*
Y823760D03*
Y850532D03*
Y847185D03*
Y843839D03*
Y840492D03*
Y863918D03*
Y860571D03*
Y857225D03*
Y853878D03*
Y880650D03*
Y877303D03*
Y873957D03*
Y870610D03*
Y867264D03*
Y894036D03*
Y890689D03*
Y887343D03*
Y883996D03*
Y910768D03*
Y907422D03*
Y904075D03*
Y900729D03*
Y897382D03*
Y924154D03*
Y920807D03*
Y917461D03*
Y914114D03*
Y940886D03*
Y937540D03*
Y934193D03*
Y930847D03*
Y927500D03*
Y954272D03*
Y950925D03*
Y947579D03*
Y944233D03*
Y971004D03*
Y967658D03*
Y964311D03*
Y960965D03*
Y957618D03*
Y984390D03*
Y981044D03*
Y977697D03*
Y974351D03*
Y1001122D03*
Y997776D03*
Y994429D03*
Y991083D03*
Y987736D03*
Y1004469D03*
Y1027894D03*
Y1044626D03*
Y1041280D03*
Y1037933D03*
Y1034587D03*
Y1031240D03*
Y1058012D03*
Y1054666D03*
Y1051319D03*
Y1047973D03*
Y1074744D03*
Y1071398D03*
Y1068051D03*
Y1064705D03*
Y1061359D03*
Y1088130D03*
Y1084784D03*
Y1081437D03*
Y1078091D03*
Y1104862D03*
Y1101516D03*
Y1098170D03*
Y1094823D03*
Y1091477D03*
Y1118248D03*
Y1114902D03*
Y1111555D03*
Y1108209D03*
Y1134981D03*
Y1131634D03*
Y1128288D03*
Y1124941D03*
Y1121595D03*
Y1148366D03*
Y1145020D03*
Y1141674D03*
Y1138327D03*
Y1165099D03*
Y1161752D03*
Y1158406D03*
Y1155059D03*
Y1151713D03*
Y1178485D03*
Y1175138D03*
Y1171792D03*
Y1168445D03*
Y1191870D03*
Y1188524D03*
Y1185177D03*
Y1181831D03*
Y1208603D03*
Y1205256D03*
Y1201910D03*
Y1198563D03*
Y1195217D03*
Y1221988D03*
Y1218642D03*
Y1215296D03*
Y1211949D03*
Y1238721D03*
Y1235374D03*
Y1232028D03*
Y1228681D03*
Y1225335D03*
Y1252107D03*
Y1248760D03*
Y1245414D03*
Y1242067D03*
Y1255453D03*
X1134567Y760177D03*
Y756831D03*
Y776910D03*
Y773563D03*
Y770217D03*
Y766870D03*
Y763524D03*
Y790296D03*
Y786949D03*
Y783603D03*
Y780256D03*
Y807028D03*
Y803681D03*
Y800335D03*
Y796988D03*
Y793642D03*
Y820414D03*
Y817067D03*
Y813721D03*
Y810374D03*
Y837146D03*
Y833799D03*
Y830453D03*
Y827107D03*
Y823760D03*
Y850532D03*
Y847185D03*
Y843839D03*
Y840492D03*
Y863918D03*
Y860571D03*
Y857225D03*
Y853878D03*
Y880650D03*
Y877303D03*
Y873957D03*
Y870610D03*
Y867264D03*
Y894036D03*
Y890689D03*
Y887343D03*
Y883996D03*
Y910768D03*
Y907422D03*
Y904075D03*
Y900729D03*
Y897382D03*
Y924154D03*
Y920807D03*
Y917461D03*
Y914114D03*
Y940886D03*
Y937540D03*
Y934193D03*
Y930847D03*
Y927500D03*
Y954272D03*
Y950925D03*
Y947579D03*
Y944233D03*
Y971004D03*
Y967658D03*
Y964311D03*
Y960965D03*
Y957618D03*
Y984390D03*
Y981044D03*
Y977697D03*
Y974351D03*
Y1001122D03*
Y997776D03*
Y994429D03*
Y991083D03*
Y987736D03*
Y1004469D03*
Y1027894D03*
Y1044626D03*
Y1041280D03*
Y1037933D03*
Y1034587D03*
Y1031240D03*
Y1058012D03*
Y1054666D03*
Y1051319D03*
Y1047973D03*
Y1074744D03*
Y1071398D03*
Y1068051D03*
Y1064705D03*
Y1061359D03*
Y1088130D03*
Y1084784D03*
Y1081437D03*
Y1078091D03*
Y1104862D03*
Y1101516D03*
Y1098170D03*
Y1094823D03*
Y1091477D03*
Y1118248D03*
Y1114902D03*
Y1111555D03*
Y1108209D03*
Y1134981D03*
Y1131634D03*
Y1128288D03*
Y1124941D03*
Y1121595D03*
Y1148366D03*
Y1145020D03*
Y1141674D03*
Y1138327D03*
Y1165099D03*
Y1161752D03*
Y1158406D03*
Y1155059D03*
Y1151713D03*
Y1178485D03*
Y1175138D03*
Y1171792D03*
Y1168445D03*
Y1191870D03*
Y1188524D03*
Y1185177D03*
Y1181831D03*
Y1208603D03*
Y1205256D03*
Y1201910D03*
Y1198563D03*
Y1195217D03*
Y1221988D03*
Y1218642D03*
Y1215296D03*
Y1211949D03*
Y1238721D03*
Y1235374D03*
Y1232028D03*
Y1228681D03*
Y1225335D03*
Y1252107D03*
Y1248760D03*
Y1245414D03*
Y1242067D03*
Y1255453D03*
X1150709Y760177D03*
Y756831D03*
Y776910D03*
Y773563D03*
Y770217D03*
Y766870D03*
Y763524D03*
Y790296D03*
Y786949D03*
Y783603D03*
Y780256D03*
Y807028D03*
Y803681D03*
Y800335D03*
Y796988D03*
Y793642D03*
Y820414D03*
Y817067D03*
Y813721D03*
Y810374D03*
Y837146D03*
Y833799D03*
Y830453D03*
Y827107D03*
Y823760D03*
Y850532D03*
Y847185D03*
Y843839D03*
Y840492D03*
Y863918D03*
Y860571D03*
Y857225D03*
Y853878D03*
Y880650D03*
Y877303D03*
Y873957D03*
Y870610D03*
Y867264D03*
Y894036D03*
Y890689D03*
Y887343D03*
Y883996D03*
Y910768D03*
Y907422D03*
Y904075D03*
Y900729D03*
Y897382D03*
Y924154D03*
Y920807D03*
Y917461D03*
Y914114D03*
Y940886D03*
Y937540D03*
Y934193D03*
Y930847D03*
Y927500D03*
Y954272D03*
Y950925D03*
Y947579D03*
Y944233D03*
Y971004D03*
Y967658D03*
Y964311D03*
Y960965D03*
Y957618D03*
Y984390D03*
Y981044D03*
Y977697D03*
Y974351D03*
Y1001122D03*
Y997776D03*
Y994429D03*
Y991083D03*
Y987736D03*
Y1004469D03*
Y1027894D03*
Y1044626D03*
Y1041280D03*
Y1037933D03*
Y1034587D03*
Y1031240D03*
Y1058012D03*
Y1054666D03*
Y1051319D03*
Y1047973D03*
Y1074744D03*
Y1071398D03*
Y1068051D03*
Y1064705D03*
Y1061359D03*
Y1088130D03*
Y1084784D03*
Y1081437D03*
Y1078091D03*
Y1104862D03*
Y1101516D03*
Y1098170D03*
Y1094823D03*
Y1091477D03*
Y1118248D03*
Y1114902D03*
Y1111555D03*
Y1108209D03*
Y1134981D03*
Y1131634D03*
Y1128288D03*
Y1124941D03*
Y1121595D03*
Y1148366D03*
Y1145020D03*
Y1141674D03*
Y1138327D03*
Y1165099D03*
Y1161752D03*
Y1158406D03*
Y1155059D03*
Y1151713D03*
Y1178485D03*
Y1175138D03*
Y1171792D03*
Y1168445D03*
Y1191870D03*
Y1188524D03*
Y1185177D03*
Y1181831D03*
Y1208603D03*
Y1205256D03*
Y1201910D03*
Y1198563D03*
Y1195217D03*
Y1221988D03*
Y1218642D03*
Y1215296D03*
Y1211949D03*
Y1238721D03*
Y1235374D03*
Y1232028D03*
Y1228681D03*
Y1225335D03*
Y1252107D03*
Y1248760D03*
Y1245414D03*
Y1242067D03*
Y1255453D03*
X1164268Y760177D03*
Y756831D03*
Y776910D03*
Y773563D03*
Y770217D03*
Y766870D03*
Y763524D03*
Y790296D03*
Y786949D03*
Y783603D03*
Y780256D03*
Y807028D03*
Y803681D03*
Y800335D03*
Y796988D03*
Y793642D03*
Y820414D03*
Y817067D03*
Y813721D03*
Y810374D03*
Y837146D03*
Y833799D03*
Y830453D03*
Y827107D03*
Y823760D03*
Y850532D03*
Y847185D03*
Y843839D03*
Y840492D03*
Y863918D03*
Y860571D03*
Y857225D03*
Y853878D03*
Y880650D03*
Y877303D03*
Y873957D03*
Y870610D03*
Y867264D03*
Y894036D03*
Y890689D03*
Y887343D03*
Y883996D03*
Y910768D03*
Y907422D03*
Y904075D03*
Y900729D03*
Y897382D03*
Y924154D03*
Y920807D03*
Y917461D03*
Y914114D03*
Y940886D03*
Y937540D03*
Y934193D03*
Y930847D03*
Y927500D03*
Y954272D03*
Y950925D03*
Y947579D03*
Y944233D03*
Y971004D03*
Y967658D03*
Y964311D03*
Y960965D03*
Y957618D03*
Y984390D03*
Y981044D03*
Y977697D03*
Y974351D03*
Y1001122D03*
Y997776D03*
Y994429D03*
Y991083D03*
Y987736D03*
Y1004469D03*
Y1027894D03*
Y1044626D03*
Y1041280D03*
Y1037933D03*
Y1034587D03*
Y1031240D03*
Y1058012D03*
Y1054666D03*
Y1051319D03*
Y1047973D03*
Y1074744D03*
Y1071398D03*
Y1068051D03*
Y1064705D03*
Y1061359D03*
Y1088130D03*
Y1084784D03*
Y1081437D03*
Y1078091D03*
Y1104862D03*
Y1101516D03*
Y1098170D03*
Y1094823D03*
Y1091477D03*
Y1118248D03*
Y1114902D03*
Y1111555D03*
Y1108209D03*
Y1134981D03*
Y1131634D03*
Y1128288D03*
Y1124941D03*
Y1121595D03*
Y1148366D03*
Y1145020D03*
Y1141674D03*
Y1138327D03*
Y1165099D03*
Y1161752D03*
Y1158406D03*
Y1155059D03*
Y1151713D03*
Y1178485D03*
Y1175138D03*
Y1171792D03*
Y1168445D03*
Y1191870D03*
Y1188524D03*
Y1185177D03*
Y1181831D03*
Y1208603D03*
Y1205256D03*
Y1201910D03*
Y1198563D03*
Y1195217D03*
Y1221988D03*
Y1218642D03*
Y1215296D03*
Y1211949D03*
Y1238721D03*
Y1235374D03*
Y1232028D03*
Y1228681D03*
Y1225335D03*
Y1252107D03*
Y1248760D03*
Y1245414D03*
Y1242067D03*
Y1255453D03*
X1180410Y760177D03*
Y756831D03*
Y776910D03*
Y773563D03*
Y770217D03*
Y766870D03*
Y763524D03*
Y790296D03*
Y786949D03*
Y783603D03*
Y780256D03*
Y807028D03*
Y803681D03*
Y800335D03*
Y796988D03*
Y793642D03*
Y820414D03*
Y817067D03*
Y813721D03*
Y810374D03*
Y837146D03*
Y833799D03*
Y830453D03*
Y827107D03*
Y823760D03*
Y850532D03*
Y847185D03*
Y843839D03*
Y840492D03*
Y863918D03*
Y860571D03*
Y857225D03*
Y853878D03*
Y880650D03*
Y877303D03*
Y873957D03*
Y870610D03*
Y867264D03*
Y894036D03*
Y890689D03*
Y887343D03*
Y883996D03*
Y910768D03*
Y907422D03*
Y904075D03*
Y900729D03*
Y897382D03*
Y924154D03*
Y920807D03*
Y917461D03*
Y914114D03*
Y940886D03*
Y937540D03*
Y934193D03*
Y930847D03*
Y927500D03*
Y954272D03*
Y950925D03*
Y947579D03*
Y944233D03*
Y971004D03*
Y967658D03*
Y964311D03*
Y960965D03*
Y957618D03*
Y984390D03*
Y981044D03*
Y977697D03*
Y974351D03*
Y1001122D03*
Y997776D03*
Y994429D03*
Y991083D03*
Y987736D03*
Y1004469D03*
Y1027894D03*
Y1044626D03*
Y1041280D03*
Y1037933D03*
Y1034587D03*
Y1031240D03*
Y1058012D03*
Y1054666D03*
Y1051319D03*
Y1047973D03*
Y1074744D03*
Y1071398D03*
Y1068051D03*
Y1064705D03*
Y1061359D03*
Y1088130D03*
Y1084784D03*
Y1081437D03*
Y1078091D03*
Y1104862D03*
Y1101516D03*
Y1098170D03*
Y1094823D03*
Y1091477D03*
Y1118248D03*
Y1114902D03*
Y1111555D03*
Y1108209D03*
Y1134981D03*
Y1131634D03*
Y1128288D03*
Y1124941D03*
Y1121595D03*
Y1148366D03*
Y1145020D03*
Y1141674D03*
Y1138327D03*
Y1165099D03*
Y1161752D03*
Y1158406D03*
Y1155059D03*
Y1151713D03*
Y1178485D03*
Y1175138D03*
Y1171792D03*
Y1168445D03*
Y1191870D03*
Y1188524D03*
Y1185177D03*
Y1181831D03*
Y1208603D03*
Y1205256D03*
Y1201910D03*
Y1198563D03*
Y1195217D03*
Y1221988D03*
Y1218642D03*
Y1215296D03*
Y1211949D03*
Y1238721D03*
Y1235374D03*
Y1232028D03*
Y1228681D03*
Y1225335D03*
Y1252107D03*
Y1248760D03*
Y1245414D03*
Y1242067D03*
Y1255453D03*
X1193969Y760177D03*
Y756831D03*
Y776910D03*
Y773563D03*
Y770217D03*
Y766870D03*
Y763524D03*
Y790296D03*
Y786949D03*
Y783603D03*
Y780256D03*
Y807028D03*
Y803681D03*
Y800335D03*
Y796988D03*
Y793642D03*
Y820414D03*
Y817067D03*
Y813721D03*
Y810374D03*
Y837146D03*
Y833799D03*
Y830453D03*
Y827107D03*
Y823760D03*
Y850532D03*
Y847185D03*
Y843839D03*
Y840492D03*
Y863918D03*
Y860571D03*
Y857225D03*
Y853878D03*
Y880650D03*
Y877303D03*
Y873957D03*
Y870610D03*
Y867264D03*
Y894036D03*
Y890689D03*
Y887343D03*
Y883996D03*
Y910768D03*
Y907422D03*
Y904075D03*
Y900729D03*
Y897382D03*
Y924154D03*
Y920807D03*
Y917461D03*
Y914114D03*
Y940886D03*
Y937540D03*
Y934193D03*
Y930847D03*
Y927500D03*
Y954272D03*
Y950925D03*
Y947579D03*
Y944233D03*
Y971004D03*
Y967658D03*
Y964311D03*
Y960965D03*
Y957618D03*
Y984390D03*
Y981044D03*
Y977697D03*
Y974351D03*
Y1001122D03*
Y997776D03*
Y994429D03*
Y991083D03*
Y987736D03*
Y1004469D03*
Y1027894D03*
Y1044626D03*
Y1041280D03*
Y1037933D03*
Y1034587D03*
Y1031240D03*
Y1058012D03*
Y1054666D03*
Y1051319D03*
Y1047973D03*
Y1074744D03*
Y1071398D03*
Y1068051D03*
Y1064705D03*
Y1061359D03*
Y1088130D03*
Y1084784D03*
Y1081437D03*
Y1078091D03*
Y1104862D03*
Y1101516D03*
Y1098170D03*
Y1094823D03*
Y1091477D03*
Y1118248D03*
Y1114902D03*
Y1111555D03*
Y1108209D03*
Y1134981D03*
Y1131634D03*
Y1128288D03*
Y1124941D03*
Y1121595D03*
Y1148366D03*
Y1145020D03*
Y1141674D03*
Y1138327D03*
Y1165099D03*
Y1161752D03*
Y1158406D03*
Y1155059D03*
Y1151713D03*
Y1178485D03*
Y1175138D03*
Y1171792D03*
Y1168445D03*
Y1191870D03*
Y1188524D03*
Y1185177D03*
Y1181831D03*
Y1208603D03*
Y1205256D03*
Y1201910D03*
Y1198563D03*
Y1195217D03*
Y1221988D03*
Y1218642D03*
Y1215296D03*
Y1211949D03*
Y1238721D03*
Y1235374D03*
Y1232028D03*
Y1228681D03*
Y1225335D03*
Y1252107D03*
Y1248760D03*
Y1245414D03*
Y1242067D03*
Y1255453D03*
X1210111Y760177D03*
Y756831D03*
Y776910D03*
Y773563D03*
Y770217D03*
Y766870D03*
Y763524D03*
Y790296D03*
Y786949D03*
Y783603D03*
Y780256D03*
Y807028D03*
Y803681D03*
Y800335D03*
Y796988D03*
Y793642D03*
Y820414D03*
Y817067D03*
Y813721D03*
Y810374D03*
Y837146D03*
Y833799D03*
Y830453D03*
Y827107D03*
Y823760D03*
Y850532D03*
Y847185D03*
Y843839D03*
Y840492D03*
Y863918D03*
Y860571D03*
Y857225D03*
Y853878D03*
Y880650D03*
Y877303D03*
Y873957D03*
Y870610D03*
Y867264D03*
Y894036D03*
Y890689D03*
Y887343D03*
Y883996D03*
Y910768D03*
Y907422D03*
Y904075D03*
Y900729D03*
Y897382D03*
Y924154D03*
Y920807D03*
Y917461D03*
Y914114D03*
Y940886D03*
Y937540D03*
Y934193D03*
Y930847D03*
Y927500D03*
Y954272D03*
Y950925D03*
Y947579D03*
Y944233D03*
Y971004D03*
Y967658D03*
Y964311D03*
Y960965D03*
Y957618D03*
Y984390D03*
Y981044D03*
Y977697D03*
Y974351D03*
Y1001122D03*
Y997776D03*
Y994429D03*
Y991083D03*
Y987736D03*
Y1004469D03*
Y1027894D03*
Y1044626D03*
Y1041280D03*
Y1037933D03*
Y1034587D03*
Y1031240D03*
Y1058012D03*
Y1054666D03*
Y1051319D03*
Y1047973D03*
Y1074744D03*
Y1071398D03*
Y1068051D03*
Y1064705D03*
Y1061359D03*
Y1088130D03*
Y1084784D03*
Y1081437D03*
Y1078091D03*
Y1104862D03*
Y1101516D03*
Y1098170D03*
Y1094823D03*
Y1091477D03*
Y1118248D03*
Y1114902D03*
Y1111555D03*
Y1108209D03*
Y1134981D03*
Y1131634D03*
Y1128288D03*
Y1124941D03*
Y1121595D03*
Y1148366D03*
Y1145020D03*
Y1141674D03*
Y1138327D03*
Y1165099D03*
Y1161752D03*
Y1158406D03*
Y1155059D03*
Y1151713D03*
Y1178485D03*
Y1175138D03*
Y1171792D03*
Y1168445D03*
Y1191870D03*
Y1188524D03*
Y1185177D03*
Y1181831D03*
Y1208603D03*
Y1205256D03*
Y1201910D03*
Y1198563D03*
Y1195217D03*
Y1221988D03*
Y1218642D03*
Y1215296D03*
Y1211949D03*
Y1238721D03*
Y1235374D03*
Y1232028D03*
Y1228681D03*
Y1225335D03*
Y1252107D03*
Y1248760D03*
Y1245414D03*
Y1242067D03*
Y1255453D03*
X1623496Y760177D03*
Y756831D03*
Y776910D03*
Y773563D03*
Y770217D03*
Y766870D03*
Y763524D03*
Y790296D03*
Y786949D03*
Y783603D03*
Y780256D03*
Y807028D03*
Y803681D03*
Y800335D03*
Y796988D03*
Y793642D03*
Y820414D03*
Y817067D03*
Y813721D03*
Y810374D03*
Y837146D03*
Y833799D03*
Y830453D03*
Y827107D03*
Y823760D03*
Y850532D03*
Y847185D03*
Y843839D03*
Y840492D03*
Y863918D03*
Y860571D03*
Y857225D03*
Y853878D03*
Y880650D03*
Y877303D03*
Y873957D03*
Y870610D03*
Y867264D03*
Y894036D03*
Y890689D03*
Y887343D03*
Y883996D03*
Y910768D03*
Y907422D03*
Y904075D03*
Y900729D03*
Y897382D03*
Y924154D03*
Y920807D03*
Y917461D03*
Y914114D03*
Y940886D03*
Y937540D03*
Y934193D03*
Y930847D03*
Y927500D03*
Y954272D03*
Y950925D03*
Y947579D03*
Y944233D03*
Y971004D03*
Y967658D03*
Y964311D03*
Y960965D03*
Y957618D03*
Y984390D03*
Y981044D03*
Y977697D03*
Y974351D03*
Y1001122D03*
Y997776D03*
Y994429D03*
Y991083D03*
Y987736D03*
Y1004469D03*
Y1027894D03*
Y1044626D03*
Y1041280D03*
Y1037933D03*
Y1034587D03*
Y1031240D03*
Y1058012D03*
Y1054666D03*
Y1051319D03*
Y1047973D03*
Y1074744D03*
Y1071398D03*
Y1068051D03*
Y1064705D03*
Y1061359D03*
Y1088130D03*
Y1084784D03*
Y1081437D03*
Y1078091D03*
Y1104862D03*
Y1101516D03*
Y1098170D03*
Y1094823D03*
Y1091477D03*
Y1118248D03*
Y1114902D03*
Y1111555D03*
Y1108209D03*
Y1134981D03*
Y1131634D03*
Y1128288D03*
Y1124941D03*
Y1121595D03*
Y1148366D03*
Y1145020D03*
Y1141674D03*
Y1138327D03*
Y1165099D03*
Y1161752D03*
Y1158406D03*
Y1155059D03*
Y1151713D03*
Y1178485D03*
Y1175138D03*
Y1171792D03*
Y1168445D03*
Y1191870D03*
Y1188524D03*
Y1185177D03*
Y1181831D03*
Y1208603D03*
Y1205256D03*
Y1201910D03*
Y1198563D03*
Y1195217D03*
Y1221988D03*
Y1218642D03*
Y1215296D03*
Y1211949D03*
Y1238721D03*
Y1235374D03*
Y1232028D03*
Y1228681D03*
Y1225335D03*
Y1252107D03*
Y1248760D03*
Y1245414D03*
Y1242067D03*
Y1255453D03*
X1639638Y760177D03*
Y756831D03*
Y776910D03*
Y773563D03*
Y770217D03*
Y766870D03*
Y763524D03*
Y790296D03*
Y786949D03*
Y783603D03*
Y780256D03*
Y807028D03*
Y803681D03*
Y800335D03*
Y796988D03*
Y793642D03*
Y820414D03*
Y817067D03*
Y813721D03*
Y810374D03*
Y837146D03*
Y833799D03*
Y830453D03*
Y827107D03*
Y823760D03*
Y850532D03*
Y847185D03*
Y843839D03*
Y840492D03*
Y863918D03*
Y860571D03*
Y857225D03*
Y853878D03*
Y880650D03*
Y877303D03*
Y873957D03*
Y870610D03*
Y867264D03*
Y894036D03*
Y890689D03*
Y887343D03*
Y883996D03*
Y910768D03*
Y907422D03*
Y904075D03*
Y900729D03*
Y897382D03*
Y924154D03*
Y920807D03*
Y917461D03*
Y914114D03*
Y940886D03*
Y937540D03*
Y934193D03*
Y930847D03*
Y927500D03*
Y954272D03*
Y950925D03*
Y947579D03*
Y944233D03*
Y971004D03*
Y967658D03*
Y964311D03*
Y960965D03*
Y957618D03*
Y984390D03*
Y981044D03*
Y977697D03*
Y974351D03*
Y1001122D03*
Y997776D03*
Y994429D03*
Y991083D03*
Y987736D03*
Y1004469D03*
Y1027894D03*
Y1044626D03*
Y1041280D03*
Y1037933D03*
Y1034587D03*
Y1031240D03*
Y1058012D03*
Y1054666D03*
Y1051319D03*
Y1047973D03*
Y1074744D03*
Y1071398D03*
Y1068051D03*
Y1064705D03*
Y1061359D03*
Y1088130D03*
Y1084784D03*
Y1081437D03*
Y1078091D03*
Y1104862D03*
Y1101516D03*
Y1098170D03*
Y1094823D03*
Y1091477D03*
Y1118248D03*
Y1114902D03*
Y1111555D03*
Y1108209D03*
Y1134981D03*
Y1131634D03*
Y1128288D03*
Y1124941D03*
Y1121595D03*
Y1148366D03*
Y1145020D03*
Y1141674D03*
Y1138327D03*
Y1165099D03*
Y1161752D03*
Y1158406D03*
Y1155059D03*
Y1151713D03*
Y1178485D03*
Y1175138D03*
Y1171792D03*
Y1168445D03*
Y1191870D03*
Y1188524D03*
Y1185177D03*
Y1181831D03*
Y1208603D03*
Y1205256D03*
Y1201910D03*
Y1198563D03*
Y1195217D03*
Y1221988D03*
Y1218642D03*
Y1215296D03*
Y1211949D03*
Y1238721D03*
Y1235374D03*
Y1232028D03*
Y1228681D03*
Y1225335D03*
Y1252107D03*
Y1248760D03*
Y1245414D03*
Y1242067D03*
Y1255453D03*
X1653197Y760177D03*
Y756831D03*
Y776910D03*
Y773563D03*
Y770217D03*
Y766870D03*
Y763524D03*
Y790296D03*
Y786949D03*
Y783603D03*
Y780256D03*
Y807028D03*
Y803681D03*
Y800335D03*
Y796988D03*
Y793642D03*
Y820414D03*
Y817067D03*
Y813721D03*
Y810374D03*
Y837146D03*
Y833799D03*
Y830453D03*
Y827107D03*
Y823760D03*
Y850532D03*
Y847185D03*
Y843839D03*
Y840492D03*
Y863918D03*
Y860571D03*
Y857225D03*
Y853878D03*
Y880650D03*
Y877303D03*
Y873957D03*
Y870610D03*
Y867264D03*
Y894036D03*
Y890689D03*
Y887343D03*
Y883996D03*
Y910768D03*
Y907422D03*
Y904075D03*
Y900729D03*
Y897382D03*
Y924154D03*
Y920807D03*
Y917461D03*
Y914114D03*
Y940886D03*
Y937540D03*
Y934193D03*
Y930847D03*
Y927500D03*
Y954272D03*
Y950925D03*
Y947579D03*
Y944233D03*
Y971004D03*
Y967658D03*
Y964311D03*
Y960965D03*
Y957618D03*
Y984390D03*
Y981044D03*
Y977697D03*
Y974351D03*
Y1001122D03*
Y997776D03*
Y994429D03*
Y991083D03*
Y987736D03*
Y1004469D03*
Y1027894D03*
Y1044626D03*
Y1041280D03*
Y1037933D03*
Y1034587D03*
Y1031240D03*
Y1058012D03*
Y1054666D03*
Y1051319D03*
Y1047973D03*
Y1074744D03*
Y1071398D03*
Y1068051D03*
Y1064705D03*
Y1061359D03*
Y1088130D03*
Y1084784D03*
Y1081437D03*
Y1078091D03*
Y1104862D03*
Y1101516D03*
Y1098170D03*
Y1094823D03*
Y1091477D03*
Y1118248D03*
Y1114902D03*
Y1111555D03*
Y1108209D03*
Y1134981D03*
Y1131634D03*
Y1128288D03*
Y1124941D03*
Y1121595D03*
Y1148366D03*
Y1145020D03*
Y1141674D03*
Y1138327D03*
Y1165099D03*
Y1161752D03*
Y1158406D03*
Y1155059D03*
Y1151713D03*
Y1178485D03*
Y1175138D03*
Y1171792D03*
Y1168445D03*
Y1191870D03*
Y1188524D03*
Y1185177D03*
Y1181831D03*
Y1208603D03*
Y1205256D03*
Y1201910D03*
Y1198563D03*
Y1195217D03*
Y1221988D03*
Y1218642D03*
Y1215296D03*
Y1211949D03*
Y1238721D03*
Y1235374D03*
Y1232028D03*
Y1228681D03*
Y1225335D03*
Y1252107D03*
Y1248760D03*
Y1245414D03*
Y1242067D03*
Y1255453D03*
X1669339Y760177D03*
Y756831D03*
Y776910D03*
Y773563D03*
Y770217D03*
Y766870D03*
Y763524D03*
Y790296D03*
Y786949D03*
Y783603D03*
Y780256D03*
Y807028D03*
Y803681D03*
Y800335D03*
Y796988D03*
Y793642D03*
Y820414D03*
Y817067D03*
Y813721D03*
Y810374D03*
Y837146D03*
Y833799D03*
Y830453D03*
Y827107D03*
Y823760D03*
Y850532D03*
Y847185D03*
Y843839D03*
Y840492D03*
Y863918D03*
Y860571D03*
Y857225D03*
Y853878D03*
Y880650D03*
Y877303D03*
Y873957D03*
Y870610D03*
Y867264D03*
Y894036D03*
Y890689D03*
Y887343D03*
Y883996D03*
Y910768D03*
Y907422D03*
Y904075D03*
Y900729D03*
Y897382D03*
Y924154D03*
Y920807D03*
Y917461D03*
Y914114D03*
Y940886D03*
Y937540D03*
Y934193D03*
Y930847D03*
Y927500D03*
Y954272D03*
Y950925D03*
Y947579D03*
Y944233D03*
Y971004D03*
Y967658D03*
Y964311D03*
Y960965D03*
Y957618D03*
Y984390D03*
Y981044D03*
Y977697D03*
Y974351D03*
Y1001122D03*
Y997776D03*
Y994429D03*
Y991083D03*
Y987736D03*
Y1004469D03*
Y1027894D03*
Y1044626D03*
Y1041280D03*
Y1037933D03*
Y1034587D03*
Y1031240D03*
Y1058012D03*
Y1054666D03*
Y1051319D03*
Y1047973D03*
Y1074744D03*
Y1071398D03*
Y1068051D03*
Y1064705D03*
Y1061359D03*
Y1088130D03*
Y1084784D03*
Y1081437D03*
Y1078091D03*
Y1104862D03*
Y1101516D03*
Y1098170D03*
Y1094823D03*
Y1091477D03*
Y1118248D03*
Y1114902D03*
Y1111555D03*
Y1108209D03*
Y1134981D03*
Y1131634D03*
Y1128288D03*
Y1124941D03*
Y1121595D03*
Y1148366D03*
Y1145020D03*
Y1141674D03*
Y1138327D03*
Y1165099D03*
Y1161752D03*
Y1158406D03*
Y1155059D03*
Y1151713D03*
Y1178485D03*
Y1175138D03*
Y1171792D03*
Y1168445D03*
Y1191870D03*
Y1188524D03*
Y1185177D03*
Y1181831D03*
Y1208603D03*
Y1205256D03*
Y1201910D03*
Y1198563D03*
Y1195217D03*
Y1221988D03*
Y1218642D03*
Y1215296D03*
Y1211949D03*
Y1238721D03*
Y1235374D03*
Y1232028D03*
Y1228681D03*
Y1225335D03*
Y1252107D03*
Y1248760D03*
Y1245414D03*
Y1242067D03*
Y1255453D03*
X1682898Y760177D03*
Y756831D03*
Y776910D03*
Y773563D03*
Y770217D03*
Y766870D03*
Y763524D03*
Y790296D03*
Y786949D03*
Y783603D03*
Y780256D03*
Y807028D03*
Y803681D03*
Y800335D03*
Y796988D03*
Y793642D03*
Y820414D03*
Y817067D03*
Y813721D03*
Y810374D03*
Y837146D03*
Y833799D03*
Y830453D03*
Y827107D03*
Y823760D03*
Y850532D03*
Y847185D03*
Y843839D03*
Y840492D03*
Y863918D03*
Y860571D03*
Y857225D03*
Y853878D03*
Y880650D03*
Y877303D03*
Y873957D03*
Y870610D03*
Y867264D03*
Y894036D03*
Y890689D03*
Y887343D03*
Y883996D03*
Y910768D03*
Y907422D03*
Y904075D03*
Y900729D03*
Y897382D03*
Y924154D03*
Y920807D03*
Y917461D03*
Y914114D03*
Y940886D03*
Y937540D03*
Y934193D03*
Y930847D03*
Y927500D03*
Y954272D03*
Y950925D03*
Y947579D03*
Y944233D03*
Y971004D03*
Y967658D03*
Y964311D03*
Y960965D03*
Y957618D03*
Y984390D03*
Y981044D03*
Y977697D03*
Y974351D03*
Y1001122D03*
Y997776D03*
Y994429D03*
Y991083D03*
Y987736D03*
Y1004469D03*
Y1027894D03*
Y1044626D03*
Y1041280D03*
Y1037933D03*
Y1034587D03*
Y1031240D03*
Y1058012D03*
Y1054666D03*
Y1051319D03*
Y1047973D03*
Y1074744D03*
Y1071398D03*
Y1068051D03*
Y1064705D03*
Y1061359D03*
Y1088130D03*
Y1084784D03*
Y1081437D03*
Y1078091D03*
Y1104862D03*
Y1101516D03*
Y1098170D03*
Y1094823D03*
Y1091477D03*
Y1118248D03*
Y1114902D03*
Y1111555D03*
Y1108209D03*
Y1134981D03*
Y1131634D03*
Y1128288D03*
Y1124941D03*
Y1121595D03*
Y1148366D03*
Y1145020D03*
Y1141674D03*
Y1138327D03*
Y1165099D03*
Y1161752D03*
Y1158406D03*
Y1155059D03*
Y1151713D03*
Y1178485D03*
Y1175138D03*
Y1171792D03*
Y1168445D03*
Y1191870D03*
Y1188524D03*
Y1185177D03*
Y1181831D03*
Y1208603D03*
Y1205256D03*
Y1201910D03*
Y1198563D03*
Y1195217D03*
Y1221988D03*
Y1218642D03*
Y1215296D03*
Y1211949D03*
Y1238721D03*
Y1235374D03*
Y1232028D03*
Y1228681D03*
Y1225335D03*
Y1252107D03*
Y1248760D03*
Y1245414D03*
Y1242067D03*
Y1255453D03*
X1699040Y760177D03*
Y756831D03*
Y776910D03*
Y773563D03*
Y770217D03*
Y766870D03*
Y763524D03*
Y790296D03*
Y786949D03*
Y783603D03*
Y780256D03*
Y807028D03*
Y803681D03*
Y800335D03*
Y796988D03*
Y793642D03*
Y820414D03*
Y817067D03*
Y813721D03*
Y810374D03*
Y837146D03*
Y833799D03*
Y830453D03*
Y827107D03*
Y823760D03*
Y850532D03*
Y847185D03*
Y843839D03*
Y840492D03*
Y863918D03*
Y860571D03*
Y857225D03*
Y853878D03*
Y880650D03*
Y877303D03*
Y873957D03*
Y870610D03*
Y867264D03*
Y894036D03*
Y890689D03*
Y887343D03*
Y883996D03*
Y910768D03*
Y907422D03*
Y904075D03*
Y900729D03*
Y897382D03*
Y924154D03*
Y920807D03*
Y917461D03*
Y914114D03*
Y940886D03*
Y937540D03*
Y934193D03*
Y930847D03*
Y927500D03*
Y954272D03*
Y950925D03*
Y947579D03*
Y944233D03*
Y971004D03*
Y967658D03*
Y964311D03*
Y960965D03*
Y957618D03*
Y984390D03*
Y981044D03*
Y977697D03*
Y974351D03*
Y1001122D03*
Y997776D03*
Y994429D03*
Y991083D03*
Y987736D03*
Y1004469D03*
Y1027894D03*
Y1044626D03*
Y1041280D03*
Y1037933D03*
Y1034587D03*
Y1031240D03*
Y1058012D03*
Y1054666D03*
Y1051319D03*
Y1047973D03*
Y1074744D03*
Y1071398D03*
Y1068051D03*
Y1064705D03*
Y1061359D03*
Y1088130D03*
Y1084784D03*
Y1081437D03*
Y1078091D03*
Y1104862D03*
Y1101516D03*
Y1098170D03*
Y1094823D03*
Y1091477D03*
Y1118248D03*
Y1114902D03*
Y1111555D03*
Y1108209D03*
Y1134981D03*
Y1131634D03*
Y1128288D03*
Y1124941D03*
Y1121595D03*
Y1148366D03*
Y1145020D03*
Y1141674D03*
Y1138327D03*
Y1165099D03*
Y1161752D03*
Y1158406D03*
Y1155059D03*
Y1151713D03*
Y1178485D03*
Y1175138D03*
Y1171792D03*
Y1168445D03*
Y1191870D03*
Y1188524D03*
Y1185177D03*
Y1181831D03*
Y1208603D03*
Y1205256D03*
Y1201910D03*
Y1198563D03*
Y1195217D03*
Y1221988D03*
Y1218642D03*
Y1215296D03*
Y1211949D03*
Y1238721D03*
Y1235374D03*
Y1232028D03*
Y1228681D03*
Y1225335D03*
Y1252107D03*
Y1248760D03*
Y1245414D03*
Y1242067D03*
Y1255453D03*
X1712599Y760177D03*
Y756831D03*
Y776910D03*
Y773563D03*
Y770217D03*
Y766870D03*
Y763524D03*
Y790296D03*
Y786949D03*
Y783603D03*
Y780256D03*
Y807028D03*
Y803681D03*
Y800335D03*
Y796988D03*
Y793642D03*
Y820414D03*
Y817067D03*
Y813721D03*
Y810374D03*
Y837146D03*
Y833799D03*
Y830453D03*
Y827107D03*
Y823760D03*
Y850532D03*
Y847185D03*
Y843839D03*
Y840492D03*
Y863918D03*
Y860571D03*
Y857225D03*
Y853878D03*
Y880650D03*
Y877303D03*
Y873957D03*
Y870610D03*
Y867264D03*
Y894036D03*
Y890689D03*
Y887343D03*
Y883996D03*
Y910768D03*
Y907422D03*
Y904075D03*
Y900729D03*
Y897382D03*
Y924154D03*
Y920807D03*
Y917461D03*
Y914114D03*
Y940886D03*
Y937540D03*
Y934193D03*
Y930847D03*
Y927500D03*
Y954272D03*
Y950925D03*
Y947579D03*
Y944233D03*
Y971004D03*
Y967658D03*
Y964311D03*
Y960965D03*
Y957618D03*
Y984390D03*
Y981044D03*
Y977697D03*
Y974351D03*
Y1001122D03*
Y997776D03*
Y994429D03*
Y991083D03*
Y987736D03*
Y1004469D03*
Y1027894D03*
Y1044626D03*
Y1041280D03*
Y1037933D03*
Y1034587D03*
Y1031240D03*
Y1058012D03*
Y1054666D03*
Y1051319D03*
Y1047973D03*
Y1074744D03*
Y1071398D03*
Y1068051D03*
Y1064705D03*
Y1061359D03*
Y1088130D03*
Y1084784D03*
Y1081437D03*
Y1078091D03*
Y1104862D03*
Y1101516D03*
Y1098170D03*
Y1094823D03*
Y1091477D03*
Y1118248D03*
Y1114902D03*
Y1111555D03*
Y1108209D03*
Y1134981D03*
Y1131634D03*
Y1128288D03*
Y1124941D03*
Y1121595D03*
Y1148366D03*
Y1145020D03*
Y1141674D03*
Y1138327D03*
Y1165099D03*
Y1161752D03*
Y1158406D03*
Y1155059D03*
Y1151713D03*
Y1178485D03*
Y1175138D03*
Y1171792D03*
Y1168445D03*
Y1191870D03*
Y1188524D03*
Y1185177D03*
Y1181831D03*
Y1208603D03*
Y1205256D03*
Y1201910D03*
Y1198563D03*
Y1195217D03*
Y1221988D03*
Y1218642D03*
Y1215296D03*
Y1211949D03*
Y1238721D03*
Y1235374D03*
Y1232028D03*
Y1228681D03*
Y1225335D03*
Y1252107D03*
Y1248760D03*
Y1245414D03*
Y1242067D03*
Y1255453D03*
X1728741Y760177D03*
Y756831D03*
Y776910D03*
Y773563D03*
Y770217D03*
Y766870D03*
Y763524D03*
Y790296D03*
Y786949D03*
Y783603D03*
Y780256D03*
Y807028D03*
Y803681D03*
Y800335D03*
Y796988D03*
Y793642D03*
Y820414D03*
Y817067D03*
Y813721D03*
Y810374D03*
Y837146D03*
Y833799D03*
Y830453D03*
Y827107D03*
Y823760D03*
Y850532D03*
Y847185D03*
Y843839D03*
Y840492D03*
Y863918D03*
Y860571D03*
Y857225D03*
Y853878D03*
Y880650D03*
Y877303D03*
Y873957D03*
Y870610D03*
Y867264D03*
Y894036D03*
Y890689D03*
Y887343D03*
Y883996D03*
Y910768D03*
Y907422D03*
Y904075D03*
Y900729D03*
Y897382D03*
Y924154D03*
Y920807D03*
Y917461D03*
Y914114D03*
Y940886D03*
Y937540D03*
Y934193D03*
Y930847D03*
Y927500D03*
Y954272D03*
Y950925D03*
Y947579D03*
Y944233D03*
Y971004D03*
Y967658D03*
Y964311D03*
Y960965D03*
Y957618D03*
Y984390D03*
Y981044D03*
Y977697D03*
Y974351D03*
Y1001122D03*
Y997776D03*
Y994429D03*
Y991083D03*
Y987736D03*
Y1004469D03*
Y1027894D03*
Y1044626D03*
Y1041280D03*
Y1037933D03*
Y1034587D03*
Y1031240D03*
Y1058012D03*
Y1054666D03*
Y1051319D03*
Y1047973D03*
Y1074744D03*
Y1071398D03*
Y1068051D03*
Y1064705D03*
Y1061359D03*
Y1088130D03*
Y1084784D03*
Y1081437D03*
Y1078091D03*
Y1104862D03*
Y1101516D03*
Y1098170D03*
Y1094823D03*
Y1091477D03*
Y1118248D03*
Y1114902D03*
Y1111555D03*
Y1108209D03*
Y1134981D03*
Y1131634D03*
Y1128288D03*
Y1124941D03*
Y1121595D03*
Y1148366D03*
Y1145020D03*
Y1141674D03*
Y1138327D03*
Y1165099D03*
Y1161752D03*
Y1158406D03*
Y1155059D03*
Y1151713D03*
Y1178485D03*
Y1175138D03*
Y1171792D03*
Y1168445D03*
Y1191870D03*
Y1188524D03*
Y1185177D03*
Y1181831D03*
Y1208603D03*
Y1205256D03*
Y1201910D03*
Y1198563D03*
Y1195217D03*
Y1221988D03*
Y1218642D03*
Y1215296D03*
Y1211949D03*
Y1238721D03*
Y1235374D03*
Y1232028D03*
Y1228681D03*
Y1225335D03*
Y1252107D03*
Y1248760D03*
Y1245414D03*
Y1242067D03*
Y1255453D03*
X1742300Y760177D03*
Y756831D03*
Y776910D03*
Y773563D03*
Y770217D03*
Y766870D03*
Y763524D03*
Y790296D03*
Y786949D03*
Y783603D03*
Y780256D03*
Y807028D03*
Y803681D03*
Y800335D03*
Y796988D03*
Y793642D03*
Y820414D03*
Y817067D03*
Y813721D03*
Y810374D03*
Y837146D03*
Y833799D03*
Y830453D03*
Y827107D03*
Y823760D03*
Y850532D03*
Y847185D03*
Y843839D03*
Y840492D03*
Y863918D03*
Y860571D03*
Y857225D03*
Y853878D03*
Y880650D03*
Y877303D03*
Y873957D03*
Y870610D03*
Y867264D03*
Y894036D03*
Y890689D03*
Y887343D03*
Y883996D03*
Y910768D03*
Y907422D03*
Y904075D03*
Y900729D03*
Y897382D03*
Y924154D03*
Y920807D03*
Y917461D03*
Y914114D03*
Y940886D03*
Y937540D03*
Y934193D03*
Y930847D03*
Y927500D03*
Y954272D03*
Y950925D03*
Y947579D03*
Y944233D03*
Y971004D03*
Y967658D03*
Y964311D03*
Y960965D03*
Y957618D03*
Y984390D03*
Y981044D03*
Y977697D03*
Y974351D03*
Y1001122D03*
Y997776D03*
Y994429D03*
Y991083D03*
Y987736D03*
Y1004469D03*
Y1027894D03*
Y1044626D03*
Y1041280D03*
Y1037933D03*
Y1034587D03*
Y1031240D03*
Y1058012D03*
Y1054666D03*
Y1051319D03*
Y1047973D03*
Y1074744D03*
Y1071398D03*
Y1068051D03*
Y1064705D03*
Y1061359D03*
Y1088130D03*
Y1084784D03*
Y1081437D03*
Y1078091D03*
Y1104862D03*
Y1101516D03*
Y1098170D03*
Y1094823D03*
Y1091477D03*
Y1118248D03*
Y1114902D03*
Y1111555D03*
Y1108209D03*
Y1134981D03*
Y1131634D03*
Y1128288D03*
Y1124941D03*
Y1121595D03*
Y1148366D03*
Y1145020D03*
Y1141674D03*
Y1138327D03*
Y1165099D03*
Y1161752D03*
Y1158406D03*
Y1155059D03*
Y1151713D03*
Y1178485D03*
Y1175138D03*
Y1171792D03*
Y1168445D03*
Y1191870D03*
Y1188524D03*
Y1185177D03*
Y1181831D03*
Y1208603D03*
Y1205256D03*
Y1201910D03*
Y1198563D03*
Y1195217D03*
Y1221988D03*
Y1218642D03*
Y1215296D03*
Y1211949D03*
Y1238721D03*
Y1235374D03*
Y1232028D03*
Y1228681D03*
Y1225335D03*
Y1252107D03*
Y1248760D03*
Y1245414D03*
Y1242067D03*
Y1255453D03*
X1758442Y760177D03*
Y756831D03*
Y776910D03*
Y773563D03*
Y770217D03*
Y766870D03*
Y763524D03*
Y790296D03*
Y786949D03*
Y783603D03*
Y780256D03*
Y807028D03*
Y803681D03*
Y800335D03*
Y796988D03*
Y793642D03*
Y820414D03*
Y817067D03*
Y813721D03*
Y810374D03*
Y837146D03*
Y833799D03*
Y830453D03*
Y827107D03*
Y823760D03*
Y850532D03*
Y847185D03*
Y843839D03*
Y840492D03*
Y863918D03*
Y860571D03*
Y857225D03*
Y853878D03*
Y880650D03*
Y877303D03*
Y873957D03*
Y870610D03*
Y867264D03*
Y894036D03*
Y890689D03*
Y887343D03*
Y883996D03*
Y910768D03*
Y907422D03*
Y904075D03*
Y900729D03*
Y897382D03*
Y924154D03*
Y920807D03*
Y917461D03*
Y914114D03*
Y940886D03*
Y937540D03*
Y934193D03*
Y930847D03*
Y927500D03*
Y954272D03*
Y950925D03*
Y947579D03*
Y944233D03*
Y971004D03*
Y967658D03*
Y964311D03*
Y960965D03*
Y957618D03*
Y984390D03*
Y981044D03*
Y977697D03*
Y974351D03*
Y1001122D03*
Y997776D03*
Y994429D03*
Y991083D03*
Y987736D03*
Y1004469D03*
Y1027894D03*
Y1044626D03*
Y1041280D03*
Y1037933D03*
Y1034587D03*
Y1031240D03*
Y1058012D03*
Y1054666D03*
Y1051319D03*
Y1047973D03*
Y1074744D03*
Y1071398D03*
Y1068051D03*
Y1064705D03*
Y1061359D03*
Y1088130D03*
Y1084784D03*
Y1081437D03*
Y1078091D03*
Y1104862D03*
Y1101516D03*
Y1098170D03*
Y1094823D03*
Y1091477D03*
Y1118248D03*
Y1114902D03*
Y1111555D03*
Y1108209D03*
Y1134981D03*
Y1131634D03*
Y1128288D03*
Y1124941D03*
Y1121595D03*
Y1148366D03*
Y1145020D03*
Y1141674D03*
Y1138327D03*
Y1165099D03*
Y1161752D03*
Y1158406D03*
Y1155059D03*
Y1151713D03*
Y1178485D03*
Y1175138D03*
Y1171792D03*
Y1168445D03*
Y1191870D03*
Y1188524D03*
Y1185177D03*
Y1181831D03*
Y1208603D03*
Y1205256D03*
Y1201910D03*
Y1198563D03*
Y1195217D03*
Y1221988D03*
Y1218642D03*
Y1215296D03*
Y1211949D03*
Y1238721D03*
Y1235374D03*
Y1232028D03*
Y1228681D03*
Y1225335D03*
Y1252107D03*
Y1248760D03*
Y1245414D03*
Y1242067D03*
Y1255453D03*
X1772000Y760177D03*
Y756831D03*
Y776910D03*
Y773563D03*
Y770217D03*
Y766870D03*
Y763524D03*
Y790296D03*
Y786949D03*
Y783603D03*
Y780256D03*
Y807028D03*
Y803681D03*
Y800335D03*
Y796988D03*
Y793642D03*
Y820414D03*
Y817067D03*
Y813721D03*
Y810374D03*
Y837146D03*
Y833799D03*
Y830453D03*
Y827107D03*
Y823760D03*
Y850532D03*
Y847185D03*
Y843839D03*
Y840492D03*
Y863918D03*
Y860571D03*
Y857225D03*
Y853878D03*
Y880650D03*
Y877303D03*
Y873957D03*
Y870610D03*
Y867264D03*
Y894036D03*
Y890689D03*
Y887343D03*
Y883996D03*
Y910768D03*
Y907422D03*
Y904075D03*
Y900729D03*
Y897382D03*
Y924154D03*
Y920807D03*
Y917461D03*
Y914114D03*
Y940886D03*
Y937540D03*
Y934193D03*
Y930847D03*
Y927500D03*
Y954272D03*
Y950925D03*
Y947579D03*
Y944233D03*
Y971004D03*
Y967658D03*
Y964311D03*
Y960965D03*
Y957618D03*
Y984390D03*
Y981044D03*
Y977697D03*
Y974351D03*
Y1001122D03*
Y997776D03*
Y994429D03*
Y991083D03*
Y987736D03*
Y1004469D03*
Y1027894D03*
Y1044626D03*
Y1041280D03*
Y1037933D03*
Y1034587D03*
Y1031240D03*
Y1058012D03*
Y1054666D03*
Y1051319D03*
Y1047973D03*
Y1074744D03*
Y1071398D03*
Y1068051D03*
Y1064705D03*
Y1061359D03*
Y1088130D03*
Y1084784D03*
Y1081437D03*
Y1078091D03*
Y1104862D03*
Y1101516D03*
Y1098170D03*
Y1094823D03*
Y1091477D03*
Y1118248D03*
Y1114902D03*
Y1111555D03*
Y1108209D03*
Y1134981D03*
Y1131634D03*
Y1128288D03*
Y1124941D03*
Y1121595D03*
Y1148366D03*
Y1145020D03*
Y1141674D03*
Y1138327D03*
Y1165099D03*
Y1161752D03*
Y1158406D03*
Y1155059D03*
Y1151713D03*
Y1178485D03*
Y1175138D03*
Y1171792D03*
Y1168445D03*
Y1191870D03*
Y1188524D03*
Y1185177D03*
Y1181831D03*
Y1208603D03*
Y1205256D03*
Y1201910D03*
Y1198563D03*
Y1195217D03*
Y1221988D03*
Y1218642D03*
Y1215296D03*
Y1211949D03*
Y1238721D03*
Y1235374D03*
Y1232028D03*
Y1228681D03*
Y1225335D03*
Y1252107D03*
Y1248760D03*
Y1245414D03*
Y1242067D03*
Y1255453D03*
X1788142Y760177D03*
Y756831D03*
Y776910D03*
Y773563D03*
Y770217D03*
Y766870D03*
Y763524D03*
Y790296D03*
Y786949D03*
Y783603D03*
Y780256D03*
Y807028D03*
Y803681D03*
Y800335D03*
Y796988D03*
Y793642D03*
Y820414D03*
Y817067D03*
Y813721D03*
Y810374D03*
Y837146D03*
Y833799D03*
Y830453D03*
Y827107D03*
Y823760D03*
Y850532D03*
Y847185D03*
Y843839D03*
Y840492D03*
Y863918D03*
Y860571D03*
Y857225D03*
Y853878D03*
Y880650D03*
Y877303D03*
Y873957D03*
Y870610D03*
Y867264D03*
Y894036D03*
Y890689D03*
Y887343D03*
Y883996D03*
Y910768D03*
Y907422D03*
Y904075D03*
Y900729D03*
Y897382D03*
Y924154D03*
Y920807D03*
Y917461D03*
Y914114D03*
Y940886D03*
Y937540D03*
Y934193D03*
Y930847D03*
Y927500D03*
Y954272D03*
Y950925D03*
Y947579D03*
Y944233D03*
Y971004D03*
Y967658D03*
Y964311D03*
Y960965D03*
Y957618D03*
Y984390D03*
Y981044D03*
Y977697D03*
Y974351D03*
Y1001122D03*
Y997776D03*
Y994429D03*
Y991083D03*
Y987736D03*
Y1004469D03*
Y1027894D03*
Y1044626D03*
Y1041280D03*
Y1037933D03*
Y1034587D03*
Y1031240D03*
Y1058012D03*
Y1054666D03*
Y1051319D03*
Y1047973D03*
Y1074744D03*
Y1071398D03*
Y1068051D03*
Y1064705D03*
Y1061359D03*
Y1088130D03*
Y1084784D03*
Y1081437D03*
Y1078091D03*
Y1104862D03*
Y1101516D03*
Y1098170D03*
Y1094823D03*
Y1091477D03*
Y1118248D03*
Y1114902D03*
Y1111555D03*
Y1108209D03*
Y1134981D03*
Y1131634D03*
Y1128288D03*
Y1124941D03*
Y1121595D03*
Y1148366D03*
Y1145020D03*
Y1141674D03*
Y1138327D03*
Y1165099D03*
Y1161752D03*
Y1158406D03*
Y1155059D03*
Y1151713D03*
Y1178485D03*
Y1175138D03*
Y1171792D03*
Y1168445D03*
Y1191870D03*
Y1188524D03*
Y1185177D03*
Y1181831D03*
Y1208603D03*
Y1205256D03*
Y1201910D03*
Y1198563D03*
Y1195217D03*
Y1221988D03*
Y1218642D03*
Y1215296D03*
Y1211949D03*
Y1238721D03*
Y1235374D03*
Y1232028D03*
Y1228681D03*
Y1225335D03*
Y1252107D03*
Y1248760D03*
Y1245414D03*
Y1242067D03*
Y1255453D03*
G54D136*
X334339Y171170D03*
X329221D03*
Y178610D03*
X331780D03*
X334339D03*
G54D235*
X829028Y491614D03*
Y486496D03*
X821588D03*
Y489055D03*
Y491614D03*
X931348Y267222D03*
Y272340D03*
X938788Y269781D03*
Y267222D03*
Y272340D03*
G54D208*
X705660Y588934D03*
X697392D03*
Y606060D03*
X705660D03*
G54D217*
X716780Y1643326D03*
X721898D03*
X719339D03*
X714221D03*
Y1666358D03*
X716780D03*
X721898D03*
X719339D03*
X737253Y1643326D03*
X734694D03*
X732135D03*
X729576D03*
X727017D03*
X724457D03*
Y1666358D03*
X727017D03*
X729576D03*
X732135D03*
X734694D03*
X737253D03*
G54D61*
X77000Y1447437D03*
X80740Y1439563D03*
X73260D03*
X154640Y431977D03*
X150900Y424103D03*
X158380D03*
X181420Y431437D03*
X185160Y423563D03*
X177680D03*
X426011Y532701D03*
X418531D03*
X422271Y540575D03*
X763029Y151312D03*
X766769Y143438D03*
X759289D03*
X757557Y1687769D03*
X765037D03*
X761297Y1679895D03*
X1050866Y1656096D03*
X1058346D03*
X1054606Y1648222D03*
G54D145*
X366588Y283311D03*
X773766Y270763D03*
G54D25*
X31099Y387783D03*
X24997D03*
X31099Y395067D03*
X24997D03*
X486949Y109959D03*
Y117243D03*
X493051D03*
Y109959D03*
G54D154*
X435262Y55016D03*
Y60016D03*
Y65016D03*
Y70016D03*
X456128Y60016D03*
Y55016D03*
Y70016D03*
Y65016D03*
X1148486Y53186D03*
Y58186D03*
Y63186D03*
Y68186D03*
X1169352Y58186D03*
Y53186D03*
Y68186D03*
Y63186D03*
G54D253*
X961084Y1541966D03*
Y1559682D03*
X992696Y1541982D03*
Y1559698D03*
X1024296Y1541982D03*
Y1559698D03*
X1055896Y1541982D03*
Y1559698D03*
G54D127*
X285260Y227776D03*
Y237224D03*
X289000D03*
X292740Y227776D03*
Y237224D03*
X761510Y1641559D03*
X757770D03*
X754030D03*
X761510Y1651007D03*
X754030D03*
X844760Y476724D03*
X852240D03*
Y467276D03*
X848500D03*
X844760D03*
G54D163*
X467750Y1684738D03*
Y1692218D03*
X470309Y1684738D03*
X472868D03*
X470309Y1692218D03*
X472868D03*
X1387620Y1716438D03*
X1385061D03*
X1390179D03*
X1387620Y1723918D03*
X1385061D03*
X1390179D03*
G54D109*
X212224Y148760D03*
X202776D03*
X212224Y156240D03*
X202776Y152500D03*
Y156240D03*
X240708Y207651D03*
Y211391D03*
Y215131D03*
X250156Y207651D03*
Y215131D03*
X599776Y417760D03*
Y425240D03*
X609224Y417760D03*
Y425240D03*
Y421500D03*
X861416Y402450D03*
X870864D03*
X861416Y409930D03*
X870864D03*
Y406190D03*
G54D181*
X492000Y413335D03*
X488260Y422665D03*
X495740D03*
X552000Y434835D03*
X548260Y444165D03*
X555740D03*
G54D244*
X897437Y1141595D03*
X944462D03*
X1303765Y545330D03*
X1613355Y547190D03*
G54D226*
X776768Y1581379D03*
Y1579410D03*
Y1577442D03*
Y1587284D03*
Y1585316D03*
Y1583347D03*
X794386Y1577442D03*
Y1581379D03*
Y1579410D03*
Y1587284D03*
Y1583347D03*
Y1585316D03*
X818768Y1581379D03*
Y1579410D03*
Y1577442D03*
Y1587284D03*
Y1585316D03*
Y1583347D03*
X836386Y1577442D03*
Y1581379D03*
Y1579410D03*
Y1587284D03*
Y1583347D03*
Y1585316D03*
X860768Y1581379D03*
Y1579410D03*
Y1577442D03*
Y1587284D03*
Y1585316D03*
Y1583347D03*
X878386Y1577442D03*
Y1581379D03*
Y1579410D03*
Y1587284D03*
Y1583347D03*
Y1585316D03*
X902768Y1581379D03*
Y1579410D03*
Y1577442D03*
Y1587284D03*
Y1585316D03*
Y1583347D03*
X920386Y1577442D03*
Y1581379D03*
Y1579410D03*
Y1587284D03*
Y1583347D03*
Y1585316D03*
G54D34*
X50380Y520331D03*
X48412D03*
Y535095D03*
X50380D03*
X58254Y520331D03*
X56286D03*
X54317D03*
X52349D03*
Y535095D03*
X54317D03*
X56286D03*
X58254D03*
X411403Y1603375D03*
X413372D03*
X415340D03*
X417309D03*
X419277D03*
X421246D03*
X423214D03*
X411403Y1622075D03*
X413372D03*
X415340D03*
X417309D03*
X419277D03*
X421246D03*
X423214D03*
X425183Y1603375D03*
Y1622075D03*
X1124532Y1637591D03*
X1122563D03*
X1120595D03*
X1118626D03*
X1124532Y1656291D03*
X1122563D03*
X1120595D03*
X1118626D03*
X1132406Y1637591D03*
X1130437D03*
X1128469D03*
X1126500D03*
X1132406Y1656291D03*
X1130437D03*
X1128469D03*
X1126500D03*
G54D280*
X1627179Y576851D03*
Y611015D03*
G54D118*
X275630Y109804D03*
X708786Y113929D03*
X1750751Y110928D03*
G54D190*
X539016Y274272D03*
X549016D03*
X559016D03*
X569016D03*
X579016D03*
X589016D03*
X599016D03*
G54D271*
X1225530Y60384D03*
X1233404D03*
X1241278D03*
X1439049Y87432D03*
X1454797D03*
X1446923D03*
G54D262*
X1027520Y543499D03*
Y549799D03*
G54D70*
X111339Y1422181D03*
Y1444819D03*
X125512Y1422181D03*
X123937D03*
X122362D03*
X120787D03*
X119213D03*
X117638D03*
X116063D03*
X114488D03*
X112913D03*
Y1444819D03*
X114488D03*
X116063D03*
X117638D03*
X119213D03*
X120787D03*
X122362D03*
X123937D03*
X125512D03*
X128661Y1422181D03*
X127087D03*
Y1444819D03*
X128661D03*
X1213913Y1408681D03*
X1212339D03*
Y1431319D03*
X1213913D03*
X1229661Y1408681D03*
X1228087D03*
X1226512D03*
X1224937D03*
X1223362D03*
X1221787D03*
X1220213D03*
X1218638D03*
X1217063D03*
X1215488D03*
Y1431319D03*
X1217063D03*
X1218638D03*
X1220213D03*
X1221787D03*
X1223362D03*
X1224937D03*
X1226512D03*
X1228087D03*
X1229661D03*
G54D52*
X62831Y1575194D03*
X80153D03*
X116246Y1580308D03*
X133568D03*
X203980Y627557D03*
X221302D03*
X1655694Y604703D03*
X1673016D03*
X1745150Y1621650D03*
X1762472D03*
X1797091Y1621550D03*
X1814413D03*
G54D146*
X366588Y288429D03*
X773766Y275881D03*
G54D17*
X17363Y233231D03*
X10543Y233275D03*
X36595Y388035D03*
X32774Y528853D03*
X46834Y366395D03*
X50631Y1533154D03*
X42150Y1553563D03*
X46150D03*
X45633Y1598379D03*
X50133D03*
X55190Y366395D03*
X64442Y507448D03*
X53299Y549778D03*
X63148Y549743D03*
X58365D03*
X59427Y1649870D03*
X66127Y1684870D03*
X76378Y1412138D03*
X72378D03*
X79323Y1533010D03*
X72768Y1550279D03*
X76806Y1599390D03*
X78406Y1607690D03*
X73427Y1649870D03*
X68427D03*
X82127Y1684870D03*
X86374Y1533654D03*
X90127Y1684870D03*
X92257Y1724314D03*
X98101Y1366520D03*
X108511Y1549979D03*
X115016Y297680D03*
Y318114D03*
X118407Y524274D03*
X126910Y1367118D03*
X119632Y1384841D03*
X115066Y1532710D03*
X120353Y1652070D03*
X124353D03*
X116353D03*
X123353Y1693449D03*
X140360Y427063D03*
X130701Y1366520D03*
X140353Y1652070D03*
X128353D03*
X127353Y1693570D03*
X132767Y1726224D03*
X150318Y213441D03*
Y221441D03*
X152232Y1384841D03*
X143500Y1445483D03*
X147000D03*
X148353Y1652070D03*
X144253D03*
X147253Y1693570D03*
X154740Y1710483D03*
X149900Y1715849D03*
Y1722849D03*
X159510Y1366891D03*
X163401Y1366520D03*
X159427Y1693570D03*
X162740Y1710483D03*
X167500Y1718483D03*
X184932Y1384841D03*
X181760Y1710371D03*
X185760Y1728859D03*
X189410Y393643D03*
X192210Y1367118D03*
X196301Y1366520D03*
X189760Y1710371D03*
X194000Y1717983D03*
X211000Y1714983D03*
X228675Y567092D03*
X225110Y1367118D03*
X229101Y1366520D03*
X217832Y1384841D03*
X236266Y65345D03*
X240266D03*
X244266D03*
X232817Y567060D03*
X239843Y715231D03*
X248266Y65345D03*
X251487Y107743D03*
X255270Y214953D03*
X255466Y648242D03*
X257910Y1367118D03*
X250632Y1384841D03*
X275797Y127026D03*
X262466Y598136D03*
X269405Y585018D03*
X263866Y590937D03*
X269061Y647432D03*
X272955Y656063D03*
X272932Y673384D03*
X262701Y1320374D03*
X261778Y1367108D03*
X279783Y127051D03*
X288597Y218502D03*
X288949Y249394D03*
X276801Y581561D03*
X288196Y682483D03*
X284232Y1338695D03*
X305266Y71090D03*
X301315Y98782D03*
X305315D03*
X293000Y222483D03*
X292949Y249394D03*
X292705Y585937D03*
X301791Y681673D03*
X305685Y690304D03*
X305662Y707625D03*
X295597Y1320346D03*
X291510Y1320772D03*
X310339Y231334D03*
X320966Y702633D03*
X317128Y1338667D03*
X325617Y76846D03*
X333988Y596787D03*
X334561Y701823D03*
X324557Y1320910D03*
X328501Y1320289D03*
X346695Y237038D03*
X342000Y280483D03*
X348157Y574323D03*
X338455Y710454D03*
X338432Y727775D03*
X350032Y1338610D03*
X352608Y279813D03*
X355828Y294873D03*
X354026Y702365D03*
X357310Y1320887D03*
X361301Y1320489D03*
X378184Y471834D03*
X375943Y537179D03*
X367621Y701555D03*
X371515Y710186D03*
X371492Y727507D03*
X386703Y126820D03*
X390859Y126867D03*
X387184Y475978D03*
X382184Y504584D03*
X392184D03*
X380771Y537121D03*
X387066Y702433D03*
X390110Y1321087D03*
X382832Y1338810D03*
X393883Y1339820D03*
X382992Y1677929D03*
X387324Y1677978D03*
X392324D03*
X407299Y209603D03*
X403299D03*
Y217554D03*
X407299D03*
X406184Y504584D03*
X397184D03*
X400673Y573836D03*
X400661Y701623D03*
X404555Y710254D03*
X404532Y727575D03*
X399000Y1627196D03*
X397324Y1677978D03*
X409000Y1680483D03*
X423299Y209603D03*
X415299D03*
X419299D03*
X415299Y217554D03*
X419984Y504507D03*
X410984D03*
X424784Y504430D03*
X420066Y684633D03*
X423926Y1031987D03*
X422692Y1340418D03*
X415414Y1358141D03*
X413000Y1680483D03*
X438673Y80183D03*
X429673D03*
X433673Y87183D03*
X438673D03*
X433685Y94140D03*
X429685D03*
X437997Y163608D03*
X433997D03*
X439299Y209603D03*
X435299D03*
X427299D03*
X431299D03*
Y217554D03*
X427299D03*
X435299D03*
X439500Y489483D03*
X433661Y683823D03*
X437555Y692454D03*
X437532Y709775D03*
X435146Y1031987D03*
X427666D03*
X431406D03*
X438886D03*
X426561Y1340402D03*
X428500Y1636983D03*
X442673Y87183D03*
X449997Y163608D03*
X445997D03*
X449997Y156608D03*
X445997D03*
X453997Y163608D03*
X443299Y209603D03*
X447299D03*
Y217554D03*
X443299D03*
X452466Y660033D03*
X450107Y1031987D03*
X442626D03*
X453847D03*
X446366D03*
X447576Y1647465D03*
X443594Y1647510D03*
X461997Y163608D03*
X469997D03*
X457931Y218161D03*
X465699Y288543D03*
X468500Y492983D03*
X466061Y659223D03*
X469955Y667854D03*
X469932Y685175D03*
X457587Y1031987D03*
X457000Y1646983D03*
X465000Y1650483D03*
X468500Y1714483D03*
X473997Y163608D03*
X481997D03*
X477997D03*
X484063Y311455D03*
X485066Y633533D03*
X498385Y111182D03*
X498661Y632723D03*
X502555Y641354D03*
X502532Y658675D03*
X528304Y213980D03*
X518500Y432483D03*
X522500D03*
X518366Y599433D03*
X531961Y598623D03*
X539503Y598399D03*
X543371Y598411D03*
X535855Y607254D03*
X535832Y624575D03*
X540106Y662783D03*
X550196Y187739D03*
X552699Y297543D03*
X573911Y217679D03*
X571063Y320455D03*
X568451Y1268001D03*
X564509Y1267997D03*
X578454Y86122D03*
X586394Y93156D03*
X577859Y217679D03*
X586500Y460983D03*
Y467483D03*
X583125Y754848D03*
X579125D03*
X587521Y754916D03*
X602328Y106553D03*
X590512D03*
X590501Y93156D03*
X602280D03*
X593758Y421688D03*
X603456Y754862D03*
X599489Y754848D03*
X595489D03*
X591521Y754916D03*
X618256Y106553D03*
X618182Y93156D03*
X608794Y194244D03*
X615385Y401636D03*
X607456Y754862D03*
X615443Y754874D03*
X611443D03*
X621310Y178592D03*
X630609Y230458D03*
X631505Y289838D03*
X626705Y302788D03*
X630195Y1389940D03*
X626295D03*
X634095D03*
X642301Y153034D03*
X638000Y418483D03*
X634244Y510521D03*
X646236Y1356420D03*
X638436D03*
X642436D03*
X656000Y520983D03*
Y512983D03*
X650036Y1356420D03*
X653836D03*
X657836D03*
X672800Y374845D03*
X676800D03*
X675500Y396345D03*
X666948Y401170D03*
X678071Y1311672D03*
X684643Y111868D03*
X680800Y374845D03*
X684800D03*
X693367Y366387D03*
X683500Y396345D03*
X679500D03*
X691500D03*
X699520Y366387D03*
X708500Y510845D03*
X704666Y510800D03*
X704500Y527345D03*
X700500D03*
X708509Y526828D03*
X708500Y543345D03*
X704500D03*
X696283Y543770D03*
X702645Y621594D03*
X698645D03*
X705657Y1384529D03*
X703799Y1630676D03*
X705688Y1650425D03*
X706623Y1666059D03*
X708953Y131151D03*
X719334Y366345D03*
X711458Y366343D03*
X716300Y379845D03*
X719500Y396345D03*
X723500D03*
X716500Y510845D03*
X720500D03*
X712500D03*
X723032Y527298D03*
X719518Y527314D03*
X712484Y526034D03*
X716016Y527408D03*
X710464Y552456D03*
X711845Y590700D03*
X711907Y606336D03*
X722129Y664150D03*
X718129D03*
X719152Y1630564D03*
X715309Y1680026D03*
X721909Y1684354D03*
X737093Y90960D03*
X737340Y118718D03*
X735449Y375011D03*
X731406Y379814D03*
X731500Y396345D03*
X727500D03*
X724500Y510845D03*
X730310Y527266D03*
X733811Y527220D03*
X726793Y527332D03*
X737324Y526986D03*
X724500Y543345D03*
X734557Y1384884D03*
X738439Y1384629D03*
X727188Y1402660D03*
X724723Y1630003D03*
X729616Y1680244D03*
X725632Y1680243D03*
X737467Y1683590D03*
X741270Y118642D03*
X739500Y379845D03*
X743500D03*
X748500Y543345D03*
X740500D03*
X751770Y1631266D03*
X752187Y1677977D03*
X741326Y1680040D03*
X745537Y1680125D03*
X745382Y1690253D03*
X760193Y96331D03*
X760500Y112483D03*
X759000Y366845D03*
X763500Y379845D03*
X767500Y396345D03*
X763500D03*
X760500Y543345D03*
X756500D03*
X767339Y1384984D03*
X759970Y1402760D03*
X758030Y1666066D03*
X772000Y527345D03*
X771216Y1384984D03*
X806500Y1329983D03*
X812526Y1348236D03*
X808526D03*
X831540Y65826D03*
X834616Y107264D03*
X835114Y120681D03*
X833715Y228051D03*
X831000Y511483D03*
X841900Y545280D03*
X834750Y569205D03*
X856630Y65976D03*
X850016Y93234D03*
X858783Y227466D03*
X863294Y269019D03*
X863571Y296868D03*
X867571D03*
X886503Y274390D03*
X925468Y267130D03*
X920268Y275342D03*
X922447Y1155558D03*
X949263Y277639D03*
X965442Y167868D03*
X969472Y1155558D03*
X985500Y155282D03*
X989605Y182536D03*
X988835Y194936D03*
X985445Y182566D03*
X988460Y366519D03*
X1005735Y160926D03*
X1001395Y221406D03*
X1004460Y366519D03*
X1000460D03*
X996460D03*
X992460D03*
X1009618Y402048D03*
X1020202Y541259D03*
X1007011Y553132D03*
X1034838Y541259D03*
X1030000Y560483D03*
X1035500D03*
X1050104Y1665367D03*
X1069236Y396940D03*
X1075526Y427447D03*
X1069839Y1366501D03*
X1092948Y479338D03*
X1091370Y1384822D03*
X1095489Y1699087D03*
X1094514Y1718899D03*
X1102439Y1366501D03*
X1098648Y1367099D03*
X1108747Y1538863D03*
X1109522Y1554416D03*
X1109000Y1668483D03*
X1098514Y1725899D03*
X1123970Y1384822D03*
X1114117Y1538863D03*
X1121010Y1591881D03*
X1125010D03*
X1115027Y1596234D03*
X1115394Y1625810D03*
X1112500Y1668483D03*
X1135139Y1366501D03*
X1131248Y1367099D03*
X1137846Y1459431D03*
X1133846D03*
X1132168Y1626448D03*
X1136097Y1626451D03*
X1166203Y77260D03*
X1163948Y1367099D03*
X1168039Y1366501D03*
X1156670Y1384822D03*
X1184000Y428908D03*
X1172000Y430483D03*
X1180000D03*
X1176000D03*
X1196848Y1367099D03*
X1189570Y1384822D03*
X1189407Y1715001D03*
X1200839Y1366501D03*
X1214254Y1709919D03*
Y1730919D03*
Y1723919D03*
Y1716919D03*
X1230312Y94118D03*
X1229648Y1367099D03*
X1222370Y1384822D03*
X1238830Y1320355D03*
X1233516Y1367089D03*
X1259472Y90347D03*
X1248859Y1422983D03*
X1252859D03*
X1253000Y1429983D03*
X1273677Y764971D03*
X1271726Y1320327D03*
X1267639Y1320753D03*
X1260361Y1338676D03*
X1275981Y90597D03*
X1284764Y95287D03*
X1280764D03*
X1288677Y761971D03*
X1277677Y764971D03*
X1281677D03*
X1296200Y64394D03*
X1292786Y548306D03*
X1298886Y596538D03*
X1300677Y761971D03*
X1292677Y765471D03*
X1296677D03*
X1300686Y1320891D03*
X1304630Y1320270D03*
X1293257Y1338648D03*
X1308110Y64394D03*
X1307366Y552696D03*
X1320020Y64462D03*
X1333399Y95567D03*
X1332360Y561678D03*
X1333439Y1320868D03*
X1326161Y1338591D03*
X1337399Y95567D03*
X1341399D03*
X1348199D03*
X1337430Y1320470D03*
X1356199Y95533D03*
X1352199D03*
X1360109D03*
X1350772Y677651D03*
X1358961Y1338791D03*
X1366018Y617576D03*
X1366239Y1321068D03*
X1370012Y1339801D03*
X1379613Y616766D03*
X1383507Y625397D03*
X1383484Y642718D03*
X1391543Y1358122D03*
X1398718Y650476D03*
X1403808Y1031986D03*
X1407548D03*
X1400068D03*
X1403690Y1289248D03*
X1398821Y1340399D03*
X1412313Y649666D03*
X1416207Y658297D03*
X1416184Y675618D03*
X1422508Y1031986D03*
X1415028D03*
X1411288D03*
X1418768D03*
X1415623Y1602142D03*
X1419622Y1613250D03*
X1438262Y58375D03*
X1434513Y112883D03*
X1439049Y119926D03*
X1431318Y683056D03*
X1429989Y1031986D03*
X1433729D03*
X1426249D03*
X1446869Y111344D03*
X1443049Y119926D03*
X1444769Y171700D03*
X1439769D03*
X1449769D03*
X1439769Y179700D03*
X1449769D03*
X1441741Y599349D03*
X1444913Y682246D03*
X1448807Y690877D03*
X1448784Y708198D03*
X1440500Y1620483D03*
X1445500D03*
X1449070Y1684205D03*
X1445079Y1684161D03*
X1454549Y119926D03*
X1460508Y139426D03*
X1454769Y171700D03*
X1464236Y702633D03*
X1461702Y1670871D03*
X1483820Y128741D03*
X1477831Y701823D03*
X1481725Y710454D03*
X1481702Y727775D03*
X1491560Y597520D03*
X1497318Y702633D03*
X1513644Y225158D03*
Y216308D03*
X1513348Y259521D03*
X1510913Y701823D03*
X1527853Y565747D03*
X1514807Y710454D03*
X1514784Y727775D03*
X1539693Y541096D03*
X1537853Y565747D03*
X1530118Y702633D03*
X1543713Y701823D03*
X1547607Y710454D03*
X1547584Y727775D03*
X1561345Y577681D03*
X1563248Y680693D03*
X1584079Y564591D03*
X1576843Y679883D03*
X1580737Y688514D03*
X1580714Y705835D03*
X1579177Y1265271D03*
X1596018Y646924D03*
X1605286Y550156D03*
X1609286D03*
X1609613Y646114D03*
X1613507Y654745D03*
X1613484Y672066D03*
X1625000Y388983D03*
X1629018Y627924D03*
X1621000Y1435483D03*
X1638334Y561270D03*
X1646507Y635745D03*
X1646484Y653066D03*
X1641804Y1311044D03*
X1636167Y1441961D03*
X1661928Y227655D03*
X1659610Y400185D03*
X1653790Y431527D03*
X1657545D03*
X1650035D03*
X1649979Y622029D03*
X1654147Y621981D03*
X1651959Y695730D03*
X1653390Y1383818D03*
X1649024Y1409704D03*
X1653024D03*
X1656824D03*
X1660624D03*
X1654513Y1711667D03*
X1658513Y1714817D03*
X1654513Y1726817D03*
Y1718667D03*
Y1733817D03*
X1663610Y400185D03*
X1674921Y1401949D03*
X1668424Y1409704D03*
X1664424D03*
X1689000Y231483D03*
X1688504Y404543D03*
X1690154Y431668D03*
X1682290Y1384173D03*
X1686172Y1383918D03*
X1681000Y1442983D03*
Y1436483D03*
X1684012Y1669224D03*
X1689513Y1711667D03*
Y1718667D03*
X1693000Y231483D03*
X1694314Y431638D03*
X1695529Y1548251D03*
X1711798Y65262D03*
X1716558D03*
X1721344Y65439D03*
X1716931Y78738D03*
X1711798Y78750D03*
X1713418Y128150D03*
X1710426Y410646D03*
X1715072Y1384273D03*
X1718949D03*
X1707703Y1402049D03*
X1726608Y108867D03*
X1730202Y1599076D03*
X1726202D03*
X1725423Y1690139D03*
X1735463Y1691948D03*
X1729436Y1690148D03*
X1728633Y1715173D03*
Y1723323D03*
X1732633Y1726473D03*
X1728633Y1730323D03*
X1750918Y128150D03*
X1751983Y261120D03*
X1737914Y1566190D03*
X1747963Y1647848D03*
X1740463Y1691948D03*
X1745463D03*
X1757322Y128154D03*
X1766606Y1566046D03*
X1760051Y1583315D03*
X1757963Y1650948D03*
X1752963Y1647848D03*
X1762963Y1650948D03*
X1767638Y72599D03*
X1767891Y100303D03*
X1771891D03*
X1773657Y1566690D03*
X1790738Y77970D03*
X1793444Y183627D03*
X1797011D03*
X1789811D03*
X1795794Y1583015D03*
X1811711Y180527D03*
X1800511Y183627D03*
X1804111D03*
X1807711D03*
X1802349Y1565746D03*
X1819705Y159855D03*
X1816308Y205012D03*
G54D62*
X71307Y1535961D03*
X107050D03*
X118703Y1370083D03*
X151303D03*
X184003D03*
X216903D03*
X249703D03*
X252353Y660034D03*
X285083Y694275D03*
X283303Y1323937D03*
X317853Y714425D03*
X316199Y1323909D03*
X350913Y714157D03*
X349103Y1323852D03*
X383953Y714225D03*
X381903Y1324052D03*
X416953Y696425D03*
X414485Y1343383D03*
X449353Y671825D03*
X481953Y645325D03*
X515253Y611225D03*
X726259Y1388092D03*
X759041Y1388192D03*
X1090441Y1370064D03*
X1123041D03*
X1155741D03*
X1188641D03*
X1221441D03*
X1259432Y1323918D03*
X1292328Y1323890D03*
X1325232Y1323833D03*
X1362905Y629368D03*
X1358032Y1324033D03*
X1395605Y662268D03*
X1390614Y1343364D03*
X1428205Y694848D03*
X1461123Y714425D03*
X1494205Y714593D03*
X1527005Y714425D03*
X1560135Y692485D03*
X1592905Y658716D03*
X1625905Y639716D03*
X1673992Y1387381D03*
X1706774Y1387481D03*
X1758590Y1568997D03*
X1794333D03*
G54D209*
X702806Y588934D03*
X700246D03*
Y606060D03*
X702806D03*
G54D191*
X572297Y149226D03*
Y157494D03*
X589423Y149226D03*
Y157494D03*
X842562Y168064D03*
Y176332D03*
X859688D03*
Y168064D03*
X1594537Y295328D03*
Y303596D03*
X1611663Y295328D03*
Y303596D03*
G54D218*
X711269Y1643326D03*
Y1666358D03*
X740205Y1643326D03*
Y1666358D03*
G54D281*
X1658169Y414202D03*
G54D137*
X329219Y220874D03*
Y239378D03*
X649319Y219363D03*
Y237867D03*
X791526Y128244D03*
Y146748D03*
X882183Y216681D03*
Y235185D03*
G54D236*
X821993Y539872D03*
X821347Y557607D03*
Y565087D03*
X829867Y536132D03*
Y543612D03*
X829221Y561347D03*
X1160163Y1441260D03*
Y1448740D03*
X1168037Y1445000D03*
X1667635Y210191D03*
X1675509Y206451D03*
Y213931D03*
G54D290*
X1787993Y194161D03*
Y196130D03*
Y198098D03*
X1806497Y194161D03*
Y200067D03*
Y198098D03*
Y196130D03*
Y202035D03*
G54D227*
X776718Y1575473D03*
Y1589253D03*
X794436Y1575473D03*
Y1589253D03*
X818718Y1575473D03*
Y1589253D03*
X836436Y1575473D03*
Y1589253D03*
X860718Y1575473D03*
Y1589253D03*
X878436Y1575473D03*
Y1589253D03*
X902718Y1575473D03*
Y1589253D03*
X920436Y1575473D03*
Y1589253D03*
G54D35*
X45951Y522792D03*
Y524760D03*
Y526729D03*
Y528697D03*
Y530666D03*
Y532634D03*
X60715Y522792D03*
Y532634D03*
Y530666D03*
Y528697D03*
Y526729D03*
Y524760D03*
X408943Y1605835D03*
Y1607804D03*
Y1609772D03*
Y1611741D03*
Y1613709D03*
Y1615678D03*
Y1617646D03*
Y1619615D03*
X427643Y1605835D03*
Y1607804D03*
Y1609772D03*
Y1611741D03*
Y1613709D03*
Y1615678D03*
Y1617646D03*
Y1619615D03*
X1116166Y1640051D03*
Y1642020D03*
Y1643988D03*
Y1645957D03*
Y1647925D03*
Y1649894D03*
Y1651862D03*
Y1653831D03*
X1134866Y1640051D03*
Y1642020D03*
Y1643988D03*
Y1645957D03*
Y1647925D03*
Y1649894D03*
Y1651862D03*
Y1653831D03*
G54D155*
X439169Y106684D03*
X437200D03*
X435232D03*
X433263D03*
X431295D03*
X429326D03*
Y141330D03*
X431295D03*
X433263D03*
X435232D03*
X437200D03*
X439169D03*
X452948Y106684D03*
X450980D03*
X449011D03*
X447043D03*
X445074D03*
X443106D03*
X441137D03*
Y141330D03*
X443106D03*
X445074D03*
X447043D03*
X449011D03*
X450980D03*
X452948D03*
X458854Y106684D03*
X456885D03*
X454917D03*
Y141330D03*
X456885D03*
X458854D03*
G54D254*
X961084Y1547766D03*
Y1553882D03*
X992696Y1547782D03*
Y1553898D03*
X1024296Y1547782D03*
Y1553898D03*
X1055896Y1547782D03*
Y1553898D03*
X1091434Y1542225D03*
Y1559343D03*
G54D80*
X139774Y1665000D03*
G54D26*
X34296Y517025D03*
X34580Y1497914D03*
Y1502214D03*
X39849Y282916D03*
Y277798D03*
X37984Y288500D03*
X39849Y312916D03*
Y307798D03*
X46984Y303500D03*
X41117Y1622896D03*
Y1626896D03*
X38411Y1668587D03*
Y1663587D03*
X62709Y268223D03*
X62839Y280357D03*
Y276357D03*
Y272357D03*
X67484Y290000D03*
X62839Y310357D03*
X53984Y303500D03*
X64680Y1552869D03*
X77238Y157191D03*
Y161191D03*
Y165191D03*
X68592Y423746D03*
X75117Y521613D03*
Y525513D03*
Y543213D03*
Y539313D03*
X81680Y1549369D03*
X85085Y140950D03*
X84858Y386502D03*
X84875Y376026D03*
X90039Y1307499D03*
X90059Y1311619D03*
X89984Y1440000D03*
Y1444500D03*
Y1448500D03*
X86967Y1663138D03*
X86926Y1667127D03*
X88404Y1698511D03*
Y1702511D03*
X88241Y1724331D03*
Y1720331D03*
X104738Y153691D03*
Y158191D03*
X108949Y1385562D03*
X109984Y1414500D03*
X98984Y1412500D03*
Y1408000D03*
Y1417000D03*
Y1421500D03*
Y1444500D03*
Y1448500D03*
X98495Y1552796D03*
X107577Y1597797D03*
X115837Y1670313D03*
Y1674313D03*
X117484Y1712450D03*
X137961Y679290D03*
Y675290D03*
X130401Y1382305D03*
X141549Y1385562D03*
X132552Y1709346D03*
X139802Y1709166D03*
X144476Y526997D03*
X147984Y1433500D03*
Y1429500D03*
Y1437500D03*
X152837Y1670087D03*
X146837Y1682587D03*
X142751Y1718241D03*
X171344Y400560D03*
X163101Y1382305D03*
X165799Y1726500D03*
X177584Y412350D03*
X174249Y1385562D03*
X174984Y1715000D03*
Y1721000D03*
X195904Y144962D03*
X196984Y149000D03*
X197484Y156500D03*
X196001Y1382305D03*
X207149Y1385562D03*
X213557Y1419187D03*
X208984Y1707000D03*
X209299Y1723000D03*
X223964Y120662D03*
Y124662D03*
X225336Y148750D03*
X220984Y156500D03*
X227504Y206820D03*
X228801Y1382305D03*
X245204Y71862D03*
X232117Y571129D03*
X235770Y711602D03*
X239949Y1385562D03*
X250281Y111743D03*
X259645Y140882D03*
X250524Y224370D03*
X251111Y640909D03*
X274940Y74536D03*
X270034Y142892D03*
X262795Y144882D03*
X270037Y159203D03*
Y155203D03*
X263194Y207660D03*
X272984Y215000D03*
X264984Y221500D03*
X270903Y611172D03*
X265075Y644555D03*
X274482Y676901D03*
X273549Y1339416D03*
X276751Y99183D03*
X279884Y136962D03*
X279984Y207000D03*
Y211000D03*
X286775Y570398D03*
X279885Y585178D03*
X285341Y674150D03*
X298431Y75673D03*
X301150Y71128D03*
X299537Y156203D03*
Y151703D03*
X297805Y678796D03*
X295297Y1336131D03*
X320041Y91803D03*
X318984Y263000D03*
X317127Y694525D03*
X307212Y711142D03*
X306445Y1339388D03*
X325526Y69863D03*
X328875Y545521D03*
X331713Y566086D03*
X330575Y698946D03*
X328201Y1336074D03*
X337398Y165170D03*
X346200Y225070D03*
X341984Y285000D03*
X339982Y731292D03*
X339349Y1339331D03*
X355399Y215325D03*
X355417Y211407D03*
X360984Y307500D03*
X359091Y550415D03*
X356641Y562415D03*
Y566415D03*
Y570415D03*
Y574415D03*
X363635Y698678D03*
X361001Y1336274D03*
X366680Y130165D03*
X373947Y158028D03*
X368799Y211361D03*
Y219361D03*
X376529Y225145D03*
X368799Y215361D03*
X376529Y228645D03*
X377039Y243615D03*
X367616Y617438D03*
X373042Y731024D03*
X372149Y1339531D03*
X374246Y1387697D03*
X389477Y142937D03*
X384072Y280370D03*
Y294370D03*
X394484Y311500D03*
X398890Y134980D03*
X395780Y138980D03*
X408625Y148300D03*
X396984Y304000D03*
X402855Y551915D03*
X396675Y698746D03*
X406082Y731092D03*
X404731Y1358862D03*
X407490Y1631219D03*
X408984Y1645500D03*
Y1653500D03*
X422477Y59935D03*
X422321Y71665D03*
Y66865D03*
X423285Y99148D03*
X419735Y104148D03*
X415625Y144300D03*
Y148300D03*
X417424Y235442D03*
X418199Y250165D03*
Y258165D03*
Y266165D03*
X418650Y1006123D03*
Y1009864D03*
Y1013604D03*
Y1028564D03*
Y1021084D03*
Y1024824D03*
Y1017344D03*
X411984Y1637000D03*
X416984Y1657500D03*
X429675Y680946D03*
X439082Y713292D03*
X428100Y1014766D03*
X437929Y1014745D03*
X437925Y1018879D03*
X428082D03*
X437925Y1023013D03*
X428082D03*
X452389Y270911D03*
X446783Y1014745D03*
Y1018879D03*
Y1023013D03*
X441484Y1604200D03*
Y1600200D03*
X444984Y1622700D03*
Y1618700D03*
X465712Y70016D03*
X468880Y239764D03*
Y227764D03*
Y231764D03*
Y247764D03*
X462075Y656346D03*
X457019Y1014745D03*
Y1018879D03*
Y1023013D03*
X467984Y1668000D03*
Y1659500D03*
Y1676000D03*
X468484Y1697000D03*
X475337Y60029D03*
X475267Y55135D03*
X475337Y64975D03*
X476609Y90574D03*
Y105574D03*
Y100574D03*
Y95574D03*
X476674Y119644D03*
Y115644D03*
X476609Y110574D03*
X476674Y123644D03*
X476412Y284738D03*
Y280858D03*
X484949Y578572D03*
X471482Y688692D03*
X475484Y1655500D03*
Y1672000D03*
X472984Y1680000D03*
X475484Y1701000D03*
Y1706500D03*
Y1714500D03*
X492981Y171625D03*
X492166Y193516D03*
Y189516D03*
X486237Y206827D03*
X489168Y233000D03*
X497518Y238119D03*
X494675Y629846D03*
X500716Y193516D03*
Y185516D03*
X508991D03*
X500716Y189516D03*
X504260Y205285D03*
X511260Y202404D03*
X504082Y662192D03*
X529484Y432500D03*
X527975Y595746D03*
X544680Y195256D03*
X539484Y445500D03*
X537382Y628092D03*
X554320Y152742D03*
X559062Y193541D03*
X546472Y218441D03*
Y230441D03*
Y239566D03*
X556157Y399586D03*
Y414274D03*
Y423949D03*
X553484Y451000D03*
X547221Y663689D03*
X574220Y235821D03*
X563412Y293738D03*
Y289858D03*
X563484Y451000D03*
X572984Y471500D03*
X561984Y477500D03*
X572984Y475500D03*
X586687Y164356D03*
Y169415D03*
X578521Y193516D03*
X578536Y197481D03*
X581008Y261171D03*
X586107Y411846D03*
Y423949D03*
Y435949D03*
X574984Y462000D03*
X586690Y454242D03*
X574984Y466000D03*
X579984Y475500D03*
Y479500D03*
X603251Y136408D03*
X603254Y132270D03*
X603253Y141640D03*
X594007Y208991D03*
X594013Y221277D03*
Y217277D03*
Y225277D03*
Y229277D03*
X593294Y400287D03*
Y404287D03*
X593611Y458461D03*
X593690Y454242D03*
X593487Y468893D03*
X593505Y479631D03*
X596984Y493500D03*
X603255Y1266598D03*
Y1262598D03*
X605984Y412000D03*
X614984Y440000D03*
X623513Y221777D03*
Y226277D03*
X632905Y474020D03*
X630386Y1357114D03*
X622343Y1367166D03*
X622261Y1386732D03*
X646145Y473905D03*
X644884Y1728000D03*
Y1722138D03*
Y1717138D03*
Y1733000D03*
X649298Y166053D03*
Y161862D03*
X649350Y174201D03*
X649298Y170053D03*
X655484Y390000D03*
X659424Y461818D03*
X659407Y457755D03*
X653549Y486941D03*
X658720Y1371199D03*
X658652Y1378931D03*
X658686Y1375061D03*
X656284Y1698400D03*
Y1712084D03*
X651884Y1728000D03*
Y1717138D03*
Y1722138D03*
Y1733000D03*
X675529Y401567D03*
Y409320D03*
Y405488D03*
X675484Y457862D03*
Y453862D03*
Y461862D03*
Y477862D03*
Y465862D03*
X675400Y474268D03*
X675484Y482862D03*
X664439Y486941D03*
X664301Y495126D03*
X669770Y504895D03*
X677770D03*
X668484Y529500D03*
X674084Y1308002D03*
X665484Y1708184D03*
X683437Y115868D03*
X683261Y1530526D03*
Y1526526D03*
X680777Y1639704D03*
Y1643904D03*
X705124Y1560573D03*
X705094Y1580523D03*
X704984Y1608500D03*
Y1600500D03*
X705625Y1616656D03*
X699901Y1670408D03*
X699939Y1674429D03*
X699823Y1678474D03*
X709907Y103308D03*
X713184Y157762D03*
X732977Y90998D03*
X733007Y95158D03*
X738139Y1400414D03*
X728345Y1614743D03*
X748719Y142050D03*
X751184Y167537D03*
X760102Y89348D03*
X754617Y111288D03*
X759751Y276322D03*
X766727Y299279D03*
X755094Y1576023D03*
Y1589023D03*
Y1584023D03*
X766134Y1591733D03*
X760146Y1693369D03*
X777773Y158026D03*
X777787Y153728D03*
X780527Y299279D03*
X781984Y371000D03*
Y364000D03*
X774984D03*
X778153Y419464D03*
X778136Y455344D03*
Y463344D03*
Y459344D03*
Y476344D03*
Y472344D03*
Y487344D03*
Y491344D03*
Y499344D03*
Y495344D03*
X791250Y267822D03*
Y281822D03*
X792586Y415344D03*
X792484Y407500D03*
X792636Y439344D03*
Y451344D03*
Y463344D03*
Y459344D03*
Y455344D03*
Y471344D03*
X792805Y467646D03*
X793146Y483458D03*
X793363Y479511D03*
X792984Y507000D03*
X795330Y1328662D03*
X808543Y386791D03*
X808550Y381020D03*
Y376753D03*
X801484Y392500D03*
X809559Y422687D03*
X809370Y431344D03*
X809286Y463578D03*
X809198Y449802D03*
X809417Y471344D03*
X809530Y476159D03*
X809417Y487344D03*
X809486Y491344D03*
X809530Y480159D03*
X809484Y504000D03*
X809603Y495344D03*
X809484Y512000D03*
Y516000D03*
X811484Y534500D03*
X811192Y541448D03*
X807348Y1340762D03*
Y1336334D03*
X802484Y1330000D03*
X807755Y1351988D03*
X810895Y1364193D03*
X807634Y1574633D03*
Y1590633D03*
Y1598633D03*
Y1606633D03*
X823903Y415344D03*
Y419344D03*
X823895Y423099D03*
X823903Y455344D03*
X823842Y463578D03*
Y471344D03*
Y467568D03*
X834446Y58632D03*
X831204Y166862D03*
Y176362D03*
X838984Y393000D03*
X830167Y405347D03*
X834984Y471000D03*
X830652Y497912D03*
X851804Y162762D03*
X843685Y490567D03*
X843721Y486478D03*
X843684Y482128D03*
X849241Y507106D03*
X843570Y494661D03*
X856003Y494585D03*
X855809Y503154D03*
X856075Y498861D03*
X849634Y1574633D03*
Y1590633D03*
Y1598633D03*
Y1606633D03*
X859287Y269057D03*
X859317Y273217D03*
X859205Y384030D03*
X861984Y395500D03*
X871504Y418720D03*
X874204Y166362D03*
X882204Y171362D03*
Y176862D03*
X884209Y187449D03*
X884199Y183169D03*
X886912Y267407D03*
X880899Y289439D03*
X887984Y326000D03*
X888966Y1056033D03*
X891634Y1574633D03*
Y1590633D03*
Y1598633D03*
Y1606633D03*
X905265Y606915D03*
X919940Y570706D03*
X933634Y1582233D03*
Y1578233D03*
Y1586233D03*
X961109Y198171D03*
X948027Y585200D03*
X948715Y614150D03*
X947540Y628662D03*
X961961Y1498695D03*
X984608Y189347D03*
X987939Y260781D03*
Y271443D03*
X987568Y295641D03*
X991540Y516014D03*
Y521014D03*
Y526074D03*
Y531074D03*
X985327Y1498695D03*
X997396Y221233D03*
Y225233D03*
X1003818Y446175D03*
Y457175D03*
Y451675D03*
Y462675D03*
Y468175D03*
Y479175D03*
Y473675D03*
Y494175D03*
Y490175D03*
Y484675D03*
Y499675D03*
X1012794Y153868D03*
X1016704Y198999D03*
X1016679Y207423D03*
X1016604Y203099D03*
X1016679Y214423D03*
Y222423D03*
Y218423D03*
Y226423D03*
X1018318Y287311D03*
Y298311D03*
X1010186Y433426D03*
X1017041Y420902D03*
X1014248Y484155D03*
X1011690Y510304D03*
X1015984Y560500D03*
X1008693Y1498695D03*
X1024443Y397726D03*
X1024484Y566000D03*
X1032059Y1498695D03*
X1045586Y1646205D03*
X1045454Y1652082D03*
X1058001Y406560D03*
X1058964Y490037D03*
X1060630Y1311203D03*
Y1307203D03*
X1055425Y1498695D03*
X1068730Y445499D03*
X1068780Y457959D03*
X1068748Y453655D03*
Y449655D03*
X1068778Y462525D03*
X1077694Y457959D03*
X1068778Y467000D03*
Y471500D03*
X1068748Y479655D03*
X1080687Y1385543D03*
X1078791Y1498695D03*
X1093422Y446105D03*
Y440605D03*
Y462605D03*
Y457105D03*
Y451605D03*
Y468105D03*
X1086422Y472105D03*
X1093422Y489641D03*
Y484605D03*
Y494641D03*
X1094323Y1633726D03*
X1094365Y1629945D03*
X1101932Y479355D03*
X1102139Y1382286D03*
X1102157Y1498695D03*
X1102507Y1634400D03*
X1102700Y1630123D03*
X1101984Y1639000D03*
X1113287Y1385543D03*
X1129717Y52651D03*
X1136890Y52599D03*
X1136122Y56512D03*
X1136389Y380533D03*
Y385698D03*
X1127393Y398020D03*
X1134839Y1382286D03*
X1150302Y74738D03*
X1155177Y204835D03*
Y209835D03*
X1147722Y489819D03*
X1145987Y1385543D03*
X1150367Y1436579D03*
X1160622Y461691D03*
Y457691D03*
Y449691D03*
Y453691D03*
Y465691D03*
Y469691D03*
Y481691D03*
X1167739Y1382286D03*
X1174913Y89556D03*
Y93556D03*
X1182675Y95864D03*
X1172016Y580602D03*
X1172076Y584622D03*
X1178887Y1385543D03*
X1184084Y1433000D03*
X1195771Y61515D03*
X1195871Y57015D03*
X1195791Y52815D03*
X1188972Y87125D03*
Y91125D03*
X1195186Y164987D03*
Y160987D03*
X1191411Y436202D03*
Y444202D03*
Y452202D03*
X1200599Y1382088D03*
X1199984Y1396500D03*
Y1401000D03*
Y1410000D03*
Y1405500D03*
Y1424000D03*
X1191084Y1428500D03*
Y1433000D03*
X1199984Y1437500D03*
Y1447500D03*
Y1442500D03*
X1192839Y1673050D03*
X1192521Y1697850D03*
X1199521D03*
X1213065Y94846D03*
X1205240Y133866D03*
Y128748D03*
X1205496Y177187D03*
Y181187D03*
X1205527Y188942D03*
X1202911Y460202D03*
X1202971Y465272D03*
X1203047Y470376D03*
X1211687Y1385543D03*
X1210984Y1401000D03*
X1208181Y1673059D03*
X1207863Y1697859D03*
X1214863D03*
X1244677Y145239D03*
X1239938Y447255D03*
Y443255D03*
X1244801Y1418462D03*
X1244843Y1422362D03*
X1257931Y464372D03*
X1248811Y468152D03*
X1258984Y765000D03*
X1249678Y1339397D03*
X1261091Y155730D03*
Y164051D03*
Y160051D03*
Y176051D03*
Y180551D03*
Y168051D03*
Y172051D03*
Y185051D03*
X1273533Y390884D03*
X1265484Y390500D03*
X1265686Y411125D03*
Y407125D03*
Y415125D03*
X1271426Y1336112D03*
X1275595Y150030D03*
X1289591Y162051D03*
Y166051D03*
Y171551D03*
Y184051D03*
X1282574Y1339369D03*
X1284584Y1430000D03*
Y1434000D03*
X1298177Y133739D03*
Y125739D03*
Y129739D03*
Y145739D03*
X1293186Y403625D03*
Y408125D03*
X1296240Y552147D03*
X1294850Y597013D03*
X1304330Y1336055D03*
X1307126Y537299D03*
X1307242Y556545D03*
X1315478Y1339312D03*
X1346244Y674443D03*
X1337130Y1336255D03*
X1348278Y1339512D03*
X1371168Y100509D03*
X1375627Y613889D03*
X1369890Y1355715D03*
X1385034Y646235D03*
X1380860Y1358843D03*
X1391977Y1670391D03*
X1384977Y1674391D03*
X1387529Y1704038D03*
X1385288Y1733118D03*
X1399741Y642765D03*
X1408327Y646789D03*
X1394792Y1009863D03*
Y1013603D03*
X1404224Y1014744D03*
X1394792Y1006122D03*
X1404224Y1018878D03*
Y1023012D03*
X1394792Y1017343D03*
Y1028563D03*
Y1024823D03*
Y1021083D03*
X1408117Y1622167D03*
X1401117Y1626167D03*
X1404967Y1630167D03*
X1417734Y679135D03*
X1422925Y1014744D03*
X1414071D03*
X1422925Y1023012D03*
X1414067Y1018878D03*
X1422925D03*
X1414067Y1023012D03*
X1421799Y1642967D03*
X1435103Y244450D03*
X1433741Y675765D03*
X1433161Y1014744D03*
Y1023012D03*
Y1018878D03*
X1435793Y1609966D03*
X1426781Y1619504D03*
Y1613966D03*
X1435981Y1619566D03*
X1448103Y244450D03*
X1440927Y679369D03*
X1450334Y711715D03*
X1467889Y61563D03*
X1458726Y128242D03*
X1461741Y564977D03*
X1465241Y695265D03*
X1474889Y61563D03*
X1469741Y548977D03*
Y552977D03*
Y544977D03*
Y556977D03*
Y560977D03*
Y564977D03*
X1473845Y698946D03*
X1483252Y731292D03*
X1513741Y543977D03*
X1506927Y698946D03*
X1526803Y201250D03*
X1516334Y731292D03*
X1542001Y300816D03*
Y308816D03*
Y304816D03*
X1539727Y698946D03*
X1549848Y284575D03*
X1549134Y731292D03*
X1550158Y1266271D03*
X1550161Y1282188D03*
Y1278188D03*
Y1286188D03*
X1569501Y297316D03*
Y301816D03*
X1573127Y531220D03*
X1572857Y677006D03*
X1564972Y1273445D03*
X1582264Y709352D03*
X1584756Y1302278D03*
X1598937Y225250D03*
X1613603Y542733D03*
X1605627Y643237D03*
X1615034Y675583D03*
X1625426Y282728D03*
Y278520D03*
X1625393Y286742D03*
X1618793Y530739D03*
X1632733Y1420450D03*
X1632651Y1444016D03*
Y1440016D03*
X1645672Y627206D03*
X1638627Y624237D03*
X1637817Y1306874D03*
X1640974Y1410398D03*
X1642651Y1442228D03*
X1658009Y141762D03*
Y146762D03*
Y151762D03*
Y161762D03*
X1648034Y656583D03*
X1659650Y696318D03*
X1669240Y1432215D03*
X1669274Y1428345D03*
X1669308Y1424483D03*
X1669326Y1420567D03*
X1685872Y1399703D03*
X1691135Y1559526D03*
Y1563526D03*
X1704778Y373773D03*
Y369773D03*
X1702868Y401485D03*
X1695011Y1696422D03*
X1717674Y364962D03*
X1712818Y666238D03*
Y662238D03*
X1725402Y112867D03*
X1733063Y1530950D03*
Y1535250D03*
X1729947Y1663465D03*
Y1667965D03*
Y1658965D03*
Y1672465D03*
X1739793Y85339D03*
X1751872Y100307D03*
X1749094Y305106D03*
X1742981Y1435005D03*
X1751963Y1585905D03*
X1741947Y1653965D03*
X1738413Y1649456D03*
X1763552Y76797D03*
X1763522Y72637D03*
X1756420Y85407D03*
X1754204Y372452D03*
X1781559Y190799D03*
X1768963Y1582405D03*
X1771412Y1666984D03*
X1771373Y1670514D03*
X1770947Y1685465D03*
X1771292Y1674057D03*
X1770947Y1681702D03*
Y1678172D03*
Y1689965D03*
X1790647Y70987D03*
X1785162Y92927D03*
X1792874Y146834D03*
Y151834D03*
Y165834D03*
X1795255Y367866D03*
X1787783Y403932D03*
X1795255Y390411D03*
X1787783Y410432D03*
Y418932D03*
Y425432D03*
X1785778Y1585832D03*
X1825064Y147834D03*
X1818064Y151834D03*
X1820216Y371329D03*
X1826153Y383952D03*
Y379552D03*
X1820053Y395552D03*
X1819283Y407932D03*
X1818783Y421432D03*
Y427432D03*
X1818776Y431678D03*
X1827216Y371329D03*
Y367359D03*
X1847775Y161834D03*
G54D173*
X474070Y295282D03*
X561070Y304282D03*
G54D119*
X274301Y115216D03*
X707457Y119341D03*
X1749422Y116340D03*
G54D272*
X1249152Y60384D03*
X1431175Y87432D03*
G54D245*
X900240Y1143460D03*
X947265D03*
G54D44*
X71121Y1493645D03*
Y1511755D03*
X82974Y1326471D03*
Y1344581D03*
X99696Y1493645D03*
Y1511755D03*
X227957Y683164D03*
Y701274D03*
X438700Y1300918D03*
Y1319028D03*
X553787Y622456D03*
Y640566D03*
X1054712Y1326452D03*
Y1344562D03*
X1339222Y643716D03*
Y661826D03*
X1414559Y1300319D03*
Y1318429D03*
X1664127Y665084D03*
Y683194D03*
X1758404Y1526681D03*
Y1544791D03*
X1786979Y1526681D03*
Y1544791D03*
G54D263*
X1024961Y543499D03*
Y545074D03*
Y546649D03*
Y548224D03*
Y549799D03*
X1030079D03*
Y548224D03*
Y546649D03*
Y545074D03*
Y543499D03*
G54D71*
X108681Y1424839D03*
Y1426413D03*
Y1427988D03*
Y1429563D03*
Y1431138D03*
Y1432713D03*
Y1434287D03*
Y1435862D03*
Y1437437D03*
Y1439012D03*
Y1440587D03*
Y1442161D03*
X131319Y1432713D03*
Y1431138D03*
Y1429563D03*
Y1427988D03*
Y1426413D03*
Y1424839D03*
Y1442161D03*
Y1440587D03*
Y1439012D03*
Y1437437D03*
Y1435862D03*
Y1434287D03*
X1209681Y1411339D03*
Y1412913D03*
Y1414488D03*
Y1416063D03*
Y1417638D03*
Y1419213D03*
Y1420787D03*
Y1422362D03*
Y1423937D03*
Y1425512D03*
Y1427087D03*
Y1428661D03*
X1232319Y1417638D03*
Y1416063D03*
Y1414488D03*
Y1412913D03*
Y1411339D03*
Y1428661D03*
Y1427087D03*
Y1425512D03*
Y1423937D03*
Y1422362D03*
Y1420787D03*
Y1419213D03*
G54D53*
X66854Y1605956D03*
X65279D03*
X63704D03*
X62129D03*
X60554D03*
X58980D03*
X57405D03*
X55830D03*
X54255D03*
X52680D03*
Y1624854D03*
X54255D03*
X55830D03*
X57405D03*
X58980D03*
X60554D03*
X62129D03*
X63704D03*
X65279D03*
X66854D03*
X631608Y1362808D03*
X633183D03*
Y1381706D03*
X631608D03*
X634758Y1362808D03*
X636333D03*
X637908D03*
X639482D03*
X641057D03*
X642632D03*
X644207D03*
X645782D03*
X634758Y1381706D03*
X636333D03*
X637908D03*
X639482D03*
X641057D03*
X642632D03*
X644207D03*
X645782D03*
X1642196Y1416092D03*
X1643771D03*
X1645346D03*
X1646921D03*
X1645346Y1434990D03*
X1646921D03*
X1643771D03*
X1642196D03*
X1648496Y1416092D03*
X1650070D03*
X1651645D03*
X1653220D03*
X1654795D03*
X1656370D03*
X1648496Y1434990D03*
X1650070D03*
X1651645D03*
X1653220D03*
X1654795D03*
X1656370D03*
X1750116Y1659507D03*
X1748542D03*
X1746967D03*
X1745392D03*
X1743817D03*
X1742242D03*
Y1678405D03*
X1743817D03*
X1745392D03*
X1746967D03*
X1748542D03*
X1750116D03*
X1756416Y1659507D03*
X1754841D03*
X1753266D03*
X1751691D03*
Y1678405D03*
X1753266D03*
X1754841D03*
X1756416D03*
G54D164*
X483967Y212897D03*
X576672Y228251D03*
G54D182*
X507261Y135722D03*
Y134147D03*
Y149895D03*
Y148321D03*
Y146746D03*
Y145171D03*
Y143596D03*
Y142021D03*
Y140447D03*
Y138872D03*
Y137297D03*
Y156195D03*
Y154620D03*
Y153045D03*
Y151470D03*
X537575Y134147D03*
Y135722D03*
Y137297D03*
Y138872D03*
Y140447D03*
Y142021D03*
Y143596D03*
Y145171D03*
Y146746D03*
Y148321D03*
Y149895D03*
Y156195D03*
Y151470D03*
Y153045D03*
Y154620D03*
G54D128*
X283817Y585179D03*
G54D90*
X131703Y1680945D03*
G54D282*
X1653051Y414202D03*
G54D147*
X385443Y256059D03*
Y271807D03*
X846352Y256772D03*
Y272520D03*
X974408Y153162D03*
Y168910D03*
G54D72*
X120000Y1433500D03*
X1221000Y1420000D03*
G54D54*
X59767Y1615405D03*
X638695Y1372257D03*
X1649283Y1425541D03*
X1749329Y1668956D03*
G54D219*
X733380Y1582361D03*
X785577Y1582363D03*
X827577D03*
X869577D03*
X911577D03*
G54D81*
X139774Y1671300D03*
Y1669725D03*
Y1666575D03*
Y1668150D03*
Y1674449D03*
Y1672874D03*
Y1677599D03*
Y1676024D03*
G54D237*
X842596Y58448D03*
X840037D03*
Y81448D03*
X842596D03*
X847715Y58448D03*
X845156D03*
Y81448D03*
X847715D03*
G54D192*
X572297Y152080D03*
Y154640D03*
X589423D03*
Y152080D03*
X842562Y170918D03*
Y173478D03*
X859688D03*
Y170918D03*
X1594537Y298182D03*
Y300742D03*
X1611663Y298182D03*
Y300742D03*
G54D246*
X901650Y1175243D03*
Y1219735D03*
X956504Y1175243D03*
Y1219735D03*
G54D36*
X50773Y754595D03*
Y775855D03*
G54D273*
X1259835Y127553D03*
Y130053D03*
Y132553D03*
Y135053D03*
Y137553D03*
Y140053D03*
Y142553D03*
Y145053D03*
X1280741Y135053D03*
Y132553D03*
Y130053D03*
Y127553D03*
Y145053D03*
Y142553D03*
Y140053D03*
Y137553D03*
G54D138*
X335823Y270260D03*
X326177D03*
X335823Y277740D03*
X326177Y274000D03*
Y277740D03*
X382323Y311240D03*
Y303760D03*
X372677D03*
Y307500D03*
Y311240D03*
X604494Y432209D03*
X594848D03*
X604494Y439689D03*
X594848Y435949D03*
Y439689D03*
X797551Y384932D03*
Y377452D03*
X787905D03*
Y381192D03*
Y384932D03*
X1246555Y90470D03*
X1236909D03*
X1246555Y97950D03*
X1236909Y94210D03*
Y97950D03*
X1678258Y220857D03*
X1668612D03*
Y224597D03*
X1678258Y228337D03*
X1668612D03*
G54D18*
X14092Y290137D03*
Y298207D03*
X28068Y290137D03*
Y298207D03*
X44692Y290137D03*
Y298207D03*
X58668Y290137D03*
Y298207D03*
X1632822Y221842D03*
Y229912D03*
X1646798Y221842D03*
Y229912D03*
G54D291*
X1796261Y189732D03*
X1794292D03*
X1792324D03*
X1802166D03*
X1800198D03*
X1798229D03*
G54D174*
X475251Y299219D03*
X562251Y308219D03*
G54D63*
X91454Y156791D03*
X286253Y154803D03*
X610229Y224877D03*
X823514Y136898D03*
X847479Y214391D03*
X1279902Y406725D03*
X1556217Y300416D03*
X1689073Y1686245D03*
X1734992Y370384D03*
G54D264*
X1091434Y1538875D03*
Y1562693D03*
G54D228*
X791280Y1297982D03*
Y1321012D03*
G54D27*
X26272Y1461614D03*
Y1478936D03*
X50272Y1461614D03*
Y1478936D03*
X74272Y1461614D03*
Y1478936D03*
X98272Y1461614D03*
Y1478936D03*
X692761Y1301317D03*
Y1318639D03*
X716639Y1301357D03*
Y1318679D03*
X740639Y1301357D03*
Y1318679D03*
X764639Y1301357D03*
Y1318679D03*
X891423Y1234759D03*
Y1252081D03*
X915423Y1234759D03*
Y1252081D03*
X950407Y1234759D03*
Y1252081D03*
X974407Y1234759D03*
Y1252081D03*
X1313500Y624839D03*
Y642161D03*
X1655872Y1300929D03*
Y1318251D03*
X1679872Y1300929D03*
Y1318251D03*
X1703872Y1300929D03*
Y1318251D03*
X1727667Y1300929D03*
Y1318251D03*
X1747479Y1487944D03*
Y1505266D03*
X1771479Y1487944D03*
Y1505266D03*
X1795479Y1487944D03*
Y1505266D03*
X1819479Y1487944D03*
Y1505266D03*
G54D183*
X512969Y130014D03*
X511394D03*
Y160328D03*
X512969D03*
X528717Y130014D03*
X527142D03*
X525568D03*
X523993D03*
X522418D03*
X520843D03*
X519268D03*
X517694D03*
X516119D03*
X514544D03*
X520843Y160328D03*
X522418D03*
X523993D03*
X525568D03*
X527142D03*
X528717D03*
X514544D03*
X516119D03*
X517694D03*
X519268D03*
X533442Y130014D03*
X531867D03*
X530292D03*
Y160328D03*
X531867D03*
X533442D03*
G54D255*
X968690Y1633144D03*
Y1659128D03*
X996314Y1633113D03*
Y1659097D03*
G54D165*
X481161Y214077D03*
X579478Y227071D03*
G54D45*
X65205Y1519505D03*
X100948D03*
X112601Y1353627D03*
X145201D03*
X177901D03*
X210801D03*
X243601D03*
X258455Y676490D03*
X277201Y1307481D03*
X291185Y710731D03*
X310097Y1307453D03*
X323955Y730881D03*
X343001Y1307396D03*
X357015Y730613D03*
X375801Y1307596D03*
X390055Y730681D03*
X408383Y1326927D03*
X423055Y712881D03*
X455455Y688281D03*
X488055Y661781D03*
X521355Y627681D03*
X720157Y1371636D03*
X752939Y1371736D03*
X1084339Y1353608D03*
X1116939D03*
X1149639D03*
X1182539D03*
X1215339D03*
X1253330Y1307462D03*
X1286226Y1307434D03*
X1319130Y1307377D03*
X1351930Y1307577D03*
X1369007Y645824D03*
X1384512Y1326908D03*
X1401707Y678724D03*
X1434307Y711304D03*
X1467225Y730881D03*
X1500307Y731049D03*
X1533107Y730881D03*
X1566237Y708941D03*
X1599007Y675172D03*
X1632007Y656172D03*
X1667890Y1370925D03*
X1700672Y1371025D03*
X1752488Y1552541D03*
X1788231D03*
G36*
G01X455114Y113180D02*
G02X454917Y112983I-197J0D01*
G01X451531D01*
G02X451334Y113180I0J197D01*
G01Y116566D01*
G02X451531Y116763I197J0D01*
G01X452974D01*
Y117550D01*
X451531D01*
G02X451334Y117747I0J197D01*
G01Y121133D01*
G02X451531Y121330I197J0D01*
G01X452974D01*
Y122117D01*
X451531D01*
G02X451334Y122314I0J197D01*
G01Y123757D01*
X450547D01*
Y122314D01*
G02X450350Y122117I-197J0D01*
G01X448907D01*
Y121330D01*
X450350D01*
G02X450547Y121133I0J-197D01*
G01Y117747D01*
G02X450350Y117550I-197J0D01*
G01X448907D01*
Y116763D01*
X450350D01*
G02X450547Y116566I0J-197D01*
G01Y113180D01*
G02X450350Y112983I-197J0D01*
G01X446964D01*
G02X446767Y113180I0J197D01*
G01Y116566D01*
G02X446964Y116763I197J0D01*
G01X448407D01*
Y117550D01*
X446964D01*
G02X446767Y117747I0J197D01*
G01Y121133D01*
G02X446964Y121330I197J0D01*
G01X448407D01*
Y122117D01*
X446964D01*
G02X446767Y122314I0J197D01*
G01Y123757D01*
X445980D01*
Y122314D01*
G02X445783Y122117I-197J0D01*
G01X444340D01*
Y121330D01*
X445783D01*
G02X445980Y121133I0J-197D01*
G01Y117747D01*
G02X445783Y117550I-197J0D01*
G01X444340D01*
Y116763D01*
X445783D01*
G02X445980Y116566I0J-197D01*
G01Y113180D01*
G02X445783Y112983I-197J0D01*
G01X442397D01*
G02X442200Y113180I0J197D01*
G01Y116566D01*
G02X442397Y116763I197J0D01*
G01X443840D01*
Y117550D01*
X442397D01*
G02X442200Y117747I0J197D01*
G01Y121133D01*
G02X442397Y121330I197J0D01*
G01X443840D01*
Y122117D01*
X442397D01*
G02X442200Y122314I0J197D01*
G01Y123757D01*
X441413D01*
Y122314D01*
G02X441216Y122117I-197J0D01*
G01X439773D01*
Y121330D01*
X441216D01*
G02X441413Y121133I0J-197D01*
G01Y117747D01*
G02X441216Y117550I-197J0D01*
G01X439773D01*
Y116763D01*
X441216D01*
G02X441413Y116566I0J-197D01*
G01Y113180D01*
G02X441216Y112983I-197J0D01*
G01X437830D01*
G02X437633Y113180I0J197D01*
G01Y116566D01*
G02X437830Y116763I197J0D01*
G01X439273D01*
Y117550D01*
X437830D01*
G02X437633Y117747I0J197D01*
G01Y121133D01*
G02X437830Y121330I197J0D01*
G01X439273D01*
Y122117D01*
X437830D01*
G02X437633Y122314I0J197D01*
G01Y123757D01*
X436846D01*
Y122314D01*
G02X436649Y122117I-197J0D01*
G01X435206D01*
Y121330D01*
X436649D01*
G02X436846Y121133I0J-197D01*
G01Y117747D01*
G02X436649Y117550I-197J0D01*
G01X435206D01*
Y116763D01*
X436649D01*
G02X436846Y116566I0J-197D01*
G01Y113180D01*
G02X436649Y112983I-197J0D01*
G01X433263D01*
G02X433066Y113180I0J197D01*
G01Y116566D01*
G02X433263Y116763I197J0D01*
G01X434706D01*
Y117550D01*
X433263D01*
G02X433066Y117747I0J197D01*
G01Y121133D01*
G02X433263Y121330I197J0D01*
G01X434706D01*
Y122117D01*
X433263D01*
G02X433066Y122314I0J197D01*
G01Y125700D01*
G02X433263Y125897I197J0D01*
G01X434706D01*
Y126684D01*
X433263D01*
G02X433066Y126881I0J197D01*
G01Y130267D01*
G02X433263Y130464I197J0D01*
G01X434706D01*
Y131251D01*
X433263D01*
G02X433066Y131448I0J197D01*
G01Y134834D01*
G02X433263Y135031I197J0D01*
G01X436649D01*
G02X436846Y134834I0J-197D01*
G01Y131448D01*
G02X436649Y131251I-197J0D01*
G01X435206D01*
Y130464D01*
X436649D01*
G02X436846Y130267I0J-197D01*
G01Y126881D01*
G02X436649Y126684I-197J0D01*
G01X435206D01*
Y125897D01*
X436649D01*
G02X436846Y125700I0J-197D01*
G01Y124257D01*
X437633D01*
Y125700D01*
G02X437830Y125897I197J0D01*
G01X439273D01*
Y126684D01*
X437830D01*
G02X437633Y126881I0J197D01*
G01Y130267D01*
G02X437830Y130464I197J0D01*
G01X439273D01*
Y131251D01*
X437830D01*
G02X437633Y131448I0J197D01*
G01Y134834D01*
G02X437830Y135031I197J0D01*
G01X441216D01*
G02X441413Y134834I0J-197D01*
G01Y131448D01*
G02X441216Y131251I-197J0D01*
G01X439773D01*
Y130464D01*
X441216D01*
G02X441413Y130267I0J-197D01*
G01Y126881D01*
G02X441216Y126684I-197J0D01*
G01X439773D01*
Y125897D01*
X441216D01*
G02X441413Y125700I0J-197D01*
G01Y124257D01*
X442200D01*
Y125700D01*
G02X442397Y125897I197J0D01*
G01X443840D01*
Y126684D01*
X442397D01*
G02X442200Y126881I0J197D01*
G01Y130267D01*
G02X442397Y130464I197J0D01*
G01X443840D01*
Y131251D01*
X442397D01*
G02X442200Y131448I0J197D01*
G01Y134834D01*
G02X442397Y135031I197J0D01*
G01X445783D01*
G02X445980Y134834I0J-197D01*
G01Y131448D01*
G02X445783Y131251I-197J0D01*
G01X444340D01*
Y130464D01*
X445783D01*
G02X445980Y130267I0J-197D01*
G01Y126881D01*
G02X445783Y126684I-197J0D01*
G01X444340D01*
Y125897D01*
X445783D01*
G02X445980Y125700I0J-197D01*
G01Y124257D01*
X446767D01*
Y125700D01*
G02X446964Y125897I197J0D01*
G01X448407D01*
Y126684D01*
X446964D01*
G02X446767Y126881I0J197D01*
G01Y130267D01*
G02X446964Y130464I197J0D01*
G01X448407D01*
Y131251D01*
X446964D01*
G02X446767Y131448I0J197D01*
G01Y134834D01*
G02X446964Y135031I197J0D01*
G01X450350D01*
G02X450547Y134834I0J-197D01*
G01Y131448D01*
G02X450350Y131251I-197J0D01*
G01X448907D01*
Y130464D01*
X450350D01*
G02X450547Y130267I0J-197D01*
G01Y126881D01*
G02X450350Y126684I-197J0D01*
G01X448907D01*
Y125897D01*
X450350D01*
G02X450547Y125700I0J-197D01*
G01Y124257D01*
X451334D01*
Y125700D01*
G02X451531Y125897I197J0D01*
G01X452974D01*
Y126684D01*
X451531D01*
G02X451334Y126881I0J197D01*
G01Y130267D01*
G02X451531Y130464I197J0D01*
G01X452974D01*
Y131251D01*
X451531D01*
G02X451334Y131448I0J197D01*
G01Y134834D01*
G02X451531Y135031I197J0D01*
G01X454917D01*
G02X455114Y134834I0J-197D01*
G01Y131448D01*
G02X454917Y131251I-197J0D01*
G01X453474D01*
Y130464D01*
X454917D01*
G02X455114Y130267I0J-197D01*
G01Y126881D01*
G02X454917Y126684I-197J0D01*
G01X453474D01*
Y125897D01*
X454917D01*
G02X455114Y125700I0J-197D01*
G01Y122314D01*
G02X454917Y122117I-197J0D01*
G01X453474D01*
Y121330D01*
X454917D01*
G02X455114Y121133I0J-197D01*
G01Y117747D01*
G02X454917Y117550I-197J0D01*
G01X453474D01*
Y116763D01*
X454917D01*
G02X455114Y116566I0J-197D01*
G01Y113180D01*
G37*
G54D129*
X286784Y585177D03*
G54D91*
X138003Y1680945D03*
G54D238*
X841742Y105951D03*
Y99651D03*
X850088Y105951D03*
Y99651D03*
G54D184*
X522418Y145171D03*
G54D82*
X136428Y1663229D03*
X134853D03*
X133278D03*
G54D265*
X1108894Y1627567D03*
Y1620087D03*
X1110000Y1689260D03*
Y1696740D03*
G54D274*
X1319667Y83687D03*
Y101327D03*
X1323604Y74869D03*
X1327541Y83687D03*
X1323604Y92509D03*
X1327541Y101327D03*
X1373745Y74869D03*
X1369808Y83687D03*
X1377682D03*
G54D19*
X14092Y292892D03*
Y295452D03*
X28068D03*
Y292892D03*
X44692D03*
Y295452D03*
X58668D03*
Y292892D03*
X1632822Y224597D03*
Y227157D03*
X1646798Y224597D03*
Y227157D03*
G54D28*
X47300Y277798D03*
Y280357D03*
Y282916D03*
X47260Y308541D03*
Y311100D03*
Y313659D03*
X54780Y282916D03*
Y280357D03*
Y277798D03*
X54740Y313659D03*
Y311100D03*
Y308541D03*
X384155Y152818D03*
Y157936D03*
X391635D03*
Y155377D03*
Y152818D03*
X603245Y401728D03*
Y404287D03*
Y406846D03*
X610725Y401728D03*
Y406846D03*
X1005169Y295634D03*
Y293075D03*
Y290516D03*
X997689D03*
Y293075D03*
Y295634D03*
X1810280Y146716D03*
X1802800D03*
Y149275D03*
X1810280Y151834D03*
X1802800D03*
X1805069Y366053D03*
Y368612D03*
Y371171D03*
X1805629Y385293D03*
Y387852D03*
Y390411D03*
X1805648Y418775D03*
X1798168D03*
X1805659Y410615D03*
Y408056D03*
Y405497D03*
X1798179D03*
Y408056D03*
Y410615D03*
X1805648Y423893D03*
Y421334D03*
X1798168D03*
Y423893D03*
X1812549Y371171D03*
Y366053D03*
X1813109Y385293D03*
Y390411D03*
G54D139*
X330934Y552397D03*
X328375D03*
X325816D03*
Y560271D03*
X328375D03*
X330934D03*
X1542675Y547341D03*
X1540116D03*
Y555215D03*
X1542675D03*
X1545234Y547341D03*
Y555215D03*
G54D148*
X389743Y482395D03*
X387184D03*
X384625D03*
Y491057D03*
X387184D03*
X389743D03*
G54D193*
X573782Y373868D03*
X565908D03*
X573782Y378986D03*
Y376427D03*
X565908D03*
Y378986D03*
X573782Y387227D03*
Y384668D03*
X565908D03*
Y387227D03*
X573782Y389786D03*
X565908D03*
X573782Y403717D03*
Y401158D03*
Y398599D03*
X565908D03*
Y401158D03*
Y403717D03*
X601908Y373868D03*
Y384668D03*
Y387227D03*
Y376427D03*
Y378986D03*
Y389786D03*
X609782Y373868D03*
Y387227D03*
Y384668D03*
Y378986D03*
Y376427D03*
Y389786D03*
G54D37*
X50773Y753020D03*
G54D46*
X59201Y1529938D03*
X94944D03*
X106597Y1364060D03*
X139197D03*
X171897D03*
X204797D03*
X237597D03*
X264459Y666057D03*
X271197Y1317914D03*
X297189Y700298D03*
X304093Y1317886D03*
X329959Y720448D03*
X336997Y1317829D03*
X363019Y720180D03*
X369797Y1318029D03*
X396059Y720248D03*
X402379Y1337360D03*
X429059Y702448D03*
X461459Y677848D03*
X494059Y651348D03*
X527359Y617248D03*
X714153Y1382069D03*
X746935Y1382169D03*
X1078335Y1364041D03*
X1110935D03*
X1143635D03*
X1176535D03*
X1209335D03*
X1247326Y1317895D03*
X1280222Y1317867D03*
X1313126Y1317810D03*
X1345926Y1318010D03*
X1375011Y635391D03*
X1378508Y1337341D03*
X1407711Y668291D03*
X1440311Y700871D03*
X1473229Y720448D03*
X1506311Y720616D03*
X1539111Y720448D03*
X1572241Y698508D03*
X1605011Y664739D03*
X1638011Y645739D03*
X1661886Y1381358D03*
X1694668Y1381458D03*
X1746484Y1562974D03*
X1782227D03*
G54D73*
X110770Y1662719D03*
X107620D03*
X110770D03*
X110775Y1657752D03*
D03*
X107625D03*
X113920Y1662719D03*
X113925Y1657752D03*
X134902Y671290D03*
X131752D03*
X138052D03*
X134902D03*
Y683290D03*
X131752D03*
X138052D03*
X134902D03*
X155710Y1679384D03*
X152560D03*
X155710D03*
Y1674239D03*
X152560D03*
X155710D03*
X169575Y670500D03*
D03*
X166425D03*
X169575Y676500D03*
D03*
X166425D03*
X158860Y1679384D03*
Y1674239D03*
X172725Y670500D03*
Y676500D03*
X235147Y127118D03*
X238297D03*
X273474Y1512220D03*
Y1516120D03*
X276624D03*
X279774D03*
X276624Y1512220D03*
Y1516120D03*
Y1512220D03*
X279774D03*
X404686Y1516120D03*
X407836D03*
X404686Y1512220D03*
X407836D03*
X401536D03*
X404686D03*
X401536Y1516120D03*
X404686D03*
X484080Y144392D03*
Y139492D03*
D03*
X480930D03*
X484080Y144392D03*
X480930D03*
X492080Y128942D03*
X495230D03*
X492080Y133942D03*
X495230D03*
X492080Y128942D03*
X488930D03*
X492080Y133942D03*
X488930D03*
X487230Y144392D03*
Y139492D03*
X540797Y1516120D03*
X543947D03*
X537647Y1512220D03*
X540797D03*
D03*
X543947D03*
X537647Y1516120D03*
X540797D03*
X573360Y122785D03*
X565210D03*
X568360D03*
X576510D03*
X672715Y1530526D03*
X675865D03*
X672715Y1526626D03*
X675865D03*
X669565Y1530526D03*
X672715D03*
X669565Y1526626D03*
X672715D03*
X1013620Y230423D03*
X1016770D03*
X1168957Y575602D03*
X1165807D03*
X1168957D03*
X1169000Y592673D03*
X1165850D03*
X1169000D03*
X1172107Y575602D03*
X1172150Y592673D03*
X1228118Y132739D03*
D03*
X1224968D03*
X1228118Y128239D03*
D03*
X1224968D03*
X1231268Y132739D03*
Y128239D03*
X1269437Y166051D03*
X1272587D03*
D03*
X1269437Y162051D03*
X1272587D03*
D03*
Y158051D03*
X1269437D03*
X1272587D03*
Y180565D03*
X1269437D03*
X1272587D03*
Y176051D03*
X1269437D03*
X1272587D03*
X1269437Y171551D03*
X1272587D03*
D03*
X1269437Y184987D03*
X1272587D03*
D03*
X1275737Y166051D03*
Y162051D03*
Y158051D03*
Y180565D03*
Y176051D03*
Y171551D03*
Y184987D03*
X1284497Y1549120D03*
X1287647D03*
X1281347D03*
X1284497D03*
X1281347Y1545220D03*
X1284497D03*
D03*
X1287647D03*
X1412559Y1549120D03*
X1415709D03*
X1409409D03*
X1412559D03*
X1409409Y1545220D03*
X1412559D03*
D03*
X1415709D03*
X1548671Y1549120D03*
X1551821D03*
X1548671Y1545220D03*
X1551821D03*
X1545521D03*
X1548671D03*
X1545521Y1549120D03*
X1548671D03*
X1677439Y1559626D03*
Y1563526D03*
X1680589D03*
X1683739D03*
X1680589Y1559626D03*
Y1563526D03*
Y1559626D03*
X1683739D03*
G54D283*
X1653642Y418139D03*
X1655610D03*
X1657578D03*
Y410265D03*
X1655610D03*
X1653642D03*
G54D256*
X989227Y378999D03*
X986668D03*
Y401047D03*
X989227D03*
X1004582Y378999D03*
X1002023D03*
X999464D03*
X996905D03*
X994345D03*
X991786D03*
Y401047D03*
X994345D03*
X996905D03*
X999464D03*
X1002023D03*
X1004582D03*
X1438312Y134818D03*
Y156866D03*
X1453667Y134818D03*
X1451108D03*
X1448549D03*
X1445989D03*
X1443430D03*
X1440871D03*
Y156866D03*
X1443430D03*
X1445989D03*
X1448549D03*
X1451108D03*
X1453667D03*
X1456226Y134818D03*
Y156866D03*
G54D55*
X64462Y1658400D03*
X66430D03*
X62493D03*
X60525D03*
X64462Y1673360D03*
X62493D03*
X60525D03*
X66430D03*
X68399Y1658400D03*
X70367D03*
X68399Y1673360D03*
X70367D03*
G54D292*
X1790355Y189682D03*
X1804135D03*
G54D157*
X426767Y109243D03*
Y111212D03*
Y113180D03*
Y115149D03*
Y117117D03*
Y119086D03*
Y121054D03*
Y123023D03*
Y124991D03*
Y126960D03*
Y128928D03*
Y130897D03*
Y132865D03*
Y134834D03*
Y136802D03*
Y138771D03*
X461413Y121054D03*
Y119086D03*
Y117117D03*
Y115149D03*
Y113180D03*
Y111212D03*
Y109243D03*
Y134834D03*
Y132865D03*
Y130897D03*
Y128928D03*
Y126960D03*
Y124991D03*
Y123023D03*
Y138771D03*
Y136802D03*
G54D175*
X476826Y304928D03*
X563826Y313928D03*
G54D64*
X99729Y289822D03*
Y310256D03*
X757184Y1722772D03*
X1072863Y1429176D03*
X1080970Y1660958D03*
X1299439Y92812D03*
X1550377Y581353D03*
G54D247*
X922441Y154311D03*
Y243799D03*
G54D166*
X481211Y215652D03*
Y217227D03*
X488297D03*
Y215652D03*
Y214077D03*
X509320Y212498D03*
Y214072D03*
X514832D03*
X572342Y223921D03*
Y225496D03*
Y227071D03*
X579428Y223921D03*
Y225496D03*
X796276Y1342737D03*
Y1341162D03*
Y1339587D03*
Y1338012D03*
Y1336438D03*
Y1345886D03*
Y1344312D03*
X905618Y1143945D03*
Y1145519D03*
Y1147094D03*
Y1148669D03*
Y1150244D03*
Y1151819D03*
Y1153393D03*
X952643Y1143945D03*
Y1145519D03*
Y1147094D03*
Y1148669D03*
Y1150244D03*
Y1151819D03*
Y1153393D03*
X1315411Y549885D03*
Y551459D03*
Y553034D03*
Y554609D03*
Y556184D03*
Y557759D03*
Y559333D03*
X1621536Y549540D03*
Y551114D03*
Y552689D03*
Y554264D03*
Y555839D03*
Y557414D03*
Y558988D03*
G54D229*
X785252Y1342245D03*
G54D257*
X999456Y193090D03*
G54D47*
X61760Y1535942D03*
X97503D03*
X109156Y1370064D03*
X141756D03*
X174456D03*
X207356D03*
X240156D03*
X261900Y660053D03*
X273756Y1323918D03*
X294630Y694294D03*
X306652Y1323890D03*
X327400Y714444D03*
X339556Y1323833D03*
X360460Y714176D03*
X372356Y1324033D03*
X393500Y714244D03*
X404938Y1343364D03*
X426500Y696444D03*
X458900Y671844D03*
X491500Y645344D03*
X524800Y611244D03*
X716712Y1388073D03*
X749494Y1388173D03*
X1080894Y1370045D03*
X1113494D03*
X1146194D03*
X1179094D03*
X1211894D03*
X1249885Y1323899D03*
X1282781Y1323871D03*
X1315685Y1323814D03*
X1348485Y1324014D03*
X1372452Y629387D03*
X1381067Y1343345D03*
X1405152Y662287D03*
X1437752Y694867D03*
X1470670Y714444D03*
X1503752Y714612D03*
X1536552Y714444D03*
X1569682Y692504D03*
X1602452Y658735D03*
X1635452Y639735D03*
X1664445Y1387362D03*
X1697227Y1387462D03*
X1749043Y1568978D03*
X1784786D03*
G54D239*
X849385Y1541015D03*
X949271Y1479729D03*
G54D293*
X1790206Y204003D03*
G54D266*
X1124186Y1546733D03*
X1119067D03*
X1121626D03*
X1119067Y1565237D03*
X1121626D03*
X1124186D03*
X1126745Y1546733D03*
Y1565237D03*
G54D29*
X55374Y390301D03*
G54D149*
X391703Y1616822D03*
X399183D03*
X434260Y1634000D03*
X441740D03*
X666860Y1514200D03*
X674340D03*
X1674734Y1547200D03*
X1682214D03*
G54D194*
X584276Y486000D03*
X593724D03*
X798724Y366000D03*
X789276D03*
X811224Y399500D03*
X801776D03*
X810224Y409500D03*
X800776D03*
G54D92*
X150318Y230828D03*
Y227088D03*
X1214094Y277848D03*
Y274108D03*
X1230094Y277848D03*
Y274108D03*
X1222094Y277848D03*
Y274108D03*
X1238094Y277848D03*
Y274108D03*
X1246094Y277848D03*
Y274108D03*
X1254094Y277848D03*
Y274108D03*
X1270094Y277848D03*
Y274108D03*
X1262094Y277848D03*
Y274108D03*
X1278094Y277848D03*
Y274108D03*
X1286094Y277848D03*
Y274108D03*
X1294094Y277848D03*
Y274108D03*
X1302094Y277848D03*
Y274108D03*
X1310094Y277848D03*
Y274108D03*
X1318094Y277848D03*
Y274108D03*
X1325530Y60824D03*
Y64564D03*
X1326094Y277848D03*
Y274108D03*
X1334094Y277848D03*
Y274108D03*
X1337440Y60824D03*
Y64564D03*
X1342094Y277848D03*
Y274108D03*
X1350094Y277848D03*
Y274108D03*
X1361550Y60824D03*
Y64564D03*
X1358094Y277848D03*
Y274108D03*
X1373750Y60824D03*
Y64564D03*
X1366094Y277848D03*
Y274108D03*
G54D275*
X1408817Y109037D03*
Y116911D03*
X1417635Y112974D03*
G54D248*
X913386Y179390D03*
Y177027D03*
Y174665D03*
Y172303D03*
Y169941D03*
Y167579D03*
Y195925D03*
Y193563D03*
Y191201D03*
Y188838D03*
Y186476D03*
Y184114D03*
Y181752D03*
Y210098D03*
Y207736D03*
Y205374D03*
Y203012D03*
Y200649D03*
Y198287D03*
Y224272D03*
Y221909D03*
Y219547D03*
Y217185D03*
Y214823D03*
Y212461D03*
Y231358D03*
Y228996D03*
Y226634D03*
X931496Y179390D03*
Y177027D03*
Y174665D03*
Y172303D03*
Y169941D03*
Y167579D03*
Y195925D03*
Y193563D03*
Y191201D03*
Y188838D03*
Y186476D03*
Y184114D03*
Y181752D03*
Y210098D03*
Y207736D03*
Y205374D03*
Y203012D03*
Y200649D03*
Y198287D03*
Y224272D03*
Y221909D03*
Y219547D03*
Y217185D03*
Y214823D03*
Y212461D03*
Y231358D03*
Y228996D03*
Y226634D03*
G54D74*
X111369Y1683513D03*
X109269D03*
X107169D03*
X109269D03*
X111369Y1688013D03*
X109269D03*
X107169D03*
X109269D03*
X155811Y1661655D03*
X153711D03*
X155811D03*
Y1666210D03*
X153711D03*
X155811D03*
X168113Y1483690D03*
X170213D03*
X168113Y1480090D03*
X170213D03*
X165750Y1491010D03*
X167850D03*
X168113Y1501890D03*
X170213D03*
X168113Y1505490D03*
X170213D03*
X165640Y1494340D03*
X167740D03*
X163288Y1510800D03*
X165388D03*
X164288Y1518040D03*
X166388D03*
X169288Y1510800D03*
X171388D03*
X169288Y1514420D03*
X171388D03*
X169288Y1518040D03*
X171388D03*
X166383Y1523431D03*
X168483D03*
X166383Y1526631D03*
X168483D03*
X164650Y1534800D03*
X162550D03*
Y1531600D03*
X164650D03*
X162550Y1542500D03*
X164650D03*
X162550Y1538000D03*
X164650D03*
X157911Y1661655D03*
Y1666210D03*
X179786Y1649166D03*
X181886D03*
X179786Y1652366D03*
X181886D03*
X179786Y1655566D03*
X181886D03*
X186386Y1658766D03*
X179786D03*
X181886D03*
X188486D03*
X275621Y1480582D03*
X273521D03*
X275621Y1484182D03*
X273521D03*
X275621Y1493982D03*
X273521D03*
X275621Y1497582D03*
X273521D03*
X273350Y1535270D03*
X275450D03*
X273350Y1538370D03*
X275450D03*
X280450Y1506600D03*
X278350D03*
X283550Y1505000D03*
X285650D03*
X278350Y1503100D03*
X280450D03*
X296175Y1480090D03*
X298275D03*
X296175Y1483690D03*
X298275D03*
X296175Y1505490D03*
X298275D03*
X296175Y1501890D03*
X298275D03*
X297350Y1518040D03*
X299450D03*
X297350Y1514420D03*
X299450D03*
X292350Y1517640D03*
X294450D03*
X297350Y1510800D03*
X299450D03*
X291350D03*
X293450D03*
X294445Y1523431D03*
X296545D03*
X294445Y1526631D03*
X296545D03*
X296207Y1532851D03*
X294107D03*
X371850Y1579400D03*
X369750D03*
X371850Y1582600D03*
X369750D03*
X372950Y1639400D03*
X370850D03*
X379250D03*
X377150D03*
X379250Y1642600D03*
X377150D03*
X379250Y1649000D03*
X377150D03*
X379250Y1645800D03*
X377150D03*
X383673Y1576448D03*
X385773D03*
X403683Y1480582D03*
X401583D03*
X403683Y1484182D03*
X401583D03*
X403683Y1497582D03*
X401583D03*
X403683Y1493982D03*
X401583D03*
X408512Y1506600D03*
X406412D03*
Y1503100D03*
X404312D03*
X409150Y1544200D03*
Y1538000D03*
X403005Y1598560D03*
X400905D03*
X411612Y1505000D03*
X413712D03*
X411400Y1533440D03*
X413500D03*
X411250Y1544200D03*
Y1538000D03*
X418090Y1557310D03*
X415990D03*
X411319Y1563520D03*
X413419D03*
X432286Y1480090D03*
X434386D03*
X432286Y1483690D03*
X434386D03*
X432286Y1501890D03*
X434386D03*
X432286Y1505490D03*
X434386D03*
X433461Y1518040D03*
X435561D03*
X433461Y1514420D03*
X435561D03*
X428461Y1517640D03*
X430561D03*
X433461Y1510800D03*
X435561D03*
X427461D03*
X429561D03*
X430556Y1523431D03*
X432656D03*
X430556Y1526631D03*
X432656D03*
X434558Y1563907D03*
X436658D03*
X431491Y1596983D03*
X429391D03*
X445567Y1579843D03*
X447667D03*
X463950Y1579400D03*
X466050D03*
X463950Y1576200D03*
X466050D03*
X513770Y107320D03*
X511670D03*
X518270D03*
X520370D03*
X539794Y1484182D03*
X537694D03*
X539794Y1480582D03*
X537694D03*
X539794Y1493982D03*
X537694D03*
X539794Y1497582D03*
X537694D03*
X542523Y1506600D03*
Y1503100D03*
X537547Y1534709D03*
X539647D03*
X537547Y1539572D03*
X539647D03*
X548338Y1503960D03*
X550438D03*
X544623Y1506600D03*
Y1503100D03*
X556523Y1517640D03*
X558623D03*
X555523Y1510800D03*
X557623D03*
X558618Y1523431D03*
Y1526631D03*
X558280Y1532851D03*
X560348Y1483690D03*
X562448D03*
X560348Y1480090D03*
X562448D03*
X560348Y1501890D03*
X562448D03*
X560348Y1505490D03*
X562448D03*
X561523Y1518040D03*
X563623D03*
X561523Y1514420D03*
X563623D03*
X561523Y1510800D03*
X563623D03*
X560718Y1523431D03*
Y1526631D03*
X560380Y1532851D03*
X643455Y1685970D03*
X641355D03*
X649750Y1652400D03*
X651850D03*
X667856Y1484182D03*
X665756D03*
X667856Y1480582D03*
X665756D03*
X667856Y1493982D03*
X665756D03*
X667856Y1497582D03*
X665756D03*
X672099Y1505135D03*
X674199D03*
Y1508335D03*
X672099D03*
X674536Y1652759D03*
X676636D03*
X667312Y1689063D03*
X665212D03*
X686211Y1537520D03*
X684111D03*
X691211D03*
X689111D03*
X686211Y1540720D03*
X684111D03*
X691211D03*
X689111D03*
X698990Y1536250D03*
X701090D03*
X698990Y1531700D03*
X701090D03*
X698990Y1548400D03*
X701090D03*
X698990Y1551700D03*
X701090D03*
X698990Y1541800D03*
X701090D03*
X711792Y173587D03*
X709692D03*
X711792Y177187D03*
X709692D03*
X711792Y185587D03*
X709692D03*
X711792Y189187D03*
X709692D03*
X711792Y197087D03*
X709692D03*
X711792Y200687D03*
X709692D03*
X711792Y208921D03*
X709692D03*
X711792Y212521D03*
X709692D03*
X709150Y1545100D03*
X711250D03*
X709150Y1551700D03*
X711250D03*
X709150Y1538500D03*
X711250D03*
X942596Y208375D03*
X940496D03*
X942596Y204775D03*
X940496D03*
X942596Y211897D03*
X940496D03*
X942596Y215497D03*
X940496D03*
X942596Y229635D03*
X940496D03*
X942596Y226035D03*
X940496D03*
X949296Y218948D03*
X947196D03*
X949296Y222548D03*
X947196D03*
X1141310Y1565312D03*
X1143410D03*
X1148727Y1565315D03*
X1146627D03*
X1161522Y1544575D03*
X1159422D03*
X1170423Y1564600D03*
X1160818Y1554023D03*
X1158718D03*
X1170423Y1575500D03*
Y1571000D03*
Y1567800D03*
X1175986Y1516690D03*
X1178086D03*
X1175986Y1513090D03*
X1178086D03*
X1175986Y1534890D03*
X1178086D03*
X1175986Y1538490D03*
X1178086D03*
X1177161Y1551040D03*
X1179261D03*
X1177161Y1547420D03*
X1179261D03*
X1172161Y1551040D03*
X1174261D03*
X1177161Y1543800D03*
X1179261D03*
X1171161D03*
X1173261D03*
X1174256Y1556431D03*
X1176356D03*
X1174256Y1559631D03*
X1176356D03*
X1172523Y1564600D03*
Y1575500D03*
Y1571000D03*
Y1567800D03*
X1283494Y1517182D03*
X1281394D03*
X1283494Y1513582D03*
X1281394D03*
X1283494Y1530582D03*
X1281394D03*
X1283494Y1526982D03*
X1281394D03*
X1286223Y1536100D03*
X1288323D03*
Y1539600D03*
X1286223D03*
X1281223Y1571370D03*
X1283323D03*
X1281223Y1568270D03*
X1283323D03*
X1304048Y1513090D03*
Y1516690D03*
Y1534890D03*
X1301834Y1528147D03*
X1303934D03*
X1301834Y1525001D03*
X1303934D03*
X1304048Y1538490D03*
X1291423Y1538000D03*
X1293523D03*
X1300223Y1550640D03*
X1302323D03*
X1299223Y1543800D03*
X1301323D03*
X1302318Y1556431D03*
X1304418D03*
X1302318Y1559631D03*
X1304418D03*
X1304080Y1565851D03*
X1301980D03*
X1306148Y1513090D03*
Y1516690D03*
Y1534890D03*
Y1538490D03*
X1305223Y1543800D03*
X1307323D03*
X1305223Y1551040D03*
X1307323D03*
X1305223Y1547420D03*
X1307323D03*
X1411556Y1517182D03*
X1409456D03*
X1411556Y1513582D03*
X1409456D03*
X1411556Y1526982D03*
X1409456D03*
X1411556Y1530582D03*
X1409456D03*
X1414285Y1536100D03*
X1412185D03*
X1419485Y1538000D03*
X1421585D03*
X1416385Y1539600D03*
X1414285D03*
X1419273Y1566440D03*
X1421373D03*
X1417023Y1577200D03*
X1419123D03*
X1416950Y1580400D03*
X1419050D03*
X1417023Y1571000D03*
X1419123D03*
X1436335Y1550640D03*
X1438435D03*
X1435335Y1543800D03*
X1437435D03*
X1438430Y1556431D03*
Y1559631D03*
X1440160Y1513090D03*
X1442260D03*
X1440160Y1516690D03*
X1442260D03*
X1440160Y1534890D03*
X1442260D03*
X1440160Y1538490D03*
X1442260D03*
X1441335Y1543800D03*
X1443435D03*
X1441335Y1551040D03*
X1443435D03*
X1441335Y1547420D03*
X1443435D03*
X1440530Y1556431D03*
Y1559631D03*
X1441187Y1682665D03*
X1439087D03*
X1441187Y1686165D03*
X1439087D03*
X1439050Y1679544D03*
X1441150D03*
X1439067Y1689273D03*
X1441167D03*
X1482680Y1668917D03*
X1480580D03*
X1482450Y1678500D03*
X1484550D03*
X1547668Y1513582D03*
X1545568D03*
X1547668Y1517182D03*
X1545568D03*
X1547668Y1530582D03*
X1545568D03*
X1547668Y1526982D03*
X1545568D03*
X1550396Y1536100D03*
X1552496D03*
X1555596Y1538000D03*
X1557696D03*
X1552496Y1539600D03*
X1550396D03*
X1545396Y1571370D03*
X1547496D03*
X1545397Y1568270D03*
X1547497D03*
X1568222Y1513090D03*
X1570322D03*
X1568222Y1516690D03*
X1570322D03*
X1568222Y1534890D03*
X1570322D03*
X1568222Y1538490D03*
X1570322D03*
X1564397Y1550640D03*
X1566497D03*
X1569397Y1543800D03*
X1571497D03*
X1563397D03*
X1565497D03*
X1569397Y1551040D03*
X1571497D03*
X1569397Y1547420D03*
X1571497D03*
X1566492Y1556431D03*
X1568592D03*
X1566492Y1559631D03*
X1568592D03*
X1568253Y1565851D03*
X1566153D03*
X1656089Y1704237D03*
X1658189D03*
X1675730Y1517182D03*
X1673630D03*
X1675730Y1513582D03*
X1673630D03*
X1675730Y1530582D03*
X1673630D03*
X1675730Y1526982D03*
X1673630D03*
X1668268Y1670149D03*
X1666168D03*
X1679972Y1538135D03*
X1682072D03*
Y1541335D03*
X1679972D03*
X1691975Y1570520D03*
Y1573720D03*
X1694075Y1570520D03*
Y1573720D03*
X1700950Y1595000D03*
X1703050D03*
X1700950Y1598100D03*
X1703050D03*
X1700950Y1604300D03*
X1703050D03*
X1700950Y1601200D03*
X1703050D03*
X1700950Y1607400D03*
X1703050D03*
X1715693Y1606340D03*
X1717793D03*
X1715693Y1599740D03*
X1717793D03*
X1715693Y1612940D03*
X1717793D03*
G54D158*
X428899Y225205D03*
Y227764D03*
Y230323D03*
Y232883D03*
Y235442D03*
Y238001D03*
X451931Y225205D03*
Y238001D03*
Y235442D03*
Y232883D03*
Y230323D03*
Y227764D03*
X506945Y227882D03*
Y230441D03*
Y233000D03*
Y235560D03*
Y238119D03*
Y240678D03*
X529977D03*
Y238119D03*
Y235560D03*
Y233000D03*
Y230441D03*
Y227882D03*
G54D284*
X1669100Y121762D03*
Y126762D03*
Y131762D03*
Y136762D03*
Y141762D03*
Y146762D03*
Y151762D03*
Y156762D03*
Y161762D03*
Y166762D03*
X1699100Y121762D03*
Y126762D03*
Y131762D03*
Y136762D03*
Y141762D03*
Y146762D03*
Y151762D03*
Y156762D03*
Y161762D03*
Y166762D03*
G54D83*
X138003Y1663229D03*
G54D176*
X478794Y304928D03*
X565794Y313928D03*
G36*
G01X65052Y1668787D02*
Y1670604D01*
G03X64855Y1670801I-197J0D01*
G01X60722D01*
G03X60525Y1670604I0J-197D01*
G01Y1666471D01*
G03X60722Y1666274I197J0D01*
G01X64855D01*
G03X65052Y1666471I0J197D01*
G01Y1668287D01*
X65840D01*
Y1666471D01*
G03X66037Y1666274I197J0D01*
G01X67853D01*
Y1665486D01*
X66037D01*
G03X65840Y1665289I0J-197D01*
G01Y1663473D01*
X65052D01*
Y1665289D01*
G03X64855Y1665486I-197J0D01*
G01X60722D01*
G03X60525Y1665289I0J-197D01*
G01Y1661156D01*
G03X60722Y1660959I197J0D01*
G01X64855D01*
G03X65052Y1661156I0J197D01*
G01Y1662973D01*
X65840D01*
Y1661156D01*
G03X66037Y1660959I197J0D01*
G01X70170D01*
G03X70367Y1661156I0J197D01*
G01Y1665289D01*
G03X70170Y1665486I-197J0D01*
G01X68353D01*
Y1666274D01*
X70170D01*
G03X70367Y1666471I0J197D01*
G01Y1670604D01*
G03X70170Y1670801I-197J0D01*
G01X66037D01*
G03X65840Y1670604I0J-197D01*
G01Y1668787D01*
X65052D01*
G37*
G54D65*
X102160Y1444500D03*
X103950Y1436000D03*
X246314Y561512D03*
X265210Y559512D03*
X527280Y120930D03*
X533520Y122200D03*
X663728Y422820D03*
X666919Y471854D03*
X829390Y1466384D03*
X818885Y1467654D03*
X1189242Y1465128D03*
X1178737Y1466398D03*
X1310450Y556184D03*
X1662146Y1414965D03*
G54D185*
X509820Y129423D03*
Y160919D03*
X535016Y129423D03*
Y160919D03*
G54D167*
X476412Y288567D03*
X563412Y297567D03*
G54D38*
X50773Y777430D03*
G54D177*
X481550Y303156D03*
X568550Y312156D03*
G54D258*
X1004868Y194419D03*
G54D66*
X97477Y1577854D03*
Y1592224D03*
X166600Y1552015D03*
Y1566385D03*
X1174473Y1585015D03*
Y1599385D03*
X1715780Y170079D03*
Y184449D03*
X1779981Y1618865D03*
Y1633235D03*
G54D195*
X595203Y167856D03*
Y170415D03*
Y172975D03*
Y175534D03*
X612801D03*
Y172975D03*
Y170415D03*
Y167856D03*
G54D276*
X1418249Y244450D03*
X1421989D03*
G54D75*
X102529Y1701386D03*
Y1698827D03*
Y1703946D03*
Y1706505D03*
X102583Y1718438D03*
Y1720997D03*
Y1723557D03*
Y1726116D03*
X120107Y1701386D03*
Y1698827D03*
Y1706505D03*
Y1703946D03*
X120161Y1720997D03*
Y1723557D03*
Y1726116D03*
Y1718438D03*
X1128889Y1679853D03*
Y1677293D03*
Y1674734D03*
Y1682412D03*
X1146467D03*
Y1679853D03*
Y1677293D03*
Y1674734D03*
G54D294*
X1797245Y212369D03*
G54D249*
X916889Y582573D03*
Y597073D03*
Y585132D03*
Y587692D03*
Y590251D03*
Y611573D03*
Y599632D03*
Y602192D03*
Y604751D03*
Y626073D03*
Y614132D03*
Y616692D03*
Y619251D03*
Y628632D03*
Y631192D03*
Y633751D03*
X931455Y582573D03*
Y597073D03*
Y590251D03*
Y587692D03*
Y585132D03*
Y611573D03*
Y604751D03*
Y602192D03*
Y599632D03*
Y626073D03*
Y619251D03*
Y616692D03*
Y614132D03*
Y633751D03*
Y631192D03*
Y628632D03*
G54D57*
X57966Y1668833D03*
Y1670801D03*
Y1660959D03*
Y1662927D03*
Y1666864D03*
Y1664896D03*
X72926Y1666864D03*
Y1664896D03*
Y1660959D03*
Y1662927D03*
Y1668833D03*
Y1670801D03*
G54D159*
X428899Y222253D03*
Y240953D03*
X451931Y222253D03*
Y240953D03*
X506945Y224930D03*
Y243630D03*
X529977Y224930D03*
Y243630D03*
G54D48*
X65205Y1526394D03*
X100948D03*
X112601Y1360516D03*
X145201D03*
X177901D03*
X210801D03*
X243601D03*
X277201Y1314370D03*
X310097Y1314342D03*
X343001Y1314285D03*
X375801Y1314485D03*
X408383Y1333816D03*
X720157Y1378525D03*
X752939Y1378625D03*
X1084339Y1360497D03*
X1116939D03*
X1149639D03*
X1182539D03*
X1215339D03*
X1253330Y1314351D03*
X1286226Y1314323D03*
X1319130Y1314266D03*
X1351930Y1314466D03*
X1384512Y1333797D03*
X1667890Y1377814D03*
X1700672Y1377914D03*
X1752488Y1559430D03*
X1788231D03*
G54D267*
X1156378Y133866D03*
X1173858Y207205D03*
X1391260Y174213D03*
G54D84*
X134853Y1672087D03*
G54D93*
X147290Y481917D03*
Y505343D03*
X174070Y481377D03*
Y504803D03*
G54D39*
X50318Y1608318D03*
Y1609893D03*
Y1611468D03*
Y1613043D03*
Y1614618D03*
Y1616192D03*
Y1617767D03*
Y1619342D03*
Y1620917D03*
Y1622492D03*
X69216Y1611468D03*
Y1609893D03*
Y1608318D03*
Y1622492D03*
Y1620917D03*
Y1619342D03*
Y1617767D03*
Y1616192D03*
Y1614618D03*
Y1613043D03*
X629246Y1373044D03*
Y1366745D03*
Y1365170D03*
Y1369895D03*
Y1368320D03*
Y1371470D03*
Y1374619D03*
Y1377769D03*
Y1379344D03*
Y1376194D03*
X648144Y1366745D03*
Y1371470D03*
Y1373044D03*
Y1365170D03*
Y1368320D03*
Y1369895D03*
Y1374619D03*
Y1376194D03*
Y1379344D03*
Y1377769D03*
X1639834Y1426328D03*
Y1420029D03*
Y1418454D03*
Y1423179D03*
Y1421604D03*
Y1427903D03*
Y1424754D03*
Y1431053D03*
Y1432628D03*
Y1429478D03*
X1658732Y1420029D03*
Y1427903D03*
Y1429478D03*
Y1432628D03*
Y1431053D03*
Y1424754D03*
Y1426328D03*
Y1418454D03*
Y1421604D03*
Y1423179D03*
X1739880Y1661869D03*
Y1663444D03*
Y1665019D03*
Y1666594D03*
Y1668169D03*
Y1669743D03*
Y1671318D03*
Y1672893D03*
Y1674468D03*
Y1676043D03*
X1758778Y1671318D03*
Y1669743D03*
Y1668169D03*
Y1666594D03*
Y1665019D03*
Y1663444D03*
Y1661869D03*
Y1676043D03*
Y1674468D03*
Y1672893D03*
G54D186*
X506670Y132573D03*
Y157769D03*
X538166Y132573D03*
Y157769D03*
G54D168*
X473445Y288569D03*
X560445Y297569D03*
G36*
G01X1744370Y279473D02*
Y270418D01*
X1742008D01*
Y266087D01*
X1746752D01*
Y262544D01*
X1744390D01*
Y265587D01*
X1741752D01*
Y262544D01*
X1739390D01*
Y265587D01*
X1736752D01*
Y262544D01*
X1734390D01*
Y265587D01*
X1731752D01*
Y262544D01*
X1729390D01*
Y266087D01*
X1733634D01*
Y270418D01*
X1731772D01*
Y272780D01*
X1734815D01*
Y273764D01*
X1731772D01*
Y276126D01*
X1734815D01*
Y277111D01*
X1731772D01*
Y279473D01*
X1735315D01*
Y270418D01*
X1734134D01*
Y266087D01*
X1737571D01*
Y270418D01*
X1736299D01*
Y272780D01*
X1739343D01*
Y273764D01*
X1736299D01*
Y276126D01*
X1739343D01*
Y277111D01*
X1736299D01*
Y279473D01*
X1739843D01*
Y270418D01*
X1738071D01*
Y266087D01*
X1741508D01*
Y270418D01*
X1740827D01*
Y272780D01*
X1743870D01*
Y273764D01*
X1740827D01*
Y276126D01*
X1743870D01*
Y277111D01*
X1740827D01*
Y279473D01*
X1744370D01*
G37*
G54D295*
X1795796Y222241D03*
Y266533D03*
G54D268*
X1176972Y76008D03*
X1171854D03*
Y83488D03*
X1176972D03*
G54D286*
X1764399Y709079D03*
X1785659D03*
G54D94*
X152705Y680396D03*
Y673782D03*
X382797Y1580912D03*
Y1587526D03*
X454288Y1576826D03*
Y1583440D03*
X1188192Y579015D03*
Y585629D03*
X1726334Y667545D03*
Y660931D03*
G54D196*
X600647Y772929D03*
G54D76*
X123811Y524366D03*
Y529484D03*
X130811D03*
Y526925D03*
Y524366D03*
X271500Y220441D03*
Y223000D03*
Y225559D03*
X278500D03*
Y220441D03*
X852500Y395559D03*
Y390441D03*
X845500D03*
Y393000D03*
Y395559D03*
G54D169*
X481156Y297251D03*
Y299219D03*
X474464Y297251D03*
X481156Y301187D03*
X474464D03*
X568156Y310187D03*
Y306251D03*
Y308219D03*
X561464Y306251D03*
Y310187D03*
G54D259*
X999455Y208592D03*
Y205049D03*
Y201506D03*
Y197962D03*
G54D178*
X474070Y303156D03*
X561070Y312156D03*
G54D67*
X113065Y1311630D03*
Y1345094D03*
X145665Y1311630D03*
Y1345094D03*
X178165Y1311630D03*
Y1345094D03*
X210765Y1311630D03*
Y1345094D03*
X243365Y1311630D03*
Y1345094D03*
X257991Y685023D03*
Y718487D03*
X277665Y1265484D03*
Y1298948D03*
X290721Y719264D03*
Y752728D03*
X310561Y1265399D03*
Y1298863D03*
X323491Y739414D03*
Y772878D03*
X343465Y1265399D03*
Y1298863D03*
X356551Y739326D03*
Y772790D03*
X375961Y1265456D03*
Y1298920D03*
X389591Y739214D03*
Y772678D03*
X408847Y1284930D03*
Y1318394D03*
X425562Y721429D03*
Y754893D03*
X457090Y696814D03*
Y730278D03*
X489462Y670314D03*
Y703778D03*
X522062Y636214D03*
Y669678D03*
X1084803Y1311611D03*
Y1345075D03*
X1117403Y1311611D03*
Y1345075D03*
X1150103Y1311611D03*
Y1345075D03*
X1183003Y1311611D03*
Y1345075D03*
X1215803Y1311611D03*
Y1345075D03*
X1253794Y1265465D03*
Y1298929D03*
X1286690Y1265380D03*
Y1298844D03*
X1319594Y1265380D03*
Y1298844D03*
X1352090Y1265437D03*
Y1298901D03*
X1368861Y654359D03*
Y687823D03*
X1384976Y1284911D03*
Y1318375D03*
X1401243Y687257D03*
Y720721D03*
X1433843Y719837D03*
Y753301D03*
X1466761Y739414D03*
Y772878D03*
X1499843Y739414D03*
Y772878D03*
X1532643Y739414D03*
Y772878D03*
X1567114Y717474D03*
Y750938D03*
X1600244Y683705D03*
Y717169D03*
X1633043Y664705D03*
Y698169D03*
G54D58*
X79729Y289822D03*
Y310256D03*
X89729Y289822D03*
Y310256D03*
X757184Y1702772D03*
Y1712772D03*
X1072863Y1409176D03*
Y1419176D03*
X1080970Y1640958D03*
Y1650958D03*
X1299439Y102812D03*
Y112812D03*
X1530377Y581353D03*
X1540377D03*
G54D85*
X129932Y1669725D03*
Y1671300D03*
Y1666575D03*
Y1668150D03*
Y1674449D03*
Y1672874D03*
Y1677599D03*
Y1676024D03*
G54D49*
X55756Y1531020D03*
Y1532792D03*
Y1534564D03*
Y1536335D03*
Y1538107D03*
Y1539879D03*
X96966Y159744D03*
Y157775D03*
Y155807D03*
Y153838D03*
X85942D03*
Y155807D03*
Y157775D03*
Y159744D03*
X91499Y1531020D03*
Y1532792D03*
Y1534564D03*
Y1536335D03*
Y1538107D03*
Y1539879D03*
X103152Y1370457D03*
Y1368686D03*
Y1366914D03*
Y1365142D03*
Y1372229D03*
Y1374001D03*
X135752Y1370457D03*
Y1368686D03*
Y1366914D03*
Y1365142D03*
Y1372229D03*
Y1374001D03*
X168452Y1370457D03*
Y1368686D03*
Y1366914D03*
Y1365142D03*
Y1372229D03*
Y1374001D03*
X201352Y1370457D03*
Y1368686D03*
Y1366914D03*
Y1365142D03*
Y1372229D03*
Y1374001D03*
X234152Y1370457D03*
Y1368686D03*
Y1366914D03*
Y1365142D03*
Y1372229D03*
Y1374001D03*
X267904Y656116D03*
Y664975D03*
Y663203D03*
Y661431D03*
Y659660D03*
Y657888D03*
X267752Y1327855D03*
Y1324311D03*
Y1322540D03*
Y1320768D03*
Y1318996D03*
Y1326083D03*
X280741Y151850D03*
Y153819D03*
Y155787D03*
Y157756D03*
X291765D03*
Y155787D03*
Y153819D03*
Y151850D03*
X300634Y699216D03*
Y697444D03*
Y695672D03*
Y693901D03*
Y692129D03*
Y690357D03*
X300648Y1327827D03*
Y1324283D03*
Y1322512D03*
Y1320740D03*
Y1318968D03*
Y1326055D03*
X333404Y715822D03*
Y714051D03*
Y712279D03*
Y710507D03*
Y719366D03*
Y717594D03*
X333552Y1327770D03*
Y1324226D03*
Y1322455D03*
Y1320683D03*
Y1318911D03*
Y1325998D03*
X366464Y717326D03*
Y715554D03*
Y713783D03*
Y712011D03*
Y710239D03*
Y719098D03*
X366352Y1327970D03*
Y1324426D03*
Y1322655D03*
Y1320883D03*
Y1319111D03*
Y1326198D03*
X399504Y717394D03*
Y715622D03*
Y713851D03*
Y712079D03*
Y710307D03*
Y719166D03*
X398934Y1341986D03*
Y1340214D03*
Y1338442D03*
Y1347301D03*
Y1343757D03*
Y1345529D03*
X432504Y701366D03*
Y699594D03*
Y697822D03*
Y696051D03*
Y694279D03*
Y692507D03*
X464904Y671451D03*
Y669679D03*
Y667907D03*
Y676766D03*
Y674994D03*
Y673222D03*
X497504Y641407D03*
Y650266D03*
Y648494D03*
Y646722D03*
Y644951D03*
Y643179D03*
X530804Y612622D03*
Y610851D03*
Y609079D03*
Y607307D03*
Y616166D03*
Y614394D03*
X615741Y223893D03*
Y221924D03*
X604717D03*
Y223893D03*
X615741Y227830D03*
Y225861D03*
X604717D03*
Y227830D03*
X710708Y1386695D03*
Y1384923D03*
Y1383151D03*
Y1392010D03*
Y1388466D03*
Y1390238D03*
X743490Y1386795D03*
Y1385023D03*
Y1383251D03*
Y1392110D03*
Y1388566D03*
Y1390338D03*
X818002Y133945D03*
Y135914D03*
Y137882D03*
Y139851D03*
X829026Y135914D03*
Y133945D03*
Y139851D03*
Y137882D03*
X841967Y211438D03*
Y213407D03*
Y215375D03*
Y217344D03*
X852991D03*
Y215375D03*
Y213407D03*
Y211438D03*
X1074890Y1370438D03*
Y1368667D03*
Y1366895D03*
Y1365123D03*
Y1372210D03*
Y1373982D03*
X1107490Y1370438D03*
Y1368667D03*
Y1366895D03*
Y1365123D03*
Y1372210D03*
Y1373982D03*
X1140190Y1370438D03*
Y1368667D03*
Y1366895D03*
Y1365123D03*
Y1372210D03*
Y1373982D03*
X1173090Y1370438D03*
Y1368667D03*
Y1366895D03*
Y1365123D03*
Y1372210D03*
Y1373982D03*
X1205890Y1370438D03*
Y1368667D03*
Y1366895D03*
Y1365123D03*
Y1372210D03*
Y1373982D03*
X1243881Y1327836D03*
Y1324292D03*
Y1322521D03*
Y1320749D03*
Y1318977D03*
Y1326064D03*
X1274390Y403772D03*
Y405741D03*
Y407709D03*
Y409678D03*
X1285414Y403772D03*
Y409678D03*
Y407709D03*
Y405741D03*
X1276777Y1327808D03*
Y1324264D03*
Y1322493D03*
Y1320721D03*
Y1318949D03*
Y1326036D03*
X1309681Y1327751D03*
Y1324207D03*
Y1322436D03*
Y1320664D03*
Y1318892D03*
Y1325979D03*
X1342481Y1327951D03*
Y1324407D03*
Y1322636D03*
Y1320864D03*
Y1319092D03*
Y1326179D03*
X1378456Y627222D03*
Y625450D03*
Y634309D03*
Y632537D03*
Y630765D03*
Y628994D03*
X1375063Y1341967D03*
Y1340195D03*
Y1338423D03*
Y1347282D03*
Y1343738D03*
Y1345510D03*
X1411156Y667209D03*
Y665437D03*
Y663665D03*
Y661894D03*
Y660122D03*
Y658350D03*
X1443756Y699789D03*
Y698017D03*
Y696245D03*
Y694474D03*
Y692702D03*
Y690930D03*
X1476674Y715822D03*
Y714051D03*
Y712279D03*
Y710507D03*
Y719366D03*
Y717594D03*
X1509756Y715990D03*
Y714219D03*
Y712447D03*
Y710675D03*
Y719534D03*
Y717762D03*
X1542556Y715822D03*
Y714051D03*
Y712279D03*
Y710507D03*
Y719366D03*
Y717594D03*
X1550705Y297463D03*
Y299432D03*
Y301400D03*
Y303369D03*
X1561729Y299432D03*
Y297463D03*
Y303369D03*
Y301400D03*
X1575686Y697426D03*
Y695654D03*
Y693882D03*
Y692111D03*
Y690339D03*
Y688567D03*
X1608456Y656570D03*
Y654798D03*
Y663657D03*
Y661885D03*
Y660113D03*
Y658342D03*
X1641456Y642885D03*
Y641113D03*
Y639342D03*
Y637570D03*
Y635798D03*
Y644657D03*
X1658441Y1387755D03*
Y1385984D03*
Y1384212D03*
Y1382440D03*
Y1391299D03*
Y1389527D03*
X1691223Y1387855D03*
Y1386084D03*
Y1384312D03*
Y1382540D03*
Y1391399D03*
Y1389627D03*
X1683561Y1683292D03*
Y1685261D03*
Y1689198D03*
Y1687229D03*
X1694585Y1683292D03*
Y1685261D03*
Y1689198D03*
Y1687229D03*
X1729480Y367431D03*
Y369400D03*
Y371368D03*
Y373337D03*
X1740504D03*
Y371368D03*
Y369400D03*
Y367431D03*
X1743039Y1564056D03*
Y1565828D03*
Y1567600D03*
Y1569371D03*
Y1571143D03*
Y1572915D03*
X1778782Y1564056D03*
Y1565828D03*
Y1567600D03*
Y1569371D03*
Y1571143D03*
Y1572915D03*
G54D187*
X513651Y209692D03*
G54D277*
X1500126Y609338D03*
X1520008D03*
G54D278*
X1545620Y209250D03*
Y224250D03*
Y219250D03*
Y214250D03*
Y239250D03*
Y234250D03*
Y229250D03*
Y254250D03*
Y249250D03*
Y244250D03*
X1564202Y209250D03*
Y224250D03*
Y219250D03*
Y214250D03*
Y239250D03*
Y234250D03*
Y229250D03*
Y254250D03*
Y249250D03*
Y244250D03*
G54D77*
X139770Y445819D03*
X154770D03*
X149770D03*
X144770D03*
X171550Y445279D03*
X166550D03*
X181550D03*
X176550D03*
X943902Y1505029D03*
X958902D03*
X953902D03*
X948902D03*
X977268D03*
X972268D03*
X967268D03*
X982268D03*
X990634D03*
X1005634D03*
X1000634D03*
X995634D03*
X1019000D03*
X1014000D03*
X1029000D03*
X1024000D03*
X1047366D03*
X1042366D03*
X1037366D03*
X1065732D03*
X1060732D03*
X1052366D03*
X1075732D03*
X1070732D03*
X1094098D03*
X1089098D03*
X1084098D03*
X1099098D03*
X1730571Y286855D03*
X1735571D03*
X1740571D03*
X1745571D03*
G54D269*
X1196187Y98316D03*
Y100875D03*
Y103434D03*
X1204849D03*
Y98316D03*
G54D179*
X475559Y1643260D03*
X473000D03*
X470441D03*
Y1650740D03*
X473000D03*
X475559D03*
X748441Y220240D03*
X751000D03*
Y212760D03*
X748441D03*
X753559Y220240D03*
Y212760D03*
X822559Y520760D03*
X820000D03*
X817441D03*
Y528240D03*
X820000D03*
X822559D03*
X1183354Y75185D03*
Y82665D03*
X1188472Y75185D03*
X1185913D03*
Y82665D03*
X1188472D03*
X1192612Y1677910D03*
X1195171D03*
X1192612Y1685390D03*
X1197730D03*
X1195171D03*
X1197730Y1677910D03*
X1207954Y1677919D03*
X1210513D03*
X1207954Y1685399D03*
X1213072D03*
X1210513D03*
X1213072Y1677919D03*
X1344958Y75369D03*
X1342399D03*
X1339840D03*
Y82849D03*
X1342399D03*
X1344958D03*
X1356868Y75335D03*
X1354309D03*
X1351750D03*
Y82815D03*
X1354309D03*
X1356868D03*
X1388918Y1682898D03*
X1383800D03*
X1386359D03*
X1388918Y1690378D03*
X1386359D03*
X1383800D03*
X1405058Y1642107D03*
X1402499D03*
X1405058Y1634627D03*
X1399940D03*
X1402499D03*
X1399940Y1642107D03*
X1426513Y1640469D03*
X1429072D03*
X1431631D03*
Y1632989D03*
X1429072D03*
X1426513D03*
G54D296*
X1787234Y709079D03*
G54D197*
X607057Y771392D03*
X613470Y759230D03*
G54D95*
X150185Y680042D03*
X155225D03*
X150185Y674136D03*
X155225D03*
X380277Y1581266D03*
Y1587172D03*
X385317Y1581266D03*
Y1587172D03*
X451768Y1577180D03*
Y1583086D03*
X456808Y1577180D03*
Y1583086D03*
X1185672Y579369D03*
Y585275D03*
X1190712Y579369D03*
Y585275D03*
X1723814Y667191D03*
X1728854D03*
X1723814Y661285D03*
X1728854D03*
G54D86*
X131703Y1663229D03*
G54D68*
X113065Y1323736D03*
Y1332988D03*
X145665Y1323736D03*
Y1332988D03*
X178165Y1323736D03*
Y1332988D03*
X210765Y1323736D03*
Y1332988D03*
X243365Y1323736D03*
Y1332988D03*
X257991Y697129D03*
Y706381D03*
X277665Y1277590D03*
Y1286842D03*
X290721Y731370D03*
Y740622D03*
X310561Y1277505D03*
Y1286757D03*
X323491Y760772D03*
Y751520D03*
X343465Y1277505D03*
Y1286757D03*
X356551Y760684D03*
Y751432D03*
X375961Y1277562D03*
Y1286814D03*
X389591Y760572D03*
Y751320D03*
X408847Y1297036D03*
Y1306288D03*
X425562Y733535D03*
Y742787D03*
X457090Y718172D03*
Y708920D03*
X489462Y682420D03*
Y691672D03*
X522062Y657572D03*
Y648320D03*
X1084803Y1323717D03*
Y1332969D03*
X1117403Y1323717D03*
Y1332969D03*
X1150103Y1323717D03*
Y1332969D03*
X1183003Y1323717D03*
Y1332969D03*
X1215803Y1323717D03*
Y1332969D03*
X1253794Y1277571D03*
Y1286823D03*
X1286690Y1277486D03*
Y1286738D03*
X1319594Y1277486D03*
Y1286738D03*
X1352090Y1277543D03*
Y1286795D03*
X1368861Y666465D03*
Y675717D03*
X1384976Y1297017D03*
Y1306269D03*
X1401243Y699363D03*
Y708615D03*
X1433843Y731943D03*
Y741195D03*
X1466761Y760772D03*
Y751520D03*
X1499843Y760772D03*
Y751520D03*
X1532643Y760772D03*
Y751520D03*
X1567114Y729580D03*
Y738832D03*
X1600244Y695811D03*
Y705063D03*
X1633043Y686063D03*
Y676811D03*
G54D59*
X77394Y734588D03*
Y1021399D03*
Y1277698D03*
X107095Y734588D03*
Y1021399D03*
Y1277698D03*
X136795Y734588D03*
Y1021399D03*
Y1277698D03*
X166496Y734588D03*
Y1021399D03*
Y1277698D03*
X196197Y734588D03*
Y1021399D03*
Y1277698D03*
X225898Y734588D03*
Y1021399D03*
Y1277698D03*
X655425Y734588D03*
Y1021399D03*
Y1277698D03*
X685126Y734588D03*
Y1021399D03*
Y1277698D03*
X714827Y734588D03*
Y1021399D03*
Y1277698D03*
X744528Y734588D03*
Y1021399D03*
Y1277698D03*
X774229Y734588D03*
Y1021399D03*
Y1277698D03*
X803929Y734588D03*
Y1021399D03*
Y1277698D03*
X1053536Y734587D03*
Y1021398D03*
Y1277697D03*
X1083237Y734587D03*
Y1021398D03*
Y1277697D03*
X1112937Y734587D03*
Y1021398D03*
Y1277697D03*
X1142638Y734587D03*
Y1021398D03*
Y1277697D03*
X1172339Y734587D03*
Y1021398D03*
Y1277697D03*
X1202040Y734587D03*
Y1021398D03*
Y1277697D03*
X1631567Y734587D03*
Y1021398D03*
Y1277697D03*
X1661268Y734587D03*
Y1021398D03*
Y1277697D03*
X1690969Y734587D03*
Y1021398D03*
Y1277697D03*
X1720670Y734587D03*
Y1021398D03*
Y1277697D03*
X1750371Y734587D03*
Y1021398D03*
Y1277697D03*
X1780071Y734587D03*
Y1021398D03*
Y1277697D03*
G54D188*
X514831Y212498D03*
G54D287*
X1762824Y709079D03*
G54D87*
X129932Y1679174D03*
G54D189*
X529815Y445740D03*
Y438260D03*
X519185D03*
Y442000D03*
Y445740D03*
X555185Y458760D03*
Y466240D03*
X565815Y462500D03*
Y458760D03*
Y466240D03*
X1576680Y574022D03*
Y579022D03*
Y584022D03*
Y589022D03*
G36*
G01X140971Y453201D02*
Y462256D01*
X143333D01*
Y466587D01*
X138589D01*
Y470130D01*
X140951D01*
Y467087D01*
X143589D01*
Y470130D01*
X145951D01*
Y467087D01*
X148589D01*
Y470130D01*
X150951D01*
Y467087D01*
X153589D01*
Y470130D01*
X155951D01*
Y466587D01*
X151707D01*
Y462256D01*
X153569D01*
Y459894D01*
X150526D01*
Y458910D01*
X153569D01*
Y456548D01*
X150526D01*
Y455563D01*
X153569D01*
Y453201D01*
X150026D01*
Y462256D01*
X151207D01*
Y466587D01*
X147770D01*
Y462256D01*
X149042D01*
Y459894D01*
X145998D01*
Y458910D01*
X149042D01*
Y456548D01*
X145998D01*
Y455563D01*
X149042D01*
Y453201D01*
X145498D01*
Y462256D01*
X147270D01*
Y466587D01*
X143833D01*
Y462256D01*
X144514D01*
Y459894D01*
X141471D01*
Y458910D01*
X144514D01*
Y456548D01*
X141471D01*
Y455563D01*
X144514D01*
Y453201D01*
X140971D01*
G37*
G36*
G01X167751Y452661D02*
Y461716D01*
X170113D01*
Y466047D01*
X165369D01*
Y469590D01*
X167731D01*
Y466547D01*
X170369D01*
Y469590D01*
X172731D01*
Y466547D01*
X175369D01*
Y469590D01*
X177731D01*
Y466547D01*
X180369D01*
Y469590D01*
X182731D01*
Y466047D01*
X178487D01*
Y461716D01*
X180349D01*
Y459354D01*
X177306D01*
Y458370D01*
X180349D01*
Y456008D01*
X177306D01*
Y455023D01*
X180349D01*
Y452661D01*
X176806D01*
Y461716D01*
X177987D01*
Y466047D01*
X174550D01*
Y461716D01*
X175822D01*
Y459354D01*
X172778D01*
Y458370D01*
X175822D01*
Y456008D01*
X172778D01*
Y455023D01*
X175822D01*
Y452661D01*
X172278D01*
Y461716D01*
X174050D01*
Y466047D01*
X170613D01*
Y461716D01*
X171294D01*
Y459354D01*
X168251D01*
Y458370D01*
X171294D01*
Y456008D01*
X168251D01*
Y455023D01*
X171294D01*
Y452661D01*
X167751D01*
G37*
G36*
G01X945103Y1512411D02*
Y1521466D01*
X947465D01*
Y1525797D01*
X942721D01*
Y1529340D01*
X945083D01*
Y1526297D01*
X947721D01*
Y1529340D01*
X950083D01*
Y1526297D01*
X952721D01*
Y1529340D01*
X955083D01*
Y1526297D01*
X957721D01*
Y1529340D01*
X960083D01*
Y1525797D01*
X955839D01*
Y1521466D01*
X957701D01*
Y1519104D01*
X954658D01*
Y1518120D01*
X957701D01*
Y1515758D01*
X954658D01*
Y1514773D01*
X957701D01*
Y1512411D01*
X954158D01*
Y1521466D01*
X955339D01*
Y1525797D01*
X951902D01*
Y1521466D01*
X953174D01*
Y1519104D01*
X950130D01*
Y1518120D01*
X953174D01*
Y1515758D01*
X950130D01*
Y1514773D01*
X953174D01*
Y1512411D01*
X949630D01*
Y1521466D01*
X951402D01*
Y1525797D01*
X947965D01*
Y1521466D01*
X948646D01*
Y1519104D01*
X945603D01*
Y1518120D01*
X948646D01*
Y1515758D01*
X945603D01*
Y1514773D01*
X948646D01*
Y1512411D01*
X945103D01*
G37*
G36*
G01X968469D02*
Y1521466D01*
X970831D01*
Y1525797D01*
X966087D01*
Y1529340D01*
X968449D01*
Y1526297D01*
X971087D01*
Y1529340D01*
X973449D01*
Y1526297D01*
X976087D01*
Y1529340D01*
X978449D01*
Y1526297D01*
X981087D01*
Y1529340D01*
X983449D01*
Y1525797D01*
X979205D01*
Y1521466D01*
X981067D01*
Y1519104D01*
X978024D01*
Y1518120D01*
X981067D01*
Y1515758D01*
X978024D01*
Y1514773D01*
X981067D01*
Y1512411D01*
X977524D01*
Y1521466D01*
X978705D01*
Y1525797D01*
X975268D01*
Y1521466D01*
X976540D01*
Y1519104D01*
X973496D01*
Y1518120D01*
X976540D01*
Y1515758D01*
X973496D01*
Y1514773D01*
X976540D01*
Y1512411D01*
X972996D01*
Y1521466D01*
X974768D01*
Y1525797D01*
X971331D01*
Y1521466D01*
X972012D01*
Y1519104D01*
X968969D01*
Y1518120D01*
X972012D01*
Y1515758D01*
X968969D01*
Y1514773D01*
X972012D01*
Y1512411D01*
X968469D01*
G37*
G36*
G01X991835D02*
Y1521466D01*
X994197D01*
Y1525797D01*
X989453D01*
Y1529340D01*
X991815D01*
Y1526297D01*
X994453D01*
Y1529340D01*
X996815D01*
Y1526297D01*
X999453D01*
Y1529340D01*
X1001815D01*
Y1526297D01*
X1004453D01*
Y1529340D01*
X1006815D01*
Y1525797D01*
X1002571D01*
Y1521466D01*
X1004433D01*
Y1519104D01*
X1001390D01*
Y1518120D01*
X1004433D01*
Y1515758D01*
X1001390D01*
Y1514773D01*
X1004433D01*
Y1512411D01*
X1000890D01*
Y1521466D01*
X1002071D01*
Y1525797D01*
X998634D01*
Y1521466D01*
X999906D01*
Y1519104D01*
X996862D01*
Y1518120D01*
X999906D01*
Y1515758D01*
X996862D01*
Y1514773D01*
X999906D01*
Y1512411D01*
X996362D01*
Y1521466D01*
X998134D01*
Y1525797D01*
X994697D01*
Y1521466D01*
X995378D01*
Y1519104D01*
X992335D01*
Y1518120D01*
X995378D01*
Y1515758D01*
X992335D01*
Y1514773D01*
X995378D01*
Y1512411D01*
X991835D01*
G37*
G36*
G01X1015201D02*
Y1521466D01*
X1017563D01*
Y1525797D01*
X1012819D01*
Y1529340D01*
X1015181D01*
Y1526297D01*
X1017819D01*
Y1529340D01*
X1020181D01*
Y1526297D01*
X1022819D01*
Y1529340D01*
X1025181D01*
Y1526297D01*
X1027819D01*
Y1529340D01*
X1030181D01*
Y1525797D01*
X1025937D01*
Y1521466D01*
X1027799D01*
Y1519104D01*
X1024756D01*
Y1518120D01*
X1027799D01*
Y1515758D01*
X1024756D01*
Y1514773D01*
X1027799D01*
Y1512411D01*
X1024256D01*
Y1521466D01*
X1025437D01*
Y1525797D01*
X1022000D01*
Y1521466D01*
X1023272D01*
Y1519104D01*
X1020228D01*
Y1518120D01*
X1023272D01*
Y1515758D01*
X1020228D01*
Y1514773D01*
X1023272D01*
Y1512411D01*
X1019728D01*
Y1521466D01*
X1021500D01*
Y1525797D01*
X1018063D01*
Y1521466D01*
X1018744D01*
Y1519104D01*
X1015701D01*
Y1518120D01*
X1018744D01*
Y1515758D01*
X1015701D01*
Y1514773D01*
X1018744D01*
Y1512411D01*
X1015201D01*
G37*
G36*
G01X1038567D02*
Y1521466D01*
X1040929D01*
Y1525797D01*
X1036185D01*
Y1529340D01*
X1038547D01*
Y1526297D01*
X1041185D01*
Y1529340D01*
X1043547D01*
Y1526297D01*
X1046185D01*
Y1529340D01*
X1048547D01*
Y1526297D01*
X1051185D01*
Y1529340D01*
X1053547D01*
Y1525797D01*
X1049303D01*
Y1521466D01*
X1051165D01*
Y1519104D01*
X1048122D01*
Y1518120D01*
X1051165D01*
Y1515758D01*
X1048122D01*
Y1514773D01*
X1051165D01*
Y1512411D01*
X1047622D01*
Y1521466D01*
X1048803D01*
Y1525797D01*
X1045366D01*
Y1521466D01*
X1046638D01*
Y1519104D01*
X1043594D01*
Y1518120D01*
X1046638D01*
Y1515758D01*
X1043594D01*
Y1514773D01*
X1046638D01*
Y1512411D01*
X1043094D01*
Y1521466D01*
X1044866D01*
Y1525797D01*
X1041429D01*
Y1521466D01*
X1042110D01*
Y1519104D01*
X1039067D01*
Y1518120D01*
X1042110D01*
Y1515758D01*
X1039067D01*
Y1514773D01*
X1042110D01*
Y1512411D01*
X1038567D01*
G37*
G36*
G01X1061933D02*
Y1521466D01*
X1064295D01*
Y1525797D01*
X1059551D01*
Y1529340D01*
X1061913D01*
Y1526297D01*
X1064551D01*
Y1529340D01*
X1066913D01*
Y1526297D01*
X1069551D01*
Y1529340D01*
X1071913D01*
Y1526297D01*
X1074551D01*
Y1529340D01*
X1076913D01*
Y1525797D01*
X1072669D01*
Y1521466D01*
X1074531D01*
Y1519104D01*
X1071488D01*
Y1518120D01*
X1074531D01*
Y1515758D01*
X1071488D01*
Y1514773D01*
X1074531D01*
Y1512411D01*
X1070988D01*
Y1521466D01*
X1072169D01*
Y1525797D01*
X1068732D01*
Y1521466D01*
X1070004D01*
Y1519104D01*
X1066960D01*
Y1518120D01*
X1070004D01*
Y1515758D01*
X1066960D01*
Y1514773D01*
X1070004D01*
Y1512411D01*
X1066460D01*
Y1521466D01*
X1068232D01*
Y1525797D01*
X1064795D01*
Y1521466D01*
X1065476D01*
Y1519104D01*
X1062433D01*
Y1518120D01*
X1065476D01*
Y1515758D01*
X1062433D01*
Y1514773D01*
X1065476D01*
Y1512411D01*
X1061933D01*
G37*
G36*
G01X1085299D02*
Y1521466D01*
X1087661D01*
Y1525797D01*
X1082917D01*
Y1529340D01*
X1085279D01*
Y1526297D01*
X1087917D01*
Y1529340D01*
X1090279D01*
Y1526297D01*
X1092917D01*
Y1529340D01*
X1095279D01*
Y1526297D01*
X1097917D01*
Y1529340D01*
X1100279D01*
Y1525797D01*
X1096035D01*
Y1521466D01*
X1097897D01*
Y1519104D01*
X1094854D01*
Y1518120D01*
X1097897D01*
Y1515758D01*
X1094854D01*
Y1514773D01*
X1097897D01*
Y1512411D01*
X1094354D01*
Y1521466D01*
X1095535D01*
Y1525797D01*
X1092098D01*
Y1521466D01*
X1093370D01*
Y1519104D01*
X1090326D01*
Y1518120D01*
X1093370D01*
Y1515758D01*
X1090326D01*
Y1514773D01*
X1093370D01*
Y1512411D01*
X1089826D01*
Y1521466D01*
X1091598D01*
Y1525797D01*
X1088161D01*
Y1521466D01*
X1088842D01*
Y1519104D01*
X1085799D01*
Y1518120D01*
X1088842D01*
Y1515758D01*
X1085799D01*
Y1514773D01*
X1088842D01*
Y1512411D01*
X1085299D01*
G37*
G54D297*
X1803347Y201642D03*
G54D96*
X150185Y678073D03*
X155225D03*
X150185Y676105D03*
X155225D03*
X380277Y1583235D03*
Y1585203D03*
X385317Y1583235D03*
Y1585203D03*
X451768Y1581117D03*
Y1579149D03*
X456808Y1581117D03*
Y1579149D03*
X1185672Y583306D03*
Y581338D03*
X1190712Y583306D03*
Y581338D03*
X1723814Y665222D03*
X1728854D03*
X1723814Y663254D03*
X1728854D03*
G54D198*
X609016Y274272D03*
G54D288*
X1797245Y201297D03*
G54D69*
X106843Y1381137D03*
X139443D03*
X172143Y1381249D03*
X205043Y1381144D03*
X237843Y1381004D03*
X264213Y649037D03*
X271443Y1334995D03*
X296957Y683158D03*
X304339Y1334995D03*
X329713Y703362D03*
X337243Y1334856D03*
X362773Y703129D03*
X370043Y1335042D03*
X395813Y703176D03*
X402625Y1354338D03*
X428813Y685444D03*
X461213Y660759D03*
X484865Y1340924D03*
X486135Y1351429D03*
X475865Y1361180D03*
X477135Y1371685D03*
X493813Y634326D03*
X519116Y124200D03*
X515385Y115300D03*
X527113Y600085D03*
X590156Y759400D03*
X581760Y759700D03*
X588886Y769200D03*
X580490Y769100D03*
X606091Y760386D03*
X598124Y759500D03*
X596854Y765500D03*
X714672Y515211D03*
X714399Y1399498D03*
X746632Y516077D03*
X747181Y1399598D03*
X827904Y1312682D03*
X829174Y1323187D03*
X1078581Y1381102D03*
X1111181Y1381074D03*
X1143881Y1380963D03*
X1176781D03*
X1209581Y1381149D03*
X1247572Y1335094D03*
X1289574Y562834D03*
X1291695Y567536D03*
X1280468Y1335001D03*
X1313372Y1334907D03*
X1346172Y1335141D03*
X1374765Y618274D03*
X1378754Y1354318D03*
X1407465Y651240D03*
X1440065Y683835D03*
X1472983Y703385D03*
X1506065Y703404D03*
X1538865Y703451D03*
X1571995Y681501D03*
X1604765Y647601D03*
X1637765Y628715D03*
X1662137Y1398599D03*
X1694919Y1398699D03*
G36*
G01X1584062Y587821D02*
X1593117D01*
Y585459D01*
X1597448D01*
Y590203D01*
X1600991D01*
Y587841D01*
X1597948D01*
Y585203D01*
X1600991D01*
Y582841D01*
X1597948D01*
Y580203D01*
X1600991D01*
Y577841D01*
X1597948D01*
Y575203D01*
X1600991D01*
Y572841D01*
X1597448D01*
Y577085D01*
X1593117D01*
Y575223D01*
X1590755D01*
Y578266D01*
X1589771D01*
Y575223D01*
X1587409D01*
Y578266D01*
X1586424D01*
Y575223D01*
X1584062D01*
Y578766D01*
X1593117D01*
Y577585D01*
X1597448D01*
Y581022D01*
X1593117D01*
Y579750D01*
X1590755D01*
Y582794D01*
X1589771D01*
Y579750D01*
X1587409D01*
Y582794D01*
X1586424D01*
Y579750D01*
X1584062D01*
Y583294D01*
X1593117D01*
Y581522D01*
X1597448D01*
Y584959D01*
X1593117D01*
Y584278D01*
X1590755D01*
Y587321D01*
X1589771D01*
Y584278D01*
X1587409D01*
Y587321D01*
X1586424D01*
Y584278D01*
X1584062D01*
Y587821D01*
G37*
G54D298*
G01X-476840Y-884638D02*
Y2768362D01*
X5911000D01*
Y-884638D01*
X-476840D01*
G01X8000Y-625138D02*
Y-630138D01*
G01X6543Y-625138D02*
X9457D01*
G01X14367Y-630138D02*
X11833D01*
Y-625138D01*
X14367D01*
G01X13353Y-627555D02*
X11833D01*
G01X16933Y-625138D02*
Y-630138D01*
X19467D01*
G01X23300Y-630305D02*
X23173Y-630221D01*
Y-630055D01*
X23300Y-629971D01*
X23427Y-630055D01*
Y-630221D01*
X23300Y-630305D01*
G01Y-628055D02*
X23173Y-627971D01*
Y-627805D01*
X23300Y-627721D01*
X23427Y-627805D01*
Y-627971D01*
X23300Y-628055D01*
G01X28083Y-631805D02*
X27450Y-630971D01*
X27133Y-630138D01*
Y-626805D01*
X27450Y-625971D01*
X28083Y-625138D01*
G01X33500D02*
X32993Y-625305D01*
X32613Y-625721D01*
X32360Y-626221D01*
X32170Y-626888D01*
X32107Y-627638D01*
X32170Y-628388D01*
X32360Y-629055D01*
X32613Y-629555D01*
X32993Y-629971D01*
X33500Y-630138D01*
X34007Y-629971D01*
X34387Y-629555D01*
X34640Y-629055D01*
X34830Y-628388D01*
X34893Y-627638D01*
X34830Y-626888D01*
X34640Y-626221D01*
X34387Y-625721D01*
X34007Y-625305D01*
X33500Y-625138D01*
G01X37207Y-629138D02*
X37587Y-629721D01*
X38093Y-630055D01*
X38663Y-630138D01*
X39170Y-630055D01*
X39677Y-629638D01*
X39993Y-629138D01*
X40057Y-628638D01*
X39930Y-628055D01*
X39487Y-627638D01*
X39043Y-627471D01*
X38473D01*
G01X39043D02*
X39423Y-627221D01*
X39740Y-626805D01*
X39867Y-626305D01*
X39740Y-625805D01*
X39423Y-625388D01*
X38853Y-625138D01*
X38283Y-625221D01*
X37713Y-625555D01*
G01X44017Y-631805D02*
X44650Y-630971D01*
X44967Y-630138D01*
Y-626805D01*
X44650Y-625971D01*
X44017Y-625138D01*
G01X47407Y-629138D02*
X47787Y-629721D01*
X48293Y-630055D01*
X48863Y-630138D01*
X49370Y-630055D01*
X49877Y-629638D01*
X50193Y-629138D01*
X50257Y-628638D01*
X50130Y-628055D01*
X49687Y-627638D01*
X49243Y-627471D01*
X48673D01*
G01X49243D02*
X49623Y-627221D01*
X49940Y-626805D01*
X50067Y-626305D01*
X49940Y-625805D01*
X49623Y-625388D01*
X49053Y-625138D01*
X48483Y-625221D01*
X47913Y-625555D01*
G01X52697Y-625971D02*
X53077Y-625471D01*
X53520Y-625221D01*
X54027Y-625138D01*
X54660Y-625305D01*
X55103Y-625721D01*
X55230Y-626221D01*
X55167Y-626721D01*
X54913Y-627138D01*
X53647Y-627971D01*
X53077Y-628555D01*
X52697Y-629388D01*
X52570Y-630138D01*
X55230D01*
G01X58873D02*
X59000Y-629055D01*
X59190Y-628138D01*
X59443Y-627305D01*
X59760Y-626388D01*
X60267Y-625138D01*
X57733D01*
G01X63277Y-628471D02*
X64923D01*
G01X67997Y-625971D02*
X68377Y-625471D01*
X68820Y-625221D01*
X69327Y-625138D01*
X69960Y-625305D01*
X70403Y-625721D01*
X70530Y-626221D01*
X70467Y-626721D01*
X70213Y-627138D01*
X68947Y-627971D01*
X68377Y-628555D01*
X67997Y-629388D01*
X67870Y-630138D01*
X70530D01*
G01X72907Y-629138D02*
X73287Y-629721D01*
X73793Y-630055D01*
X74363Y-630138D01*
X74870Y-630055D01*
X75377Y-629638D01*
X75693Y-629138D01*
X75757Y-628638D01*
X75630Y-628055D01*
X75187Y-627638D01*
X74743Y-627471D01*
X74173D01*
G01X74743D02*
X75123Y-627221D01*
X75440Y-626805D01*
X75567Y-626305D01*
X75440Y-625805D01*
X75123Y-625388D01*
X74553Y-625138D01*
X73983Y-625221D01*
X73413Y-625555D01*
G01X80160Y-630138D02*
Y-625138D01*
X77817Y-628721D01*
X80983D01*
G01X83107Y-629388D02*
X83487Y-629805D01*
X83930Y-630055D01*
X84500Y-630138D01*
X85070Y-629971D01*
X85513Y-629638D01*
X85830Y-629055D01*
X85893Y-628388D01*
X85767Y-627721D01*
X85450Y-627305D01*
X85007Y-626971D01*
X84563Y-626888D01*
X84120Y-626971D01*
X83550Y-627305D01*
X83740Y-625138D01*
X85450D01*
G01X93497Y-630138D02*
Y-625138D01*
X95903D01*
G01X95017Y-627555D02*
X93497D01*
G01X98217Y-630138D02*
X99800Y-625138D01*
X101383Y-630138D01*
G01X100813Y-628388D02*
X98787D01*
G01X103570Y-630138D02*
X106230Y-625138D01*
G01X103570D02*
X106230Y-630138D01*
G01X110000Y-630305D02*
X109873Y-630221D01*
Y-630055D01*
X110000Y-629971D01*
X110127Y-630055D01*
Y-630221D01*
X110000Y-630305D01*
G01Y-628055D02*
X109873Y-627971D01*
Y-627805D01*
X110000Y-627721D01*
X110127Y-627805D01*
Y-627971D01*
X110000Y-628055D01*
G01X114783Y-631805D02*
X114150Y-630971D01*
X113833Y-630138D01*
Y-626805D01*
X114150Y-625971D01*
X114783Y-625138D01*
G01X120200D02*
X119693Y-625305D01*
X119313Y-625721D01*
X119060Y-626221D01*
X118870Y-626888D01*
X118807Y-627638D01*
X118870Y-628388D01*
X119060Y-629055D01*
X119313Y-629555D01*
X119693Y-629971D01*
X120200Y-630138D01*
X120707Y-629971D01*
X121087Y-629555D01*
X121340Y-629055D01*
X121530Y-628388D01*
X121593Y-627638D01*
X121530Y-626888D01*
X121340Y-626221D01*
X121087Y-625721D01*
X120707Y-625305D01*
X120200Y-625138D01*
G01X123907Y-629138D02*
X124287Y-629721D01*
X124793Y-630055D01*
X125363Y-630138D01*
X125870Y-630055D01*
X126377Y-629638D01*
X126693Y-629138D01*
X126757Y-628638D01*
X126630Y-628055D01*
X126187Y-627638D01*
X125743Y-627471D01*
X125173D01*
G01X125743D02*
X126123Y-627221D01*
X126440Y-626805D01*
X126567Y-626305D01*
X126440Y-625805D01*
X126123Y-625388D01*
X125553Y-625138D01*
X124983Y-625221D01*
X124413Y-625555D01*
G01X130717Y-631805D02*
X131350Y-630971D01*
X131667Y-630138D01*
Y-626805D01*
X131350Y-625971D01*
X130717Y-625138D01*
G01X134107Y-629138D02*
X134487Y-629721D01*
X134993Y-630055D01*
X135563Y-630138D01*
X136070Y-630055D01*
X136577Y-629638D01*
X136893Y-629138D01*
X136957Y-628638D01*
X136830Y-628055D01*
X136387Y-627638D01*
X135943Y-627471D01*
X135373D01*
G01X135943D02*
X136323Y-627221D01*
X136640Y-626805D01*
X136767Y-626305D01*
X136640Y-625805D01*
X136323Y-625388D01*
X135753Y-625138D01*
X135183Y-625221D01*
X134613Y-625555D01*
G01X139523Y-629555D02*
X139967Y-629971D01*
X140473Y-630138D01*
X140980Y-629971D01*
X141423Y-629471D01*
X141740Y-628721D01*
X141867Y-627971D01*
Y-627055D01*
X141740Y-626305D01*
X141423Y-625638D01*
X141043Y-625305D01*
X140600Y-625138D01*
X140093Y-625305D01*
X139713Y-625638D01*
X139460Y-626138D01*
X139333Y-626805D01*
X139460Y-627388D01*
X139777Y-627971D01*
X140157Y-628305D01*
X140600Y-628388D01*
X141107Y-628221D01*
X141487Y-627805D01*
X141867Y-627055D01*
G01X145573Y-630138D02*
X145700Y-629055D01*
X145890Y-628138D01*
X146143Y-627305D01*
X146460Y-626388D01*
X146967Y-625138D01*
X144433D01*
G01X149977Y-628471D02*
X151623D01*
G01X154507Y-629138D02*
X154887Y-629721D01*
X155393Y-630055D01*
X155963Y-630138D01*
X156470Y-630055D01*
X156977Y-629638D01*
X157293Y-629138D01*
X157357Y-628638D01*
X157230Y-628055D01*
X156787Y-627638D01*
X156343Y-627471D01*
X155773D01*
G01X156343D02*
X156723Y-627221D01*
X157040Y-626805D01*
X157167Y-626305D01*
X157040Y-625805D01*
X156723Y-625388D01*
X156153Y-625138D01*
X155583Y-625221D01*
X155013Y-625555D01*
G01X159797Y-628055D02*
X160240Y-627471D01*
X160620Y-627138D01*
X161127Y-626971D01*
X161570Y-627138D01*
X161887Y-627471D01*
X162140Y-627971D01*
X162203Y-628555D01*
X162140Y-629055D01*
X161887Y-629555D01*
X161507Y-629971D01*
X161063Y-630138D01*
X160557Y-629971D01*
X160113Y-629471D01*
X159860Y-628721D01*
X159797Y-627888D01*
X159923Y-626805D01*
X160113Y-626221D01*
X160430Y-625638D01*
X160873Y-625221D01*
X161317Y-625138D01*
X161760Y-625305D01*
X162077Y-625721D01*
G01X166100Y-630138D02*
Y-625138D01*
X165340Y-626138D01*
G01Y-630138D02*
X166860D01*
G01X171960D02*
Y-625138D01*
X169617Y-628721D01*
X172783D01*
G01X-4000Y-560138D02*
Y-635138D01*
X496000D01*
Y-560138D01*
X-4000D01*
G01X191000D02*
Y-635138D01*
G01Y-610138D02*
X294000D01*
Y-585138D01*
G01X191000D02*
X294000D01*
G01X296000Y-560138D02*
Y-635138D01*
G01X294000Y-560138D02*
Y-635138D01*
G01X301507Y-620138D02*
Y-615138D01*
X302773D01*
X303280Y-615388D01*
X303660Y-615721D01*
X303977Y-616221D01*
X304230Y-616805D01*
X304293Y-617638D01*
X304230Y-618471D01*
X303977Y-619055D01*
X303660Y-619555D01*
X303280Y-619888D01*
X302773Y-620138D01*
X301507D01*
G01X306417D02*
X308000Y-615138D01*
X309583Y-620138D01*
G01X309013Y-618388D02*
X306987D01*
G01X313100Y-615138D02*
Y-620138D01*
G01X311643Y-615138D02*
X314557D01*
G01X319467Y-620138D02*
X316933D01*
Y-615138D01*
X319467D01*
G01X318453Y-617555D02*
X316933D01*
G01X323300Y-620305D02*
X323173Y-620221D01*
Y-620055D01*
X323300Y-619971D01*
X323427Y-620055D01*
Y-620221D01*
X323300Y-620305D01*
G01Y-618055D02*
X323173Y-617971D01*
Y-617805D01*
X323300Y-617721D01*
X323427Y-617805D01*
Y-617971D01*
X323300Y-618055D01*
G01X296000Y-610138D02*
X496000D01*
G01X301633Y-595138D02*
Y-590138D01*
X303153D01*
X303660Y-590388D01*
X304040Y-590971D01*
X304167Y-591638D01*
X304040Y-592305D01*
X303723Y-592805D01*
X303153Y-593055D01*
X301633D01*
G01X306860Y-595305D02*
X309140Y-590138D01*
G01X311643Y-595138D02*
Y-590138D01*
X314557Y-595138D01*
Y-590138D01*
G01X318200Y-595305D02*
X318073Y-595221D01*
Y-595055D01*
X318200Y-594971D01*
X318327Y-595055D01*
Y-595221D01*
X318200Y-595305D01*
G01Y-593055D02*
X318073Y-592971D01*
Y-592805D01*
X318200Y-592721D01*
X318327Y-592805D01*
Y-592971D01*
X318200Y-593055D01*
G01X296000Y-585138D02*
X496000D01*
G01X301633Y-570138D02*
Y-565138D01*
X303153D01*
X303660Y-565388D01*
X304040Y-565971D01*
X304167Y-566638D01*
X304040Y-567305D01*
X303723Y-567805D01*
X303153Y-568055D01*
X301633D01*
G01X306733Y-570138D02*
Y-565138D01*
X308317D01*
X308823Y-565388D01*
X309140Y-565721D01*
X309267Y-566388D01*
X309140Y-567055D01*
X308760Y-567471D01*
X308317Y-567721D01*
X306733D01*
G01X308317D02*
X309267Y-570138D01*
G01X313100D02*
X312593Y-570055D01*
X312150Y-569721D01*
X311770Y-569221D01*
X311517Y-568638D01*
X311390Y-567971D01*
Y-567305D01*
X311517Y-566638D01*
X311770Y-566055D01*
X312150Y-565555D01*
X312593Y-565221D01*
X313100Y-565138D01*
X313607Y-565221D01*
X314050Y-565555D01*
X314430Y-566055D01*
X314683Y-566638D01*
X314810Y-567305D01*
Y-567971D01*
X314683Y-568638D01*
X314430Y-569221D01*
X314050Y-569721D01*
X313607Y-570055D01*
X313100Y-570138D01*
G01X316933Y-569138D02*
X317250Y-569638D01*
X317630Y-569971D01*
X318073Y-570138D01*
X318580Y-569971D01*
X318960Y-569638D01*
X319340Y-569138D01*
X319467Y-568471D01*
Y-565138D01*
G01X324567Y-570138D02*
X322033D01*
Y-565138D01*
X324567D01*
G01X323553Y-567555D02*
X322033D01*
G01X329793Y-565555D02*
X329413Y-565305D01*
X328970Y-565138D01*
X328463D01*
X327893Y-565388D01*
X327450Y-565805D01*
X327133Y-566305D01*
X326880Y-567138D01*
X326817Y-567888D01*
X326943Y-568638D01*
X327133Y-569138D01*
X327513Y-569638D01*
X327957Y-569971D01*
X328400Y-570138D01*
X328843D01*
X329287Y-569971D01*
X329667Y-569721D01*
X329983Y-569388D01*
G01X333500Y-565138D02*
Y-570138D01*
G01X332043Y-565138D02*
X334957D01*
G01X338600Y-570305D02*
X338473Y-570221D01*
Y-570055D01*
X338600Y-569971D01*
X338727Y-570055D01*
Y-570221D01*
X338600Y-570305D01*
G01Y-568055D02*
X338473Y-567971D01*
Y-567805D01*
X338600Y-567721D01*
X338727Y-567805D01*
Y-567971D01*
X338600Y-568055D01*
G01X411000Y-610138D02*
Y-635138D01*
G01X413633Y-612638D02*
Y-617638D01*
X416167D01*
G01X419240Y-612638D02*
X420760D01*
G01X420000D02*
Y-617638D01*
G01X419240D02*
X420760D01*
G01X425607Y-614971D02*
X425860Y-614721D01*
X426050Y-614305D01*
X426177Y-613721D01*
X426050Y-613221D01*
X425797Y-612888D01*
X425353Y-612638D01*
X423643D01*
Y-617638D01*
X425733D01*
X426177Y-617305D01*
X426430Y-616805D01*
X426557Y-616221D01*
X426430Y-615638D01*
X426050Y-615138D01*
X425607Y-614971D01*
X423643D01*
G01X430200Y-617805D02*
X430073Y-617721D01*
Y-617555D01*
X430200Y-617471D01*
X430327Y-617555D01*
Y-617721D01*
X430200Y-617805D01*
G01Y-615555D02*
X430073Y-615471D01*
Y-615305D01*
X430200Y-615221D01*
X430327Y-615305D01*
Y-615471D01*
X430200Y-615555D01*
G01X454000Y-610138D02*
Y-635138D01*
G01Y-585138D02*
Y-610138D01*
G01X459013Y-637305D02*
X459120Y-637180D01*
X459200Y-636971D01*
X459253Y-636680D01*
X459200Y-636430D01*
X459093Y-636263D01*
X458907Y-636138D01*
X458187D01*
Y-638638D01*
X459067D01*
X459253Y-638471D01*
X459360Y-638221D01*
X459413Y-637930D01*
X459360Y-637638D01*
X459200Y-637388D01*
X459013Y-637305D01*
X458187D01*
G01X461480Y-638638D02*
Y-636971D01*
G01Y-637263D02*
X461373Y-637096D01*
X461213Y-637013D01*
X461027Y-636971D01*
X460840Y-637055D01*
X460680Y-637221D01*
X460573Y-637471D01*
X460520Y-637805D01*
X460573Y-638138D01*
X460680Y-638388D01*
X460840Y-638555D01*
X461027Y-638638D01*
X461213Y-638596D01*
X461373Y-638471D01*
X461480Y-638305D01*
G01X462800Y-638346D02*
X462933Y-638513D01*
X463120Y-638638D01*
X463280D01*
X463440Y-638555D01*
X463547Y-638430D01*
X463600Y-638263D01*
X463573Y-638013D01*
X463467Y-637888D01*
X462987Y-637638D01*
X462880Y-637346D01*
X462933Y-637138D01*
X463040Y-637013D01*
X463200Y-636971D01*
X463360Y-637013D01*
X463520Y-637138D01*
G01X465000Y-637513D02*
X465853D01*
X465773Y-637221D01*
X465640Y-637055D01*
X465453Y-636971D01*
X465267Y-637013D01*
X465107Y-637138D01*
X465000Y-637430D01*
X464947Y-637680D01*
Y-637930D01*
X465000Y-638180D01*
X465133Y-638430D01*
X465293Y-638596D01*
X465480Y-638638D01*
X465667Y-638555D01*
X465853Y-638305D01*
G01X467120Y-638638D02*
Y-636138D01*
G01Y-637388D02*
X467253Y-637138D01*
X467413Y-637013D01*
X467573Y-636971D01*
X467813Y-637055D01*
X467973Y-637221D01*
X468080Y-637513D01*
Y-637846D01*
X468027Y-638180D01*
X467920Y-638430D01*
X467733Y-638596D01*
X467573Y-638638D01*
X467413Y-638596D01*
X467253Y-638471D01*
X467120Y-638263D01*
G01X469800Y-638638D02*
X469640Y-638596D01*
X469480Y-638430D01*
X469373Y-638138D01*
X469320Y-637805D01*
X469373Y-637471D01*
X469480Y-637180D01*
X469640Y-637013D01*
X469800Y-636971D01*
X469960Y-637013D01*
X470120Y-637180D01*
X470227Y-637471D01*
X470253Y-637805D01*
X470227Y-638138D01*
X470120Y-638430D01*
X469960Y-638596D01*
X469800Y-638638D01*
G01X472480D02*
Y-636971D01*
G01Y-637263D02*
X472373Y-637096D01*
X472213Y-637013D01*
X472027Y-636971D01*
X471840Y-637055D01*
X471680Y-637221D01*
X471573Y-637471D01*
X471520Y-637805D01*
X471573Y-638138D01*
X471680Y-638388D01*
X471840Y-638555D01*
X472027Y-638638D01*
X472213Y-638596D01*
X472373Y-638471D01*
X472480Y-638305D01*
G01X473827Y-638638D02*
Y-636971D01*
G01Y-637305D02*
X473960Y-637138D01*
X474093Y-637013D01*
X474280Y-636971D01*
X474413Y-637013D01*
X474573Y-637138D01*
G01X476880Y-636138D02*
Y-638638D01*
G01Y-638263D02*
X476773Y-638471D01*
X476613Y-638596D01*
X476427Y-638638D01*
X476213Y-638555D01*
X476053Y-638346D01*
X475947Y-638096D01*
X475920Y-637805D01*
X475947Y-637513D01*
X476053Y-637263D01*
X476213Y-637055D01*
X476427Y-636971D01*
X476613Y-637013D01*
X476747Y-637096D01*
X476880Y-637263D01*
G01X480267Y-638638D02*
Y-636138D01*
X480933D01*
X481147Y-636263D01*
X481280Y-636430D01*
X481333Y-636763D01*
X481280Y-637096D01*
X481120Y-637305D01*
X480933Y-637430D01*
X480267D01*
G01X480933D02*
X481333Y-638638D01*
G01X482600Y-637513D02*
X483453D01*
X483373Y-637221D01*
X483240Y-637055D01*
X483053Y-636971D01*
X482867Y-637013D01*
X482707Y-637138D01*
X482600Y-637430D01*
X482547Y-637680D01*
Y-637930D01*
X482600Y-638180D01*
X482733Y-638430D01*
X482893Y-638596D01*
X483080Y-638638D01*
X483267Y-638555D01*
X483453Y-638305D01*
G01X484720Y-636971D02*
X485200Y-638638D01*
X485680Y-636971D01*
G01X487400Y-638721D02*
X487347Y-638680D01*
Y-638596D01*
X487400Y-638555D01*
X487453Y-638596D01*
Y-638680D01*
X487400Y-638721D01*
G01X489147Y-638346D02*
X489333Y-638555D01*
X489547Y-638638D01*
X489760Y-638555D01*
X489947Y-638305D01*
X490080Y-637930D01*
X490133Y-637555D01*
Y-637096D01*
X490080Y-636721D01*
X489947Y-636388D01*
X489787Y-636221D01*
X489600Y-636138D01*
X489387Y-636221D01*
X489227Y-636388D01*
X489120Y-636638D01*
X489067Y-636971D01*
X489120Y-637263D01*
X489253Y-637555D01*
X489413Y-637721D01*
X489600Y-637763D01*
X489813Y-637680D01*
X489973Y-637471D01*
X490133Y-637096D01*
G01X492013Y-637305D02*
X492120Y-637180D01*
X492200Y-636971D01*
X492253Y-636680D01*
X492200Y-636430D01*
X492093Y-636263D01*
X491907Y-636138D01*
X491187D01*
Y-638638D01*
X492067D01*
X492253Y-638471D01*
X492360Y-638221D01*
X492413Y-637930D01*
X492360Y-637638D01*
X492200Y-637388D01*
X492013Y-637305D01*
X491187D01*
G01X457900Y-612638D02*
Y-617638D01*
G01X456443Y-612638D02*
X459357D01*
G01X463000Y-617638D02*
X462620Y-617555D01*
X462240Y-617221D01*
X461987Y-616638D01*
X461860Y-615971D01*
X461987Y-615305D01*
X462240Y-614721D01*
X462620Y-614388D01*
X463000Y-614305D01*
X463380Y-614388D01*
X463760Y-614721D01*
X464013Y-615305D01*
X464077Y-615971D01*
X464013Y-616638D01*
X463760Y-617221D01*
X463380Y-617555D01*
X463000Y-617638D01*
G01X468100D02*
X467720Y-617555D01*
X467340Y-617221D01*
X467087Y-616638D01*
X466960Y-615971D01*
X467087Y-615305D01*
X467340Y-614721D01*
X467720Y-614388D01*
X468100Y-614305D01*
X468480Y-614388D01*
X468860Y-614721D01*
X469113Y-615305D01*
X469177Y-615971D01*
X469113Y-616638D01*
X468860Y-617221D01*
X468480Y-617555D01*
X468100Y-617638D01*
G01X473200D02*
Y-612638D01*
G01X478300Y-617805D02*
X478173Y-617721D01*
Y-617555D01*
X478300Y-617471D01*
X478427Y-617555D01*
Y-617721D01*
X478300Y-617805D01*
G01Y-615555D02*
X478173Y-615471D01*
Y-615305D01*
X478300Y-615221D01*
X478427Y-615305D01*
Y-615471D01*
X478300Y-615555D01*
G01X456633Y-592638D02*
Y-587638D01*
X458217D01*
X458723Y-587888D01*
X459040Y-588221D01*
X459167Y-588888D01*
X459040Y-589555D01*
X458660Y-589971D01*
X458217Y-590221D01*
X456633D01*
G01X458217D02*
X459167Y-592638D01*
G01X464267D02*
X461733D01*
Y-587638D01*
X464267D01*
G01X463253Y-590055D02*
X461733D01*
G01X466517Y-587638D02*
X468100Y-592638D01*
X469683Y-587638D01*
G01X473200Y-592805D02*
X473073Y-592721D01*
Y-592555D01*
X473200Y-592471D01*
X473327Y-592555D01*
Y-592721D01*
X473200Y-592805D01*
G01Y-590555D02*
X473073Y-590471D01*
Y-590305D01*
X473200Y-590221D01*
X473327Y-590305D01*
Y-590471D01*
X473200Y-590555D01*
G01X-476840Y-884638D02*
Y2768362D01*
X5911000D01*
Y-884638D01*
X-476840D01*
G01X8820Y-607488D02*
X10387D01*
Y-609378D01*
X9917Y-610008D01*
X9368Y-610428D01*
X8585Y-610638D01*
X7802Y-610428D01*
X7253Y-610008D01*
X6783Y-609378D01*
X6470Y-608643D01*
X6313Y-607803D01*
Y-607068D01*
X6470Y-606438D01*
X6783Y-605703D01*
X7253Y-605073D01*
X7723Y-604653D01*
X8350Y-604338D01*
X8898D01*
X9525Y-604548D01*
X9995Y-604968D01*
G01X12927Y-604338D02*
Y-608853D01*
X13240Y-609798D01*
X13867Y-610428D01*
X14650Y-610638D01*
X15433Y-610428D01*
X16060Y-609798D01*
X16373Y-608853D01*
Y-604338D01*
G01X20010D02*
X21890D01*
G01X20950D02*
Y-610638D01*
G01X20010D02*
X21890D01*
G01X25605Y-609798D02*
X26232Y-610323D01*
X26937Y-610638D01*
X27563D01*
X28190Y-610323D01*
X28660Y-609798D01*
X28895Y-609063D01*
X28738Y-608328D01*
X28347Y-607698D01*
X27642Y-607278D01*
X26702Y-607068D01*
X26153Y-606648D01*
X25918Y-605913D01*
X26075Y-605178D01*
X26467Y-604653D01*
X27015Y-604338D01*
X27563D01*
X28112Y-604548D01*
X28582Y-605073D01*
G01X31905Y-610638D02*
Y-604338D01*
G01X35195D02*
Y-610638D01*
G01Y-607488D02*
X31905D01*
G01X37892Y-610638D02*
X39850Y-604338D01*
X41808Y-610638D01*
G01X41103Y-608433D02*
X38597D01*
G01X44348Y-610638D02*
Y-604338D01*
X47952Y-610638D01*
Y-604338D01*
G01X57027Y-610638D02*
Y-604338D01*
X58593D01*
X59220Y-604653D01*
X59690Y-605073D01*
X60082Y-605703D01*
X60395Y-606438D01*
X60473Y-607488D01*
X60395Y-608538D01*
X60082Y-609273D01*
X59690Y-609903D01*
X59220Y-610323D01*
X58593Y-610638D01*
X57027D01*
G01X64110Y-604338D02*
X65990D01*
G01X65050D02*
Y-610638D01*
G01X64110D02*
X65990D01*
G01X69705Y-609798D02*
X70332Y-610323D01*
X71037Y-610638D01*
X71663D01*
X72290Y-610323D01*
X72760Y-609798D01*
X72995Y-609063D01*
X72838Y-608328D01*
X72447Y-607698D01*
X71742Y-607278D01*
X70802Y-607068D01*
X70253Y-606648D01*
X70018Y-605913D01*
X70175Y-605178D01*
X70567Y-604653D01*
X71115Y-604338D01*
X71663D01*
X72212Y-604548D01*
X72682Y-605073D01*
G01X77650Y-604338D02*
Y-610638D01*
G01X75848Y-604338D02*
X79452D01*
G01X83950Y-610848D02*
X83793Y-610743D01*
Y-610533D01*
X83950Y-610428D01*
X84107Y-610533D01*
Y-610743D01*
X83950Y-610848D01*
G01X90093Y-611793D02*
X90407Y-610428D01*
G01X96550Y-604338D02*
Y-610638D01*
G01X94748Y-604338D02*
X98352D01*
G01X100892Y-610638D02*
X102850Y-604338D01*
X104808Y-610638D01*
G01X104103Y-608433D02*
X101597D01*
G01X109150Y-610638D02*
X108523Y-610533D01*
X107975Y-610113D01*
X107505Y-609483D01*
X107192Y-608748D01*
X107035Y-607908D01*
Y-607068D01*
X107192Y-606228D01*
X107505Y-605493D01*
X107975Y-604863D01*
X108523Y-604443D01*
X109150Y-604338D01*
X109777Y-604443D01*
X110325Y-604863D01*
X110795Y-605493D01*
X111108Y-606228D01*
X111265Y-607068D01*
Y-607908D01*
X111108Y-608748D01*
X110795Y-609483D01*
X110325Y-610113D01*
X109777Y-610533D01*
X109150Y-610638D01*
G01X115450D02*
Y-607803D01*
X113883Y-604338D01*
G01X117017D02*
X115450Y-607803D01*
G01X120027Y-604338D02*
Y-608853D01*
X120340Y-609798D01*
X120967Y-610428D01*
X121750Y-610638D01*
X122533Y-610428D01*
X123160Y-609798D01*
X123473Y-608853D01*
Y-604338D01*
G01X126092Y-610638D02*
X128050Y-604338D01*
X130008Y-610638D01*
G01X129303Y-608433D02*
X126797D01*
G01X132548Y-610638D02*
Y-604338D01*
X136152Y-610638D01*
Y-604338D01*
G01X10073Y-614863D02*
X9603Y-614548D01*
X9055Y-614338D01*
X8428D01*
X7723Y-614653D01*
X7175Y-615178D01*
X6783Y-615808D01*
X6470Y-616858D01*
X6392Y-617803D01*
X6548Y-618748D01*
X6783Y-619378D01*
X7253Y-620008D01*
X7802Y-620428D01*
X8350Y-620638D01*
X8898D01*
X9447Y-620428D01*
X9917Y-620113D01*
X10308Y-619693D01*
G01X13710Y-614338D02*
X15590D01*
G01X14650D02*
Y-620638D01*
G01X13710D02*
X15590D01*
G01X20950Y-614338D02*
Y-620638D01*
G01X19148Y-614338D02*
X22752D01*
G01X27250Y-620638D02*
Y-617803D01*
X25683Y-614338D01*
G01X28817D02*
X27250Y-617803D01*
G01X38127Y-619378D02*
X38597Y-620113D01*
X39223Y-620533D01*
X39928Y-620638D01*
X40555Y-620533D01*
X41182Y-620008D01*
X41573Y-619378D01*
X41652Y-618748D01*
X41495Y-618013D01*
X40947Y-617488D01*
X40398Y-617278D01*
X39693D01*
G01X40398D02*
X40868Y-616963D01*
X41260Y-616438D01*
X41417Y-615808D01*
X41260Y-615178D01*
X40868Y-614653D01*
X40163Y-614338D01*
X39458Y-614443D01*
X38753Y-614863D01*
G01X44427Y-619378D02*
X44897Y-620113D01*
X45523Y-620533D01*
X46228Y-620638D01*
X46855Y-620533D01*
X47482Y-620008D01*
X47873Y-619378D01*
X47952Y-618748D01*
X47795Y-618013D01*
X47247Y-617488D01*
X46698Y-617278D01*
X45993D01*
G01X46698D02*
X47168Y-616963D01*
X47560Y-616438D01*
X47717Y-615808D01*
X47560Y-615178D01*
X47168Y-614653D01*
X46463Y-614338D01*
X45758Y-614443D01*
X45053Y-614863D01*
G01X50727Y-619378D02*
X51197Y-620113D01*
X51823Y-620533D01*
X52528Y-620638D01*
X53155Y-620533D01*
X53782Y-620008D01*
X54173Y-619378D01*
X54252Y-618748D01*
X54095Y-618013D01*
X53547Y-617488D01*
X52998Y-617278D01*
X52293D01*
G01X52998D02*
X53468Y-616963D01*
X53860Y-616438D01*
X54017Y-615808D01*
X53860Y-615178D01*
X53468Y-614653D01*
X52763Y-614338D01*
X52058Y-614443D01*
X51353Y-614863D01*
G01X58593Y-620638D02*
X58750Y-619273D01*
X58985Y-618118D01*
X59298Y-617068D01*
X59690Y-615913D01*
X60317Y-614338D01*
X57183D01*
G01X64893Y-620638D02*
X65050Y-619273D01*
X65285Y-618118D01*
X65598Y-617068D01*
X65990Y-615913D01*
X66617Y-614338D01*
X63483D01*
G01X71193Y-621793D02*
X71507Y-620428D01*
G01X77650Y-614338D02*
Y-620638D01*
G01X75848Y-614338D02*
X79452D01*
G01X81992Y-620638D02*
X83950Y-614338D01*
X85908Y-620638D01*
G01X85203Y-618433D02*
X82697D01*
G01X89310Y-614338D02*
X91190D01*
G01X90250D02*
Y-620638D01*
G01X89310D02*
X91190D01*
G01X94200Y-614338D02*
X95297Y-620638D01*
X96550Y-614338D01*
X97803Y-620638D01*
X98900Y-614338D01*
G01X100892Y-620638D02*
X102850Y-614338D01*
X104808Y-620638D01*
G01X104103Y-618433D02*
X101597D01*
G01X107348Y-620638D02*
Y-614338D01*
X110952Y-620638D01*
Y-614338D01*
G01X121358Y-622738D02*
X120575Y-621688D01*
X120183Y-620638D01*
Y-616438D01*
X120575Y-615388D01*
X121358Y-614338D01*
G01X132783Y-620638D02*
Y-614338D01*
X134742D01*
X135368Y-614653D01*
X135760Y-615073D01*
X135917Y-615913D01*
X135760Y-616753D01*
X135290Y-617278D01*
X134742Y-617593D01*
X132783D01*
G01X134742D02*
X135917Y-620638D01*
G01X140650Y-620848D02*
X140493Y-620743D01*
Y-620533D01*
X140650Y-620428D01*
X140807Y-620533D01*
Y-620743D01*
X140650Y-620848D01*
G01X146950Y-620638D02*
X146323Y-620533D01*
X145775Y-620113D01*
X145305Y-619483D01*
X144992Y-618748D01*
X144835Y-617908D01*
Y-617068D01*
X144992Y-616228D01*
X145305Y-615493D01*
X145775Y-614863D01*
X146323Y-614443D01*
X146950Y-614338D01*
X147577Y-614443D01*
X148125Y-614863D01*
X148595Y-615493D01*
X148908Y-616228D01*
X149065Y-617068D01*
Y-617908D01*
X148908Y-618748D01*
X148595Y-619483D01*
X148125Y-620113D01*
X147577Y-620533D01*
X146950Y-620638D01*
G01X153250Y-620848D02*
X153093Y-620743D01*
Y-620533D01*
X153250Y-620428D01*
X153407Y-620533D01*
Y-620743D01*
X153250Y-620848D01*
G01X161273Y-614863D02*
X160803Y-614548D01*
X160255Y-614338D01*
X159628D01*
X158923Y-614653D01*
X158375Y-615178D01*
X157983Y-615808D01*
X157670Y-616858D01*
X157592Y-617803D01*
X157748Y-618748D01*
X157983Y-619378D01*
X158453Y-620008D01*
X159002Y-620428D01*
X159550Y-620638D01*
X160098D01*
X160647Y-620428D01*
X161117Y-620113D01*
X161508Y-619693D01*
G01X165850Y-620848D02*
X165693Y-620743D01*
Y-620533D01*
X165850Y-620428D01*
X166007Y-620533D01*
Y-620743D01*
X165850Y-620848D01*
G01X172542Y-622738D02*
X173325Y-621688D01*
X173717Y-620638D01*
Y-616438D01*
X173325Y-615388D01*
X172542Y-614338D01*
G01X6548Y-600638D02*
Y-594338D01*
X10152Y-600638D01*
Y-594338D01*
G01X14650Y-600638D02*
X14023Y-600533D01*
X13475Y-600113D01*
X13005Y-599483D01*
X12692Y-598748D01*
X12535Y-597908D01*
Y-597068D01*
X12692Y-596228D01*
X13005Y-595493D01*
X13475Y-594863D01*
X14023Y-594443D01*
X14650Y-594338D01*
X15277Y-594443D01*
X15825Y-594863D01*
X16295Y-595493D01*
X16608Y-596228D01*
X16765Y-597068D01*
Y-597908D01*
X16608Y-598748D01*
X16295Y-599483D01*
X15825Y-600113D01*
X15277Y-600533D01*
X14650Y-600638D01*
G01X20950Y-600848D02*
X20793Y-600743D01*
Y-600533D01*
X20950Y-600428D01*
X21107Y-600533D01*
Y-600743D01*
X20950Y-600848D01*
G01X25762Y-595388D02*
X26232Y-594758D01*
X26780Y-594443D01*
X27407Y-594338D01*
X28190Y-594548D01*
X28738Y-595073D01*
X28895Y-595703D01*
X28817Y-596333D01*
X28503Y-596858D01*
X26937Y-597908D01*
X26232Y-598643D01*
X25762Y-599693D01*
X25605Y-600638D01*
X28895D01*
G01X33550D02*
Y-594338D01*
X32610Y-595598D01*
G01Y-600638D02*
X34490D01*
G01X39850D02*
Y-594338D01*
X38910Y-595598D01*
G01Y-600638D02*
X40790D01*
G01X45993Y-601793D02*
X46307Y-600428D01*
G01X50100Y-594338D02*
X51197Y-600638D01*
X52450Y-594338D01*
X53703Y-600638D01*
X54800Y-594338D01*
G01X60317Y-600638D02*
X57183D01*
Y-594338D01*
X60317D01*
G01X59063Y-597383D02*
X57183D01*
G01X63248Y-600638D02*
Y-594338D01*
X66852Y-600638D01*
Y-594338D01*
G01X69705Y-600638D02*
Y-594338D01*
G01X72995D02*
Y-600638D01*
G01Y-597488D02*
X69705D01*
G01X75927Y-594338D02*
Y-598853D01*
X76240Y-599798D01*
X76867Y-600428D01*
X77650Y-600638D01*
X78433Y-600428D01*
X79060Y-599798D01*
X79373Y-598853D01*
Y-594338D01*
G01X81992Y-600638D02*
X83950Y-594338D01*
X85908Y-600638D01*
G01X85203Y-598433D02*
X82697D01*
G01X95062Y-595388D02*
X95532Y-594758D01*
X96080Y-594443D01*
X96707Y-594338D01*
X97490Y-594548D01*
X98038Y-595073D01*
X98195Y-595703D01*
X98117Y-596333D01*
X97803Y-596858D01*
X96237Y-597908D01*
X95532Y-598643D01*
X95062Y-599693D01*
X94905Y-600638D01*
X98195D01*
G01X101048D02*
Y-594338D01*
X104652Y-600638D01*
Y-594338D01*
G01X107427Y-600638D02*
Y-594338D01*
X108993D01*
X109620Y-594653D01*
X110090Y-595073D01*
X110482Y-595703D01*
X110795Y-596438D01*
X110873Y-597488D01*
X110795Y-598538D01*
X110482Y-599273D01*
X110090Y-599903D01*
X109620Y-600323D01*
X108993Y-600638D01*
X107427D01*
G01X120183D02*
Y-594338D01*
X122142D01*
X122768Y-594653D01*
X123160Y-595073D01*
X123317Y-595913D01*
X123160Y-596753D01*
X122690Y-597278D01*
X122142Y-597593D01*
X120183D01*
G01X122142D02*
X123317Y-600638D01*
G01X126327D02*
Y-594338D01*
X127893D01*
X128520Y-594653D01*
X128990Y-595073D01*
X129382Y-595703D01*
X129695Y-596438D01*
X129773Y-597488D01*
X129695Y-598538D01*
X129382Y-599273D01*
X128990Y-599903D01*
X128520Y-600323D01*
X127893Y-600638D01*
X126327D01*
G01X134350Y-600848D02*
X134193Y-600743D01*
Y-600533D01*
X134350Y-600428D01*
X134507Y-600533D01*
Y-600743D01*
X134350Y-600848D01*
G01X30650Y-589938D02*
X28130Y-589521D01*
X25925Y-587855D01*
X24035Y-585355D01*
X22775Y-582438D01*
X22145Y-579105D01*
Y-575771D01*
X22775Y-572438D01*
X24035Y-569521D01*
X25925Y-567022D01*
X28130Y-565355D01*
X30650Y-564938D01*
X33170Y-565355D01*
X35375Y-567022D01*
X37265Y-569521D01*
X38525Y-572438D01*
X39155Y-575771D01*
Y-579105D01*
X38525Y-582438D01*
X37265Y-585355D01*
X35375Y-587855D01*
X33170Y-589521D01*
X30650Y-589938D01*
G01X33170Y-583271D02*
X36950Y-589938D01*
G01X50495Y-573272D02*
Y-584938D01*
X51755Y-587855D01*
X53645Y-589521D01*
X55850Y-589938D01*
X58055Y-589521D01*
X59945Y-587855D01*
X61205Y-584938D01*
G01Y-589938D02*
Y-573272D01*
G01X86720Y-589938D02*
Y-573272D01*
G01Y-576188D02*
X85460Y-574522D01*
X83570Y-573688D01*
X81365Y-573272D01*
X79160Y-574105D01*
X77270Y-575771D01*
X76010Y-578272D01*
X75380Y-581605D01*
X76010Y-584938D01*
X77270Y-587439D01*
X79160Y-589105D01*
X81365Y-589938D01*
X83570Y-589521D01*
X85460Y-588272D01*
X86720Y-586605D01*
G01X100895Y-589938D02*
Y-573272D01*
G01Y-577438D02*
X102155Y-575355D01*
X104045Y-573688D01*
X106565Y-573272D01*
X108770Y-573688D01*
X110660Y-575355D01*
X111605Y-578272D01*
Y-589938D01*
G01X131450Y-564938D02*
Y-589938D01*
G01X127040Y-573272D02*
X135860D01*
G01X162320Y-589938D02*
Y-573272D01*
G01Y-576188D02*
X161060Y-574522D01*
X159170Y-573688D01*
X156965Y-573272D01*
X154760Y-574105D01*
X152870Y-575771D01*
X151610Y-578272D01*
X150980Y-581605D01*
X151610Y-584938D01*
X152870Y-587439D01*
X154760Y-589105D01*
X156965Y-589938D01*
X159170Y-589521D01*
X161060Y-588272D01*
X162320Y-586605D01*
G01X213500Y-602638D02*
Y-594638D01*
X215900D01*
X216700Y-595038D01*
X217300Y-595971D01*
X217500Y-597038D01*
X217300Y-598105D01*
X216800Y-598905D01*
X215900Y-599305D01*
X213500D01*
G01X221000Y-602638D02*
X223500Y-594638D01*
X226000Y-602638D01*
G01X225100Y-599838D02*
X221900D01*
G01X229400Y-601572D02*
X230200Y-602238D01*
X231100Y-602638D01*
X231900D01*
X232700Y-602238D01*
X233300Y-601572D01*
X233600Y-600638D01*
X233400Y-599705D01*
X232900Y-598905D01*
X232000Y-598371D01*
X230800Y-598105D01*
X230100Y-597571D01*
X229800Y-596638D01*
X230000Y-595705D01*
X230500Y-595038D01*
X231200Y-594638D01*
X231900D01*
X232600Y-594905D01*
X233200Y-595571D01*
G01X239500Y-594638D02*
Y-602638D01*
G01X237200Y-594638D02*
X241800D01*
G01X246200Y-599971D02*
X248800D01*
G01X255500Y-594638D02*
Y-602638D01*
G01X253200Y-594638D02*
X257800D01*
G01X263500Y-602638D02*
X262700Y-602505D01*
X262000Y-601971D01*
X261400Y-601171D01*
X261000Y-600238D01*
X260800Y-599171D01*
Y-598105D01*
X261000Y-597038D01*
X261400Y-596105D01*
X262000Y-595305D01*
X262700Y-594771D01*
X263500Y-594638D01*
X264300Y-594771D01*
X265000Y-595305D01*
X265600Y-596105D01*
X266000Y-597038D01*
X266200Y-598105D01*
Y-599171D01*
X266000Y-600238D01*
X265600Y-601171D01*
X265000Y-601971D01*
X264300Y-602505D01*
X263500Y-602638D01*
G01X269500D02*
Y-594638D01*
X271900D01*
X272700Y-595038D01*
X273300Y-595971D01*
X273500Y-597038D01*
X273300Y-598105D01*
X272800Y-598905D01*
X271900Y-599305D01*
X269500D01*
G01X202000Y-569638D02*
Y-577638D01*
X206000D01*
G01X213800D02*
Y-572305D01*
G01Y-573238D02*
X213400Y-572705D01*
X212800Y-572438D01*
X212100Y-572305D01*
X211400Y-572571D01*
X210800Y-573105D01*
X210400Y-573905D01*
X210200Y-574971D01*
X210400Y-576038D01*
X210800Y-576838D01*
X211400Y-577371D01*
X212100Y-577638D01*
X212800Y-577505D01*
X213400Y-577105D01*
X213800Y-576572D01*
G01X217900Y-580038D02*
X218500Y-580305D01*
X219300Y-580038D01*
X219800Y-579505D01*
X220200Y-578838D01*
X220800Y-576705D01*
X222100Y-572305D01*
G01X218900D02*
X220800Y-576705D01*
G01X226500Y-574038D02*
X229700D01*
X229400Y-573105D01*
X228900Y-572571D01*
X228200Y-572305D01*
X227500Y-572438D01*
X226900Y-572838D01*
X226500Y-573771D01*
X226300Y-574572D01*
Y-575371D01*
X226500Y-576171D01*
X227000Y-576971D01*
X227600Y-577505D01*
X228300Y-577638D01*
X229000Y-577371D01*
X229700Y-576572D01*
G01X234600Y-577638D02*
Y-572305D01*
G01Y-573371D02*
X235100Y-572838D01*
X235600Y-572438D01*
X236300Y-572305D01*
X236800Y-572438D01*
X237400Y-572838D01*
G01X226000Y-626038D02*
X226500Y-626838D01*
X227100Y-627371D01*
X227800Y-627638D01*
X228600Y-627371D01*
X229200Y-626838D01*
X229800Y-626038D01*
X230000Y-624971D01*
Y-619638D01*
G01X237800Y-627638D02*
Y-622305D01*
G01Y-623238D02*
X237400Y-622705D01*
X236800Y-622438D01*
X236100Y-622305D01*
X235400Y-622571D01*
X234800Y-623105D01*
X234400Y-623905D01*
X234200Y-624971D01*
X234400Y-626038D01*
X234800Y-626838D01*
X235400Y-627371D01*
X236100Y-627638D01*
X236800Y-627505D01*
X237400Y-627105D01*
X237800Y-626572D01*
G01X245600Y-622971D02*
X244900Y-622438D01*
X244300Y-622305D01*
X243500Y-622571D01*
X242900Y-623105D01*
X242500Y-624038D01*
X242400Y-624971D01*
X242500Y-625905D01*
X242900Y-626705D01*
X243500Y-627371D01*
X244300Y-627638D01*
X245000Y-627371D01*
X245600Y-626838D01*
G01X250300Y-627638D02*
Y-619638D01*
G01X253500Y-622305D02*
X250300Y-625371D01*
G01X251600Y-624171D02*
X253700Y-627638D01*
G01X328600Y-620971D02*
X329200Y-620171D01*
X329900Y-619771D01*
X330700Y-619638D01*
X331700Y-619905D01*
X332400Y-620571D01*
X332600Y-621371D01*
X332500Y-622172D01*
X332100Y-622838D01*
X330100Y-624171D01*
X329200Y-625105D01*
X328600Y-626438D01*
X328400Y-627638D01*
X332600D01*
G01X338500Y-619638D02*
X337700Y-619905D01*
X337100Y-620571D01*
X336700Y-621371D01*
X336400Y-622438D01*
X336300Y-623638D01*
X336400Y-624838D01*
X336700Y-625905D01*
X337100Y-626705D01*
X337700Y-627371D01*
X338500Y-627638D01*
X339300Y-627371D01*
X339900Y-626705D01*
X340300Y-625905D01*
X340600Y-624838D01*
X340700Y-623638D01*
X340600Y-622438D01*
X340300Y-621371D01*
X339900Y-620571D01*
X339300Y-619905D01*
X338500Y-619638D01*
G01X344600Y-620971D02*
X345200Y-620171D01*
X345900Y-619771D01*
X346700Y-619638D01*
X347700Y-619905D01*
X348400Y-620571D01*
X348600Y-621371D01*
X348500Y-622172D01*
X348100Y-622838D01*
X346100Y-624171D01*
X345200Y-625105D01*
X344600Y-626438D01*
X344400Y-627638D01*
X348600D01*
G01X352300Y-626038D02*
X352900Y-626971D01*
X353700Y-627505D01*
X354600Y-627638D01*
X355400Y-627505D01*
X356200Y-626838D01*
X356700Y-626038D01*
X356800Y-625238D01*
X356600Y-624305D01*
X355900Y-623638D01*
X355200Y-623371D01*
X354300D01*
G01X355200D02*
X355800Y-622971D01*
X356300Y-622305D01*
X356500Y-621505D01*
X356300Y-620705D01*
X355800Y-620038D01*
X354900Y-619638D01*
X354000Y-619771D01*
X353100Y-620305D01*
G01X360700Y-627905D02*
X364300Y-619638D01*
G01X370500D02*
X369700Y-619905D01*
X369100Y-620571D01*
X368700Y-621371D01*
X368400Y-622438D01*
X368300Y-623638D01*
X368400Y-624838D01*
X368700Y-625905D01*
X369100Y-626705D01*
X369700Y-627371D01*
X370500Y-627638D01*
X371300Y-627371D01*
X371900Y-626705D01*
X372300Y-625905D01*
X372600Y-624838D01*
X372700Y-623638D01*
X372600Y-622438D01*
X372300Y-621371D01*
X371900Y-620571D01*
X371300Y-619905D01*
X370500Y-619638D01*
G01X379700Y-627638D02*
Y-619638D01*
X376000Y-625371D01*
X381000D01*
G01X384700Y-627905D02*
X388300Y-619638D01*
G01X394500Y-627638D02*
Y-619638D01*
X393300Y-621238D01*
G01Y-627638D02*
X395700D01*
G01X402300D02*
X402500Y-625905D01*
X402800Y-624438D01*
X403200Y-623105D01*
X403700Y-621638D01*
X404500Y-619638D01*
X400500D01*
G01X328300Y-602638D02*
Y-594638D01*
X330300D01*
X331100Y-595038D01*
X331700Y-595571D01*
X332200Y-596371D01*
X332600Y-597305D01*
X332700Y-598638D01*
X332600Y-599971D01*
X332200Y-600905D01*
X331700Y-601705D01*
X331100Y-602238D01*
X330300Y-602638D01*
X328300D01*
G01X336000D02*
X338500Y-594638D01*
X341000Y-602638D01*
G01X340100Y-599838D02*
X336900D01*
G01X344600Y-602638D02*
Y-594638D01*
X348400D01*
G01X347000Y-598505D02*
X344600D01*
G01X354500Y-594638D02*
X353700Y-594905D01*
X353100Y-595571D01*
X352700Y-596371D01*
X352400Y-597438D01*
X352300Y-598638D01*
X352400Y-599838D01*
X352700Y-600905D01*
X353100Y-601705D01*
X353700Y-602371D01*
X354500Y-602638D01*
X355300Y-602371D01*
X355900Y-601705D01*
X356300Y-600905D01*
X356600Y-599838D01*
X356700Y-598638D01*
X356600Y-597438D01*
X356300Y-596371D01*
X355900Y-595571D01*
X355300Y-594905D01*
X354500Y-594638D01*
G01X362500D02*
Y-602638D01*
G01X360200Y-594638D02*
X364800D01*
G01X367900Y-602638D02*
Y-594638D01*
X370500Y-601305D01*
X373100Y-594638D01*
Y-602638D01*
G01X379300Y-598371D02*
X379700Y-597971D01*
X380000Y-597305D01*
X380200Y-596371D01*
X380000Y-595571D01*
X379600Y-595038D01*
X378900Y-594638D01*
X376200D01*
Y-602638D01*
X379500D01*
X380200Y-602105D01*
X380600Y-601305D01*
X380800Y-600371D01*
X380600Y-599438D01*
X380000Y-598638D01*
X379300Y-598371D01*
X376200D01*
G01X384300Y-601038D02*
X384900Y-601971D01*
X385700Y-602505D01*
X386600Y-602638D01*
X387400Y-602505D01*
X388200Y-601838D01*
X388700Y-601038D01*
X388800Y-600238D01*
X388600Y-599305D01*
X387900Y-598638D01*
X387200Y-598371D01*
X386300D01*
G01X387200D02*
X387800Y-597971D01*
X388300Y-597305D01*
X388500Y-596505D01*
X388300Y-595705D01*
X387800Y-595038D01*
X386900Y-594638D01*
X386000Y-594771D01*
X385100Y-595305D01*
G01X393300Y-594638D02*
X395700D01*
G01X394500D02*
Y-602638D01*
G01X393300D02*
X395700D01*
G01X404700Y-595305D02*
X404100Y-594905D01*
X403400Y-594638D01*
X402600D01*
X401700Y-595038D01*
X401000Y-595705D01*
X400500Y-596505D01*
X400100Y-597838D01*
X400000Y-599038D01*
X400200Y-600238D01*
X400500Y-601038D01*
X401100Y-601838D01*
X401800Y-602371D01*
X402500Y-602638D01*
X403200D01*
X403900Y-602371D01*
X404500Y-601971D01*
X405000Y-601438D01*
G01X410500Y-594638D02*
X409700Y-594905D01*
X409100Y-595571D01*
X408700Y-596371D01*
X408400Y-597438D01*
X408300Y-598638D01*
X408400Y-599838D01*
X408700Y-600905D01*
X409100Y-601705D01*
X409700Y-602371D01*
X410500Y-602638D01*
X411300Y-602371D01*
X411900Y-601705D01*
X412300Y-600905D01*
X412600Y-599838D01*
X412700Y-598638D01*
X412600Y-597438D01*
X412300Y-596371D01*
X411900Y-595571D01*
X411300Y-594905D01*
X410500Y-594638D01*
G01X346100Y-577638D02*
Y-569638D01*
X349900D01*
G01X348500Y-573505D02*
X346100D01*
G01X356000Y-569638D02*
X355200Y-569905D01*
X354600Y-570571D01*
X354200Y-571371D01*
X353900Y-572438D01*
X353800Y-573638D01*
X353900Y-574838D01*
X354200Y-575905D01*
X354600Y-576705D01*
X355200Y-577371D01*
X356000Y-577638D01*
X356800Y-577371D01*
X357400Y-576705D01*
X357800Y-575905D01*
X358100Y-574838D01*
X358200Y-573638D01*
X358100Y-572438D01*
X357800Y-571371D01*
X357400Y-570571D01*
X356800Y-569905D01*
X356000Y-569638D01*
G01X364000D02*
Y-577638D01*
G01X361700Y-569638D02*
X366300D01*
G01X372600Y-573638D02*
X374600D01*
Y-576038D01*
X374000Y-576838D01*
X373300Y-577371D01*
X372300Y-577638D01*
X371300Y-577371D01*
X370600Y-576838D01*
X370000Y-576038D01*
X369600Y-575105D01*
X369400Y-574038D01*
Y-573105D01*
X369600Y-572305D01*
X370000Y-571371D01*
X370600Y-570571D01*
X371200Y-570038D01*
X372000Y-569638D01*
X372700D01*
X373500Y-569905D01*
X374100Y-570438D01*
G01X377000Y-580305D02*
X383000D01*
G01X385400Y-577638D02*
Y-569638D01*
X388000Y-576305D01*
X390600Y-569638D01*
Y-577638D01*
G01X396800Y-573371D02*
X397200Y-572971D01*
X397500Y-572305D01*
X397700Y-571371D01*
X397500Y-570571D01*
X397100Y-570038D01*
X396400Y-569638D01*
X393700D01*
Y-577638D01*
X397000D01*
X397700Y-577105D01*
X398100Y-576305D01*
X398300Y-575371D01*
X398100Y-574438D01*
X397500Y-573638D01*
X396800Y-573371D01*
X393700D01*
G01X417000Y-630638D02*
Y-622638D01*
X415800Y-624238D01*
G01Y-630638D02*
X418200D01*
G01X423100Y-627305D02*
X423800Y-626371D01*
X424400Y-625838D01*
X425200Y-625571D01*
X425900Y-625838D01*
X426400Y-626371D01*
X426800Y-627171D01*
X426900Y-628105D01*
X426800Y-628905D01*
X426400Y-629705D01*
X425800Y-630371D01*
X425100Y-630638D01*
X424300Y-630371D01*
X423600Y-629572D01*
X423200Y-628371D01*
X423100Y-627038D01*
X423300Y-625305D01*
X423600Y-624371D01*
X424100Y-623438D01*
X424800Y-622771D01*
X425500Y-622638D01*
X426200Y-622905D01*
X426700Y-623571D01*
G01X433000Y-630905D02*
X432800Y-630771D01*
Y-630505D01*
X433000Y-630371D01*
X433200Y-630505D01*
Y-630771D01*
X433000Y-630905D01*
G01X439100Y-627305D02*
X439800Y-626371D01*
X440400Y-625838D01*
X441200Y-625571D01*
X441900Y-625838D01*
X442400Y-626371D01*
X442800Y-627171D01*
X442900Y-628105D01*
X442800Y-628905D01*
X442400Y-629705D01*
X441800Y-630371D01*
X441100Y-630638D01*
X440300Y-630371D01*
X439600Y-629572D01*
X439200Y-628371D01*
X439100Y-627038D01*
X439300Y-625305D01*
X439600Y-624371D01*
X440100Y-623438D01*
X440800Y-622771D01*
X441500Y-622638D01*
X442200Y-622905D01*
X442700Y-623571D01*
G01X462000Y-630638D02*
Y-622638D01*
X460800Y-624238D01*
G01Y-630638D02*
X463200D01*
G01X469800D02*
X470000Y-628905D01*
X470300Y-627438D01*
X470700Y-626105D01*
X471200Y-624638D01*
X472000Y-622638D01*
X468000D01*
G01X478000Y-630905D02*
X477800Y-630771D01*
Y-630505D01*
X478000Y-630371D01*
X478200Y-630505D01*
Y-630771D01*
X478000Y-630905D01*
G01X484100Y-623971D02*
X484700Y-623171D01*
X485400Y-622771D01*
X486200Y-622638D01*
X487200Y-622905D01*
X487900Y-623571D01*
X488100Y-624371D01*
X488000Y-625172D01*
X487600Y-625838D01*
X485600Y-627171D01*
X484700Y-628105D01*
X484100Y-629438D01*
X483900Y-630638D01*
X488100D01*
G01X486200Y-598305D02*
X485600Y-597905D01*
X484900Y-597638D01*
X484100D01*
X483200Y-598038D01*
X482500Y-598705D01*
X482000Y-599505D01*
X481600Y-600838D01*
X481500Y-602038D01*
X481700Y-603238D01*
X482000Y-604038D01*
X482600Y-604838D01*
X483300Y-605371D01*
X484000Y-605638D01*
X484700D01*
X485400Y-605371D01*
X486000Y-604971D01*
X486500Y-604438D01*
G54D79*
X129932Y1665000D03*
G54D199*
X606890Y461348D03*
X617204D03*
X606890Y465088D03*
Y468828D03*
X617204D03*
Y465088D03*
G54D97*
X155260Y1715941D03*
Y1718500D03*
Y1721059D03*
X162740Y1715941D03*
Y1718500D03*
Y1721059D03*
X181760Y1715441D03*
Y1718000D03*
Y1720559D03*
X189240Y1715441D03*
X198760Y1715000D03*
Y1712441D03*
X189240Y1718000D03*
Y1720559D03*
X198760Y1717559D03*
X206240Y1715000D03*
Y1712441D03*
Y1717559D03*
G54D289*
X1787943Y192193D03*
X1806547D03*
G54D88*
X139774Y1679174D03*
G54D98*
X162609Y400600D03*
X157491D03*
X160050Y406900D03*
X184271Y400060D03*
X186830Y406360D03*
X189389Y400060D03*
G54D89*
X136428Y1680945D03*
X134853D03*
X133278D03*
G54D99*
X168071Y1411468D03*
Y1432728D03*
X300044Y1387041D03*
Y1408301D03*
X328994Y1376650D03*
Y1397910D03*
M02*
